G04 ================== begin FILE IDENTIFICATION RECORD ==================*
G04 Layout Name:  9127_F0T_Expander_BD_F_v02_0110_1240.brd*
G04 Film Name:    bot*
G04 File Format:  Gerber RS274X*
G04 File Origin:  Cadence Allegro 17.2-S081*
G04 Origin Date:  Wed Jan 11 16:06:12 2023*
G04 *
G04 Layer:  PIN/SPECIAL_DRILL*
G04 Layer:  DRAWING FORMAT/TITLE_BLOCK_A*
G04 Layer:  DRAWING FORMAT/TITLE_BLOCK*
G04 Layer:  VIA CLASS/BOTTOM*
G04 Layer:  PIN/BOTTOM*
G04 Layer:  MANUFACTURING/PHOTOPLOT_OUTLINE*
G04 Layer:  ETCH/BOTTOM*
G04 Layer:  DRAWING FORMAT/TITLE_DATA_BOT*
G04 *
G04 Offset:    (0.00 0.00)*
G04 Mirror:    No*
G04 Mode:      Positive*
G04 Rotation:  0*
G04 FullContactRelief:  No*
G04 UndefLineWidth:     6.00*
G04 ================== end FILE IDENTIFICATION RECORD ====================*
%FSLAX25Y25*MOIN*%
%IR0*IPPOS*OFA0.00000B0.00000*MIA0B0*SFA1.00000B1.00000*%
%AMMACRO77*
4,1,8,-.02,-.005,
.002,-.005,
.002,-.01,
.02,-.01,
.02,.01,
.002,.01,
.002,.005,
-.02,.005,
-.02,-.005,
0.0*
%
%ADD77MACRO77*%
%ADD49O,.137X.062*%
%ADD10C,.02*%
%ADD72R,.111X.095*%
%ADD54R,.0041X.016*%
%ADD41C,.03*%
%ADD60R,.016X.0041*%
%ADD31O,.137X.064*%
%ADD26C,.04*%
%ADD79C,.041*%
%ADD97C,.061*%
%ADD91C,.052*%
%ADD33C,.016*%
%ADD32C,.044*%
%ADD13C,.026*%
%ADD40C,.018*%
%ADD86C,.028*%
%ADD48C,.064*%
%ADD87C,.048*%
%ADD46C,.0282*%
%ADD104C,.085*%
%ADD85C,.07051*%
%ADD71C,.0193*%
%ADD65R,.386X.046*%
%ADD47C,.0157*%
%ADD98R,.061X.061*%
%ADD14R,.046X.386*%
%AMMACRO80*
4,1,8,.0425,-.078,
-.0425,-.078,
-.0425,.078,
.0425,.078,
.0425,.0236,
.0145,.0236,
.0145,-.0236,
.0425,-.0236,
.0425,-.078,
0.0*
%
%ADD80MACRO80*%
%ADD22C,.0177*%
%ADD38C,.0395*%
%ADD45R,.0282X.0282*%
%ADD44C,.0199*%
%ADD96R,.07051X.07051*%
%ADD35C,.0785*%
%ADD43C,.03568*%
%AMMACRO28*
4,1,28,-.00748,.00052,
-.00984,.00052,
-.00984,.00603,
-.009782,.006705,
-.009607,.007359,
-.009321,.007974,
-.008933,.008529,
-.008455,.009009,
-.0079,.009398,
-.007286,.009685,
-.006632,.009861,
-.005957,.00992,
-.00591,.00992,
.00591,.00992,
.006585,.009869,
.007242,.009701,
.007859,.009421,
.008418,.009039,
.008903,.008565,
.009297,.008015,
.009591,.007404,
.009773,.006751,
.00984,.006077,
.00984,.00603,
.00984,.00052,
.00748,.00052,
.00748,-.00991,
-.00748,-.00991,
-.00748,.00052,
0.0*
%
%ADD28MACRO28*%
%AMMACRO37*
4,1,28,.00052,.00748,
.00052,.00984,
.00603,.00984,
.006705,.009782,
.007359,.009607,
.007974,.009321,
.008529,.008933,
.009009,.008455,
.009398,.0079,
.009685,.007286,
.009861,.006632,
.00992,.005957,
.00992,.00591,
.00992,-.00591,
.009869,-.006585,
.009701,-.007242,
.009421,-.007859,
.009039,-.008418,
.008565,-.008903,
.008015,-.009297,
.007404,-.009591,
.006751,-.009773,
.006077,-.00984,
.00603,-.00984,
.00052,-.00984,
.00052,-.00748,
-.00991,-.00748,
-.00991,.00748,
.00052,.00748,
0.0*
%
%ADD37MACRO37*%
%AMMACRO92*
4,1,8,.0034,.0082,
-.0034,.0082,
-.0082,.0034,
-.0082,-.00341,
-.00341,-.0082,
.0034,-.0082,
.0082,-.0034,
.0082,.0034,
.0034,.0082,
0.0*
%
%ADD92MACRO92*%
%AMMACRO93*
4,1,8,.0082,-.0034,
.0082,.0034,
.0034,.0082,
-.00341,.0082,
-.0082,.00341,
-.0082,-.0034,
-.0034,-.0082,
.0034,-.0082,
.0082,-.0034,
0.0*
%
%ADD93MACRO93*%
%AMMACRO27*
4,1,28,-.00748,-.00051,
-.00984,-.00051,
-.00984,-.00602,
-.009782,-.006695,
-.009607,-.007349,
-.009321,-.007964,
-.008933,-.008519,
-.008455,-.008998,
-.0079,-.009388,
-.007287,-.009675,
-.006632,-.009851,
-.005958,-.00991,
-.00591,-.00991,
.00591,-.00991,
.006585,-.009859,
.007242,-.009691,
.007859,-.009411,
.008418,-.009029,
.008903,-.008555,
.009297,-.008005,
.00959,-.007394,
.009773,-.006742,
.00984,-.006068,
.00984,-.00602,
.00984,-.00051,
.00748,-.00051,
.00748,.00992,
-.00748,.00992,
-.00748,-.00051,
0.0*
%
%ADD27MACRO27*%
%AMMACRO36*
4,1,28,-.00051,.00748,
-.00051,.00984,
-.00602,.00984,
-.006695,.009782,
-.007349,.009607,
-.007964,.009321,
-.008519,.008933,
-.008998,.008455,
-.009388,.0079,
-.009675,.007287,
-.009851,.006632,
-.00991,.005958,
-.00991,.00591,
-.00991,-.00591,
-.009859,-.006585,
-.009691,-.007242,
-.009411,-.007859,
-.009029,-.008418,
-.008555,-.008903,
-.008005,-.009297,
-.007394,-.00959,
-.006742,-.009773,
-.006068,-.00984,
-.00602,-.00984,
-.00051,-.00984,
-.00051,-.00748,
.00992,-.00748,
.00992,.00748,
-.00051,.00748,
0.0*
%
%ADD36MACRO36*%
%ADD73R,.02X.01*%
%ADD89R,.02X.011*%
%ADD15R,.01X.02*%
%ADD81R,.02X.012*%
%ADD68R,.022X.01*%
%ADD88R,.021X.012*%
%ADD70R,.01X.022*%
%ADD50R,.015X.012*%
%ADD34R,.05X.04*%
%ADD25R,.012X.015*%
%ADD18R,.04X.05*%
%ADD105R,.032X.024*%
%ADD66R,.018X.02*%
%ADD61R,.024X.024*%
%ADD56R,.053X.022*%
%AMMACRO51*
21,1,.016,.0041,0.0,0.0,135.*%
%ADD51MACRO51*%
%ADD101R,.014X.052*%
%ADD100R,.024X.042*%
%ADD83R,.012X.063*%
%ADD76R,.044X.014*%
%ADD53R,.024X.024*%
%ADD52R,.024X.016*%
%ADD39R,.014X.061*%
%ADD108C,.122*%
%ADD106O,.044X.071*%
%ADD99R,.036X.032*%
%ADD78R,.014X.044*%
%ADD75R,.044X.024*%
%ADD62R,.016X.024*%
%ADD57R,.024X.017*%
%ADD17R,.032X.028*%
%AMMACRO67*
4,1,8,.02,.005,
-.002,.005,
-.002,.01,
-.02,.01,
-.02,-.01,
-.002,-.01,
-.002,-.005,
.02,-.005,
.02,.005,
0.0*
%
%ADD67MACRO67*%
%ADD59R,.028X.032*%
%ADD55R,.036X.016*%
%ADD102R,.024X.046*%
%ADD82C,.134*%
%AMMACRO63*
21,1,.016,.0041,0.0,0.0,123.215*%
%ADD63MACRO63*%
%ADD19R,.054X.044*%
%ADD12C,.125*%
%ADD84C,.315*%
%ADD64R,.044X.054*%
%ADD103R,.017X.046*%
%ADD107O,.044X.087*%
%ADD11C,.256*%
%ADD69R,.124X.124*%
%ADD24C,.158*%
%ADD42C,.178*%
%ADD23C,.394*%
%AMMACRO95*
4,1,8,-.0425,.078,
.0425,.078,
.0425,-.078,
-.0425,-.078,
-.0425,-.0236,
-.0145,-.0236,
-.0145,.0236,
-.0425,.0236,
-.0425,.078,
0.0*
%
%ADD95MACRO95*%
%ADD74R,.079X.059*%
%AMMACRO30*
4,1,28,-.00052,-.00748,
-.00052,-.00984,
-.00603,-.00984,
-.006705,-.009782,
-.007359,-.009607,
-.007974,-.009321,
-.008529,-.008933,
-.009009,-.008455,
-.009398,-.0079,
-.009685,-.007286,
-.009861,-.006632,
-.00992,-.005957,
-.00992,-.00591,
-.00992,.00591,
-.009869,.006585,
-.009701,.007242,
-.009421,.007859,
-.009039,.008418,
-.008565,.008903,
-.008015,.009297,
-.007404,.009591,
-.006751,.009773,
-.006077,.00984,
-.00603,.00984,
-.00052,.00984,
-.00052,.00748,
.00991,.00748,
.00991,-.00748,
-.00052,-.00748,
0.0*
%
%ADD30MACRO30*%
%AMMACRO20*
4,1,28,.00748,-.00052,
.00984,-.00052,
.00984,-.00603,
.009782,-.006705,
.009607,-.007359,
.009321,-.007974,
.008933,-.008529,
.008455,-.009009,
.0079,-.009398,
.007286,-.009685,
.006632,-.009861,
.005957,-.00992,
.00591,-.00992,
-.00591,-.00992,
-.006585,-.009869,
-.007242,-.009701,
-.007859,-.009421,
-.008418,-.009039,
-.008903,-.008565,
-.009297,-.008015,
-.009591,-.007404,
-.009773,-.006751,
-.00984,-.006077,
-.00984,-.00603,
-.00984,-.00052,
-.00748,-.00052,
-.00748,.00991,
.00748,.00991,
.00748,-.00052,
0.0*
%
%ADD20MACRO20*%
%ADD16R,.059X.079*%
%AMMACRO94*
4,1,8,-.0034,-.0082,
.0034,-.0082,
.0082,-.0034,
.0082,.00341,
.00341,.0082,
-.0034,.0082,
-.0082,.0034,
-.0082,-.0034,
-.0034,-.0082,
0.0*
%
%ADD94MACRO94*%
%AMMACRO90*
4,1,8,-.0082,.0034,
-.0082,-.0034,
-.0034,-.0082,
.00341,-.0082,
.0082,-.00341,
.0082,.0034,
.0034,.0082,
-.0034,.0082,
-.0082,.0034,
0.0*
%
%ADD90MACRO90*%
%AMMACRO29*
4,1,28,.00051,-.00748,
.00051,-.00984,
.00602,-.00984,
.006695,-.009782,
.007349,-.009607,
.007964,-.009321,
.008519,-.008933,
.008998,-.008455,
.009388,-.0079,
.009675,-.007287,
.009851,-.006632,
.00991,-.005958,
.00991,-.00591,
.00991,.00591,
.009859,.006585,
.009691,.007242,
.009411,.007859,
.009029,.008418,
.008555,.008903,
.008005,.009297,
.007394,.00959,
.006742,.009773,
.006068,.00984,
.00602,.00984,
.00051,.00984,
.00051,.00748,
-.00992,.00748,
-.00992,-.00748,
.00051,-.00748,
0.0*
%
%ADD29MACRO29*%
%AMMACRO21*
4,1,28,.00748,.00051,
.00984,.00051,
.00984,.00602,
.009782,.006695,
.009607,.007349,
.009321,.007964,
.008933,.008519,
.008455,.008998,
.0079,.009388,
.007287,.009675,
.006632,.009851,
.005958,.00991,
.00591,.00991,
-.00591,.00991,
-.006585,.009859,
-.007242,.009691,
-.007859,.009411,
-.008418,.009029,
-.008903,.008555,
-.009297,.008005,
-.00959,.007394,
-.009773,.006742,
-.00984,.006068,
-.00984,.00602,
-.00984,.00051,
-.00748,.00051,
-.00748,-.00992,
.00748,-.00992,
.00748,.00051,
0.0*
%
%ADD21MACRO21*%
%ADD109C,.01*%
%ADD110C,.011*%
%ADD111C,.012*%
%ADD112C,.014*%
%ADD113C,.015*%
%ADD114C,.006*%
%ADD115C,.0052*%
%ADD116C,.0035*%
%ADD117C,.008*%
%ADD118C,.0053*%
%ADD119C,.0045*%
%ADD120C,.0039*%
%ADD123C,.03004*%
%ADD128C,.03006*%
%ADD127C,.02504*%
%ADD133C,.02704*%
%ADD122C,.03604*%
%ADD125C,.03606*%
%ADD124C,.05804*%
%ADD135C,.08407*%
%ADD121C,.09208*%
%ADD129C,.04684*%
%ADD136C,.13006*%
%ADD137C,.1622*%
%ADD126C,.218*%
%ADD132C,.40404*%
%ADD130C,.1742*%
%ADD134O,.03606X.07006*%
%ADD131C,.28772*%
G75*
%LPD*%
G75*
G36*
G01X1081725Y1645992D02*
X1833071D01*
G02X1838945Y1640118I0J-5874D01*
G01Y970426D01*
G02X1837225Y966273I-5874J0D01*
G01X1826876Y955925D01*
G03X1823984Y948944I6982J-6982D01*
G01Y344836D01*
G03X1826876Y337855I9873J0D01*
G01X1837225Y327506D01*
G02X1838945Y323354I-4153J-4153D01*
G01Y7874D01*
G02X1833071Y2000I-5874J0D01*
G01X1756949D01*
G02X1751075Y7874I0J5874D01*
G01Y46654D01*
G03X1749600Y50571I-5938J0D01*
G01Y50666D01*
X1749606Y50672D01*
X1751979D01*
G02X1753072Y46654I-6841J-4019D01*
G01Y7874D01*
G03X1756947Y3998I3876J0D01*
G01X1833071D01*
G03X1836948Y7874I0J3877D01*
G01Y323354D01*
G03X1835813Y326094I-3876J0D01*
G01X1825464Y336443D01*
G02X1821987Y344836I8393J8394D01*
G01X1821986D01*
Y948944D01*
X1821987D01*
G02X1825464Y957337I11871J-1D01*
G01X1835813Y967685D01*
G03X1836948Y970426I-2742J2741D01*
G01Y1640118D01*
G03X1833073Y1643994I-3876J0D01*
G01X1633526D01*
Y1644873D01*
X1578560D01*
Y1643994D01*
X1285912D01*
Y1644677D01*
X1232543D01*
Y1643994D01*
X1081724D01*
G03X1078854Y1642722I1J-3877D01*
G02X1070058Y1638822I-8797J7971D01*
G01X800966D01*
G02X792169Y1642722I0J11872D01*
G03X789299Y1643994I-2871J-2603D01*
G01X608951D01*
Y1644464D01*
X555228D01*
Y1643994D01*
X262776D01*
Y1644377D01*
X208818D01*
Y1643994D01*
X7874D01*
G03X3998Y1640118I0J-3876D01*
G01Y970425D01*
G03X5133Y967685I3877J1D01*
G01X15480Y957338D01*
G02X18958Y948943I-8394J-8396D01*
G01Y344836D01*
G02X15480Y336442I-11871J1D01*
G01X5132Y326094D01*
G03X3998Y323355I2742J-2739D01*
G01Y7874D01*
G03X7874Y3998I3876J0D01*
G01X23484D01*
G03X27360Y7874I0J3876D01*
G01Y46654D01*
G02X35295Y54588I7935J-1D01*
G01X64100D01*
X64454Y54234D01*
Y52945D01*
X64100Y52591D01*
X35295D01*
G03X29358Y46654I0J-5937D01*
G01Y7874D01*
G02X23484Y2000I-5874J0D01*
G01X7874D01*
G02X2000Y7874I0J5874D01*
G01Y323354D01*
G02X3720Y327506I5873J-1D01*
G01X14068Y337855D01*
G03X16961Y344836I-6980J6983D01*
G01Y948943D01*
G03X14068Y955925I-9875J-1D01*
G01X3720Y966273D01*
G02X2000Y970426I4154J4153D01*
G01Y1640118D01*
G02X7874Y1645992I5874J0D01*
G01X789298D01*
G02X793649Y1644063I-1J-5873D01*
G03X800966Y1640819I7317J6631D01*
G01X1070058D01*
G03X1077374Y1644063I-1J9873D01*
G02X1081725Y1645992I4352J-3945D01*
G37*
G36*
G01X1795591Y220610D02*
X1788041Y213060D01*
G02X1787858Y213007I-140J142D01*
G01X1787635Y213067D01*
X1787513Y213100D01*
G02X1787423Y213152I52J193D01*
G01X1787405Y213170D01*
X1787379Y213215D01*
X1787372Y213242D01*
G03X1785918Y214366I-1454J-378D01*
G03X1784416Y212864I0J-1502D01*
G03X1785540Y211410I1502J0D01*
G01X1785541D01*
G02X1785631Y211358I-52J-193D01*
G01X1785649Y211340D01*
X1785675Y211295D01*
X1785715Y211147D01*
X1785775Y210924D01*
G02X1785722Y210741I-195J-43D01*
G01X1785666Y210685D01*
G02X1785618Y210650I-140J142D01*
G01X1785594Y210637D01*
X1785564Y210631D01*
G03X1784168Y209295I354J-1767D01*
G01Y209294D01*
G02X1784096Y209183I-194J47D01*
G01X1784072Y209164D01*
X1784009Y209143D01*
X1752300D01*
G02X1752184Y209181I1J200D01*
G01X1752159Y209198D01*
X1752123Y209247D01*
X1752112Y209278D01*
G03X1751396Y210202I-1706J-582D01*
G01X1751360Y210225D01*
X1751338Y210259D01*
G02X1751309Y210333I168J109D01*
G01X1751259Y210625D01*
G02X1751263Y210708I197J32D01*
G01X1751272Y210745D01*
X1751298Y210779D01*
G03X1751609Y211693I-1191J915D01*
G01Y211695D01*
G03X1750107Y213197I-1502J0D01*
G03X1749120Y212827I0J-1501D01*
G01X1749092Y212803D01*
X1749059Y212791D01*
G02X1748989Y212778I-71J187D01*
G01X1748725D01*
G02X1748655Y212791I1J200D01*
G01X1748622Y212803D01*
X1748594Y212827D01*
G03X1747607Y213197I-987J-1131D01*
G03X1746105Y211695I0J-1502D01*
G03X1746684Y210510I1502J0D01*
G02X1746759Y210382I-123J-158D01*
G02X1746761Y210352I-198J-28D01*
G01Y210038D01*
G02X1746759Y210008I-200J-2D01*
G02X1746693Y209888I-198J31D01*
G02X1746684Y209880I-137J145D01*
G03X1746209Y209246I922J-1186D01*
G01X1746195Y209211D01*
X1746145Y209177D01*
G02X1746033Y209143I-112J166D01*
G01X1744807D01*
X1744804D01*
G02X1744663Y209204I3J200D01*
G03X1744617Y209255I-1138J-980D01*
G03X1744613Y209259I-143J-139D01*
G02X1744561Y209350I141J141D01*
G02X1744554Y209400I193J52D01*
G01Y209526D01*
G02X1744570Y209603I200J-1D01*
G03X1745053Y210713I-1034J1110D01*
G03X1744629Y211766I-1520J0D01*
G01X1744618Y211795D01*
Y212095D01*
G02X1744631Y212165I200J-1D01*
G01X1744643Y212198D01*
X1744667Y212226D01*
G03Y214200I-1131J987D01*
G01X1744643Y214228D01*
X1744631Y214261D01*
G02X1744618Y214331I187J71D01*
G01Y214595D01*
G02X1744631Y214665I200J-1D01*
G01X1744643Y214698D01*
X1744667Y214726D01*
G03X1745037Y215713I-1131J987D01*
G03X1742033I-1502J0D01*
G03X1742403Y214726I1501J0D01*
G01X1742427Y214698D01*
X1742439Y214665D01*
G02X1742452Y214595I-187J-71D01*
G01Y214331D01*
G02X1742439Y214261I-200J1D01*
G01X1742427Y214228D01*
X1742403Y214200D01*
G03Y212226I1131J-987D01*
G01X1742427Y212198D01*
X1742439Y212165D01*
G02X1742452Y212095I-187J-71D01*
G01Y211795D01*
X1742441Y211766D01*
G03X1742017Y210713I1096J-1053D01*
G03X1742501Y209602I1517J0D01*
G02X1742516Y209527I-185J-76D01*
G01Y209401D01*
G02X1742513Y209365I-200J-1D01*
G02X1742509Y209350I-195J44D01*
G02X1742457Y209259I-193J50D01*
G03X1742453Y209255I139J-143D01*
G03X1742407Y209204I1092J-1031D01*
G02X1742266Y209143I-144J139D01*
G01X1734735D01*
G02X1734563Y209242I1J200D01*
G01X1734388Y209540D01*
G02X1734361Y209641I173J100D01*
G01Y209693D01*
X1734368Y209706D01*
X1734387Y209739D01*
G03X1734581Y210477I-1308J738D01*
G01Y210478D01*
G03X1734211Y211465I-1501J0D01*
G01X1734187Y211493D01*
X1734175Y211526D01*
G02X1734162Y211596I187J71D01*
G01Y211860D01*
G02X1734175Y211930I200J-1D01*
G01X1734187Y211963D01*
X1734211Y211991D01*
G03Y213965I-1131J987D01*
G01X1734187Y213993D01*
X1734175Y214026D01*
G02X1734162Y214096I187J71D01*
G01Y214360D01*
G02X1734175Y214430I200J-1D01*
G01X1734187Y214463D01*
X1734211Y214491D01*
G03X1734581Y215478I-1131J987D01*
G03X1731577I-1502J0D01*
G03X1731947Y214491I1501J0D01*
G01X1731971Y214463D01*
X1731983Y214430D01*
G02X1731996Y214360I-187J-71D01*
G01Y214096D01*
G02X1731983Y214026I-200J1D01*
G01X1731971Y213993D01*
X1731947Y213965D01*
G03Y211991I1131J-987D01*
G01X1731971Y211963D01*
X1731983Y211930D01*
G02X1731996Y211860I-187J-71D01*
G01Y211596D01*
G02X1731983Y211526I-200J1D01*
G01X1731971Y211493D01*
X1731947Y211465D01*
G03X1731577Y210478I1131J-987D01*
G01Y210477D01*
G03X1731771Y209739I1502J0D01*
G01X1731790Y209706D01*
X1731797Y209693D01*
Y209641D01*
G02X1731770Y209540I-200J-1D01*
G01X1731595Y209242D01*
G02X1731423Y209143I-173J101D01*
G01X1708132D01*
G02X1707963Y209237I1J200D01*
G01X1707824Y209480D01*
X1707786Y209546D01*
G02X1707760Y209645I174J99D01*
G01Y209699D01*
X1707788Y209746D01*
G03X1707996Y210509I-1294J763D01*
G01Y210533D01*
G03X1706494Y212011I-1502J-24D01*
G03X1705507Y211641I0J-1501D01*
G01X1705479Y211617D01*
X1705446Y211605D01*
G02X1705376Y211592I-71J187D01*
G01X1705112D01*
G02X1705042Y211605I1J200D01*
G01X1705009Y211617D01*
X1704981Y211641D01*
G03X1703994Y212011I-987J-1131D01*
G03X1702492Y210533I0J-1502D01*
G01Y210509D01*
G03X1702700Y209746I1502J0D01*
G01X1702714Y209723D01*
X1702728Y209671D01*
Y209645D01*
G02X1702702Y209546I-200J0D01*
G01X1702664Y209480D01*
X1702525Y209237D01*
G02X1702356Y209143I-170J106D01*
G01X1685498D01*
G02X1685376Y209185I1J200D01*
G01X1685351Y209205D01*
X1685315Y209260D01*
X1685306Y209295D01*
G03X1681806I-1750J-431D01*
G01Y209294D01*
G02X1681734Y209183I-194J47D01*
G01X1681710Y209164D01*
X1681647Y209143D01*
X1649938D01*
G02X1649822Y209181I1J200D01*
G01X1649797Y209198D01*
X1649761Y209247D01*
X1649750Y209278D01*
G03X1649034Y210202I-1706J-582D01*
G01X1648998Y210225D01*
X1648976Y210259D01*
G02X1648947Y210333I168J109D01*
G01X1648897Y210625D01*
G02X1648901Y210708I197J32D01*
G01X1648910Y210745D01*
X1648936Y210779D01*
G03X1649247Y211693I-1191J915D01*
G01Y211695D01*
G03X1647745Y213197I-1502J0D01*
G03X1646758Y212827I0J-1501D01*
G01X1646730Y212803D01*
X1646697Y212791D01*
G02X1646627Y212778I-71J187D01*
G01X1646363D01*
G02X1646293Y212791I1J200D01*
G01X1646260Y212803D01*
X1646232Y212827D01*
G03X1645245Y213197I-987J-1131D01*
G03X1643743Y211695I0J-1502D01*
G03X1644322Y210510I1502J0D01*
G02X1644397Y210382I-123J-158D01*
G02X1644399Y210352I-198J-28D01*
G01Y210038D01*
G02X1644397Y210008I-200J-2D01*
G02X1644331Y209888I-198J31D01*
G02X1644322Y209880I-137J145D01*
G03X1643847Y209246I922J-1186D01*
G01X1643833Y209211D01*
X1643783Y209177D01*
G02X1643671Y209143I-112J166D01*
G01X1642445D01*
X1642442D01*
G02X1642301Y209204I3J200D01*
G03X1642255Y209255I-1138J-980D01*
G03X1642251Y209259I-143J-139D01*
G02X1642199Y209350I141J141D01*
G02X1642192Y209400I193J52D01*
G01Y209526D01*
G02X1642208Y209603I200J-1D01*
G03X1642691Y210713I-1034J1110D01*
G03X1642267Y211766I-1520J0D01*
G01X1642256Y211795D01*
Y212095D01*
G02X1642269Y212165I200J-1D01*
G01X1642281Y212198D01*
X1642305Y212226D01*
G03Y214200I-1131J987D01*
G01X1642281Y214228D01*
X1642269Y214261D01*
G02X1642256Y214331I187J71D01*
G01Y214595D01*
G02X1642269Y214665I200J-1D01*
G01X1642281Y214698D01*
X1642305Y214726D01*
G03X1642675Y215713I-1131J987D01*
G03X1639671I-1502J0D01*
G03X1640041Y214726I1501J0D01*
G01X1640065Y214698D01*
X1640077Y214665D01*
G02X1640090Y214595I-187J-71D01*
G01Y214331D01*
G02X1640077Y214261I-200J1D01*
G01X1640065Y214228D01*
X1640041Y214200D01*
G03Y212226I1131J-987D01*
G01X1640065Y212198D01*
X1640077Y212165D01*
G02X1640090Y212095I-187J-71D01*
G01Y211795D01*
X1640079Y211766D01*
G03X1639655Y210713I1096J-1053D01*
G03X1640139Y209602I1517J0D01*
G02X1640154Y209527I-185J-76D01*
G01Y209401D01*
G02X1640151Y209365I-200J-1D01*
G02X1640147Y209350I-195J44D01*
G02X1640095Y209259I-193J50D01*
G03X1640091Y209255I139J-143D01*
G03X1640045Y209204I1092J-1031D01*
G02X1639904Y209143I-144J139D01*
G01X1632373D01*
G02X1632201Y209242I1J200D01*
G01X1632026Y209540D01*
G02X1631999Y209641I173J100D01*
G01Y209693D01*
X1632006Y209706D01*
X1632025Y209739D01*
G03X1632219Y210477I-1308J738D01*
G01Y210478D01*
G03X1631849Y211465I-1501J0D01*
G01X1631825Y211493D01*
X1631813Y211526D01*
G02X1631800Y211596I187J71D01*
G01Y211860D01*
G02X1631813Y211930I200J-1D01*
G01X1631825Y211963D01*
X1631849Y211991D01*
G03Y213965I-1131J987D01*
G01X1631825Y213993D01*
X1631813Y214026D01*
G02X1631800Y214096I187J71D01*
G01Y214360D01*
G02X1631813Y214430I200J-1D01*
G01X1631825Y214463D01*
X1631849Y214491D01*
G03X1632219Y215478I-1131J987D01*
G03X1629215I-1502J0D01*
G03X1629585Y214491I1501J0D01*
G01X1629609Y214463D01*
X1629621Y214430D01*
G02X1629634Y214360I-187J-71D01*
G01Y214096D01*
G02X1629621Y214026I-200J1D01*
G01X1629609Y213993D01*
X1629585Y213965D01*
G03Y211991I1131J-987D01*
G01X1629609Y211963D01*
X1629621Y211930D01*
G02X1629634Y211860I-187J-71D01*
G01Y211596D01*
G02X1629621Y211526I-200J1D01*
G01X1629609Y211493D01*
X1629585Y211465D01*
G03X1629215Y210478I1131J-987D01*
G01Y210477D01*
G03X1629409Y209739I1502J0D01*
G01X1629428Y209706D01*
X1629435Y209693D01*
Y209641D01*
G02X1629408Y209540I-200J-1D01*
G01X1629233Y209242D01*
G02X1629061Y209143I-173J101D01*
G01X1605770D01*
G02X1605601Y209237I1J200D01*
G01X1605462Y209480D01*
X1605424Y209546D01*
G02X1605398Y209645I174J99D01*
G01Y209699D01*
X1605426Y209746D01*
G03X1605634Y210509I-1294J763D01*
G01Y210533D01*
G03X1604132Y212011I-1502J-24D01*
G03X1603145Y211641I0J-1501D01*
G01X1603117Y211617D01*
X1603084Y211605D01*
G02X1603014Y211592I-71J187D01*
G01X1602750D01*
G02X1602680Y211605I1J200D01*
G01X1602647Y211617D01*
X1602619Y211641D01*
G03X1601632Y212011I-987J-1131D01*
G03X1600130Y210533I0J-1502D01*
G01Y210509D01*
G03X1600338Y209746I1502J0D01*
G01X1600352Y209723D01*
X1600366Y209671D01*
Y209645D01*
G02X1600340Y209546I-200J0D01*
G01X1600302Y209480D01*
X1600163Y209237D01*
G02X1599994Y209143I-170J106D01*
G01X1583136D01*
G02X1583014Y209185I1J200D01*
G01X1582989Y209205D01*
X1582953Y209260D01*
X1582944Y209295D01*
G03X1579444I-1750J-431D01*
G01Y209294D01*
G02X1579372Y209183I-194J47D01*
G01X1579348Y209164D01*
X1579285Y209143D01*
X1547576D01*
G02X1547460Y209181I1J200D01*
G01X1547435Y209198D01*
X1547399Y209247D01*
X1547388Y209278D01*
G03X1546672Y210202I-1706J-582D01*
G01X1546636Y210225D01*
X1546614Y210259D01*
G02X1546585Y210333I168J109D01*
G01X1546535Y210625D01*
G02X1546539Y210708I197J32D01*
G01X1546548Y210745D01*
X1546574Y210779D01*
G03X1546885Y211693I-1191J915D01*
G01Y211695D01*
G03X1545383Y213197I-1502J0D01*
G03X1544396Y212827I0J-1501D01*
G01X1544368Y212803D01*
X1544335Y212791D01*
G02X1544265Y212778I-71J187D01*
G01X1544001D01*
G02X1543931Y212791I1J200D01*
G01X1543898Y212803D01*
X1543870Y212827D01*
G03X1542883Y213197I-987J-1131D01*
G03X1541381Y211695I0J-1502D01*
G03X1541960Y210510I1502J0D01*
G02X1542035Y210382I-123J-158D01*
G02X1542037Y210352I-198J-28D01*
G01Y210038D01*
G02X1542035Y210008I-200J-2D01*
G02X1541966Y209885I-198J30D01*
G02X1541960Y209880I-131J151D01*
G03X1541494Y209267I923J-1185D01*
G01X1541477Y209226D01*
X1541445Y209196D01*
G02X1541419Y209176I-134J148D01*
G01X1541395Y209160D01*
X1541340Y209143D01*
X1540083D01*
X1540080D01*
G02X1539939Y209204I3J200D01*
G03X1539893Y209255I-1138J-980D01*
G03X1539889Y209259I-143J-139D01*
G02X1539837Y209350I141J141D01*
G02X1539830Y209400I193J52D01*
G01Y209526D01*
G02X1539846Y209603I200J-1D01*
G03X1540329Y210713I-1034J1110D01*
G03X1539905Y211766I-1520J0D01*
G01X1539894Y211795D01*
Y212095D01*
G02X1539907Y212165I200J-1D01*
G01X1539919Y212198D01*
X1539943Y212226D01*
G03Y214200I-1131J987D01*
G01X1539919Y214228D01*
X1539907Y214261D01*
G02X1539894Y214331I187J71D01*
G01Y214595D01*
G02X1539907Y214665I200J-1D01*
G01X1539919Y214698D01*
X1539943Y214726D01*
G03X1540313Y215713I-1131J987D01*
G03X1537309I-1502J0D01*
G03X1537679Y214726I1501J0D01*
G01X1537703Y214698D01*
X1537715Y214665D01*
G02X1537728Y214595I-187J-71D01*
G01Y214331D01*
G02X1537715Y214261I-200J1D01*
G01X1537703Y214228D01*
X1537679Y214200D01*
G03Y212226I1131J-987D01*
G01X1537703Y212198D01*
X1537715Y212165D01*
G02X1537728Y212095I-187J-71D01*
G01Y211795D01*
X1537717Y211766D01*
G03X1537293Y210713I1096J-1053D01*
G03X1537777Y209602I1517J0D01*
G02X1537792Y209527I-185J-76D01*
G01Y209401D01*
G02X1537789Y209365I-200J-1D01*
G02X1537785Y209350I-195J44D01*
G02X1537733Y209259I-193J50D01*
G03X1537729Y209255I139J-143D01*
G03X1537683Y209204I1092J-1031D01*
G02X1537542Y209143I-144J139D01*
G01X1530011D01*
G02X1529839Y209242I1J200D01*
G01X1529664Y209540D01*
G02X1529637Y209641I173J100D01*
G01Y209693D01*
X1529644Y209706D01*
X1529663Y209739D01*
G03X1529857Y210477I-1308J738D01*
G01Y210478D01*
G03X1529487Y211465I-1501J0D01*
G01X1529463Y211493D01*
X1529451Y211526D01*
G02X1529438Y211596I187J71D01*
G01Y211860D01*
G02X1529451Y211930I200J-1D01*
G01X1529463Y211963D01*
X1529487Y211991D01*
G03Y213965I-1131J987D01*
G01X1529463Y213993D01*
X1529451Y214026D01*
G02X1529438Y214096I187J71D01*
G01Y214360D01*
G02X1529451Y214430I200J-1D01*
G01X1529463Y214463D01*
X1529487Y214491D01*
G03X1529857Y215478I-1131J987D01*
G03X1526853I-1502J0D01*
G03X1527223Y214491I1501J0D01*
G01X1527247Y214463D01*
X1527259Y214430D01*
G02X1527272Y214360I-187J-71D01*
G01Y214096D01*
G02X1527259Y214026I-200J1D01*
G01X1527247Y213993D01*
X1527223Y213965D01*
G03Y211991I1131J-987D01*
G01X1527247Y211963D01*
X1527259Y211930D01*
G02X1527272Y211860I-187J-71D01*
G01Y211596D01*
G02X1527259Y211526I-200J1D01*
G01X1527247Y211493D01*
X1527223Y211465D01*
G03X1526853Y210478I1131J-987D01*
G01Y210477D01*
G03X1527047Y209739I1502J0D01*
G01X1527066Y209706D01*
X1527073Y209693D01*
Y209641D01*
G02X1527046Y209540I-200J-1D01*
G01X1526871Y209242D01*
G02X1526699Y209143I-173J101D01*
G01X1503408D01*
G02X1503239Y209237I1J200D01*
G01X1503100Y209480D01*
X1503062Y209546D01*
G02X1503036Y209645I174J99D01*
G01Y209699D01*
X1503064Y209746D01*
G03X1503272Y210509I-1294J763D01*
G01Y210533D01*
G03X1501770Y212011I-1502J-24D01*
G03X1500783Y211641I0J-1501D01*
G01X1500755Y211617D01*
X1500722Y211605D01*
G02X1500652Y211592I-71J187D01*
G01X1500388D01*
G02X1500318Y211605I1J200D01*
G01X1500285Y211617D01*
X1500257Y211641D01*
G03X1499270Y212011I-987J-1131D01*
G03X1497768Y210533I0J-1502D01*
G01Y210509D01*
G03X1497976Y209746I1502J0D01*
G01X1497990Y209723D01*
X1498004Y209671D01*
Y209645D01*
G02X1497978Y209546I-200J0D01*
G01X1497940Y209480D01*
X1497801Y209237D01*
G02X1497632Y209143I-170J106D01*
G01X1480465D01*
G02X1480345Y209183I0J200D01*
G01X1480318Y209203D01*
X1480283Y209255D01*
X1480273Y209287D01*
G03X1477391I-1441J-423D01*
G01Y209286D01*
G02X1477319Y209183I-192J57D01*
G01X1477293Y209163D01*
X1477232Y209143D01*
X1445214D01*
G02X1445098Y209181I1J200D01*
G01X1445073Y209198D01*
X1445037Y209247D01*
X1445026Y209278D01*
G03X1444310Y210202I-1706J-582D01*
G01X1444274Y210225D01*
X1444252Y210259D01*
G02X1444223Y210333I168J109D01*
G01X1444173Y210625D01*
G02X1444177Y210708I197J32D01*
G01X1444186Y210745D01*
X1444212Y210779D01*
G03X1444523Y211693I-1191J915D01*
G01Y211695D01*
G03X1443021Y213197I-1502J0D01*
G03X1442034Y212827I0J-1501D01*
G01X1442006Y212803D01*
X1441973Y212791D01*
G02X1441903Y212778I-71J187D01*
G01X1441639D01*
G02X1441569Y212791I1J200D01*
G01X1441536Y212803D01*
X1441508Y212827D01*
G03X1440521Y213197I-987J-1131D01*
G03X1439019Y211695I0J-1502D01*
G03X1439598Y210510I1502J0D01*
G02X1439673Y210382I-123J-158D01*
G02X1439675Y210352I-198J-28D01*
G01Y210038D01*
G02X1439673Y210008I-200J-2D01*
G02X1439604Y209885I-198J30D01*
G02X1439598Y209880I-131J151D01*
G03X1439132Y209267I923J-1185D01*
G01X1439115Y209226D01*
X1439083Y209196D01*
G02X1439057Y209176I-134J148D01*
G01X1439033Y209160D01*
X1438978Y209143D01*
X1437721D01*
X1437718D01*
G02X1437577Y209204I3J200D01*
G03X1437531Y209255I-1138J-980D01*
G03X1437527Y209259I-143J-139D01*
G02X1437475Y209350I141J141D01*
G02X1437468Y209400I193J52D01*
G01Y209526D01*
G02X1437484Y209603I200J-1D01*
G03X1437967Y210713I-1034J1110D01*
G03X1437543Y211766I-1520J0D01*
G01X1437532Y211795D01*
Y212095D01*
G02X1437545Y212165I200J-1D01*
G01X1437557Y212198D01*
X1437581Y212226D01*
G03Y214200I-1131J987D01*
G01X1437557Y214228D01*
X1437545Y214261D01*
G02X1437532Y214331I187J71D01*
G01Y214595D01*
G02X1437545Y214665I200J-1D01*
G01X1437557Y214698D01*
X1437581Y214726D01*
G03X1437951Y215713I-1131J987D01*
G03X1434947I-1502J0D01*
G03X1435317Y214726I1501J0D01*
G01X1435341Y214698D01*
X1435353Y214665D01*
G02X1435366Y214595I-187J-71D01*
G01Y214331D01*
G02X1435353Y214261I-200J1D01*
G01X1435341Y214228D01*
X1435317Y214200D01*
G03Y212226I1131J-987D01*
G01X1435341Y212198D01*
X1435353Y212165D01*
G02X1435366Y212095I-187J-71D01*
G01Y211795D01*
X1435355Y211766D01*
G03X1434931Y210713I1096J-1053D01*
G03X1435415Y209602I1517J0D01*
G02X1435430Y209527I-185J-76D01*
G01Y209401D01*
G02X1435427Y209365I-200J-1D01*
G02X1435423Y209350I-195J44D01*
G02X1435371Y209259I-193J50D01*
G03X1435367Y209255I139J-143D01*
G03X1435321Y209204I1092J-1031D01*
G02X1435180Y209143I-144J139D01*
G01X1427649D01*
G02X1427477Y209242I1J200D01*
G01X1427302Y209540D01*
G02X1427275Y209641I173J100D01*
G01Y209693D01*
X1427282Y209706D01*
X1427301Y209739D01*
G03X1427495Y210477I-1308J738D01*
G01Y210478D01*
G03X1427125Y211465I-1501J0D01*
G01X1427101Y211493D01*
X1427089Y211526D01*
G02X1427076Y211596I187J71D01*
G01Y211860D01*
G02X1427089Y211930I200J-1D01*
G01X1427101Y211963D01*
X1427125Y211991D01*
G03Y213965I-1131J987D01*
G01X1427101Y213993D01*
X1427089Y214026D01*
G02X1427076Y214096I187J71D01*
G01Y214360D01*
G02X1427089Y214430I200J-1D01*
G01X1427101Y214463D01*
X1427125Y214491D01*
G03X1427495Y215478I-1131J987D01*
G03X1424491I-1502J0D01*
G03X1424861Y214491I1501J0D01*
G01X1424885Y214463D01*
X1424897Y214430D01*
G02X1424910Y214360I-187J-71D01*
G01Y214096D01*
G02X1424897Y214026I-200J1D01*
G01X1424885Y213993D01*
X1424861Y213965D01*
G03Y211991I1131J-987D01*
G01X1424885Y211963D01*
X1424897Y211930D01*
G02X1424910Y211860I-187J-71D01*
G01Y211596D01*
G02X1424897Y211526I-200J1D01*
G01X1424885Y211493D01*
X1424861Y211465D01*
G03X1424491Y210478I1131J-987D01*
G01Y210477D01*
G03X1424685Y209739I1502J0D01*
G01X1424704Y209706D01*
X1424711Y209693D01*
Y209641D01*
G02X1424684Y209540I-200J-1D01*
G01X1424509Y209242D01*
G02X1424337Y209143I-173J101D01*
G01X1401046D01*
G02X1400877Y209237I1J200D01*
G01X1400738Y209480D01*
X1400700Y209546D01*
G02X1400674Y209645I174J99D01*
G01Y209699D01*
X1400702Y209746D01*
G03X1400910Y210509I-1294J763D01*
G01Y210533D01*
G03X1399408Y212011I-1502J-24D01*
G03X1398421Y211641I0J-1501D01*
G01X1398393Y211617D01*
X1398360Y211605D01*
G02X1398290Y211592I-71J187D01*
G01X1398026D01*
G02X1397956Y211605I1J200D01*
G01X1397923Y211617D01*
X1397895Y211641D01*
G03X1396908Y212011I-987J-1131D01*
G03X1395406Y210533I0J-1502D01*
G01Y210509D01*
G03X1395614Y209746I1502J0D01*
G01X1395628Y209723D01*
X1395642Y209671D01*
Y209645D01*
G02X1395616Y209546I-200J0D01*
G01X1395578Y209480D01*
X1395439Y209237D01*
G02X1395270Y209143I-170J106D01*
G01X1330773D01*
G02X1330651Y209185I1J200D01*
G01X1330626Y209205D01*
X1330590Y209260D01*
X1330581Y209295D01*
G03X1327081I-1750J-431D01*
G01Y209294D01*
G02X1327009Y209183I-194J47D01*
G01X1326985Y209164D01*
X1326922Y209143D01*
X1295213D01*
G02X1295097Y209181I1J200D01*
G01X1295072Y209198D01*
X1295036Y209247D01*
X1295025Y209278D01*
G03X1294309Y210202I-1706J-582D01*
G01X1294273Y210225D01*
X1294251Y210259D01*
G02X1294222Y210333I168J109D01*
G01X1294172Y210625D01*
G02X1294176Y210708I197J32D01*
G01X1294185Y210745D01*
X1294211Y210779D01*
G03X1294522Y211693I-1191J915D01*
G01Y211695D01*
G03X1293020Y213197I-1502J0D01*
G03X1292033Y212827I0J-1501D01*
G01X1292005Y212803D01*
X1291972Y212791D01*
G02X1291902Y212778I-71J187D01*
G01X1291638D01*
G02X1291568Y212791I1J200D01*
G01X1291535Y212803D01*
X1291507Y212827D01*
G03X1290520Y213197I-987J-1131D01*
G03X1289018Y211695I0J-1502D01*
G03X1289597Y210510I1502J0D01*
G02X1289672Y210382I-123J-158D01*
G02X1289674Y210352I-198J-28D01*
G01Y210038D01*
G02X1289672Y210008I-200J-2D01*
G02X1289603Y209885I-198J30D01*
G02X1289597Y209880I-131J151D01*
G03X1289131Y209267I923J-1185D01*
G01X1289114Y209226D01*
X1289082Y209196D01*
G02X1289056Y209176I-134J148D01*
G01X1289032Y209160D01*
X1288977Y209143D01*
X1287720D01*
X1287717D01*
G02X1287576Y209204I3J200D01*
G03X1287530Y209255I-1138J-980D01*
G03X1287526Y209259I-143J-139D01*
G02X1287474Y209350I141J141D01*
G02X1287467Y209400I193J52D01*
G01Y209526D01*
G02X1287483Y209603I200J-1D01*
G03X1287966Y210713I-1034J1110D01*
G03X1287542Y211766I-1520J0D01*
G01X1287531Y211795D01*
Y212095D01*
G02X1287544Y212165I200J-1D01*
G01X1287556Y212198D01*
X1287580Y212226D01*
G03Y214200I-1131J987D01*
G01X1287556Y214228D01*
X1287544Y214261D01*
G02X1287531Y214331I187J71D01*
G01Y214595D01*
G02X1287544Y214665I200J-1D01*
G01X1287556Y214698D01*
X1287580Y214726D01*
G03X1287950Y215713I-1131J987D01*
G03X1284946I-1502J0D01*
G03X1285316Y214726I1501J0D01*
G01X1285340Y214698D01*
X1285352Y214665D01*
G02X1285365Y214595I-187J-71D01*
G01Y214331D01*
G02X1285352Y214261I-200J1D01*
G01X1285340Y214228D01*
X1285316Y214200D01*
G03Y212226I1131J-987D01*
G01X1285340Y212198D01*
X1285352Y212165D01*
G02X1285365Y212095I-187J-71D01*
G01Y211795D01*
X1285354Y211766D01*
G03X1284930Y210713I1096J-1053D01*
G03X1285414Y209602I1517J0D01*
G02X1285429Y209527I-185J-76D01*
G01Y209401D01*
G02X1285426Y209365I-200J-1D01*
G02X1285422Y209350I-195J44D01*
G02X1285370Y209259I-193J50D01*
G03X1285366Y209255I139J-143D01*
G03X1285320Y209204I1092J-1031D01*
G02X1285179Y209143I-144J139D01*
G01X1277648D01*
G02X1277476Y209242I1J200D01*
G01X1277301Y209540D01*
G02X1277274Y209641I173J100D01*
G01Y209693D01*
X1277281Y209706D01*
X1277300Y209739D01*
G03X1277494Y210477I-1308J738D01*
G01Y210478D01*
G03X1277124Y211465I-1501J0D01*
G01X1277100Y211493D01*
X1277088Y211526D01*
G02X1277075Y211596I187J71D01*
G01Y211860D01*
G02X1277088Y211930I200J-1D01*
G01X1277100Y211963D01*
X1277124Y211991D01*
G03Y213965I-1131J987D01*
G01X1277100Y213993D01*
X1277088Y214026D01*
G02X1277075Y214096I187J71D01*
G01Y214360D01*
G02X1277088Y214430I200J-1D01*
G01X1277100Y214463D01*
X1277124Y214491D01*
G03X1277494Y215478I-1131J987D01*
G03X1274490I-1502J0D01*
G03X1274860Y214491I1501J0D01*
G01X1274884Y214463D01*
X1274896Y214430D01*
G02X1274909Y214360I-187J-71D01*
G01Y214096D01*
G02X1274896Y214026I-200J1D01*
G01X1274884Y213993D01*
X1274860Y213965D01*
G03Y211991I1131J-987D01*
G01X1274884Y211963D01*
X1274896Y211930D01*
G02X1274909Y211860I-187J-71D01*
G01Y211596D01*
G02X1274896Y211526I-200J1D01*
G01X1274884Y211493D01*
X1274860Y211465D01*
G03X1274490Y210478I1131J-987D01*
G01Y210477D01*
G03X1274684Y209739I1502J0D01*
G01X1274703Y209706D01*
X1274710Y209693D01*
Y209641D01*
G02X1274683Y209540I-200J-1D01*
G01X1274508Y209242D01*
G02X1274336Y209143I-173J101D01*
G01X1251045D01*
G02X1250876Y209237I1J200D01*
G01X1250737Y209480D01*
X1250699Y209546D01*
G02X1250673Y209645I174J99D01*
G01Y209699D01*
X1250701Y209746D01*
G03X1250909Y210509I-1294J763D01*
G01Y210533D01*
G03X1249407Y212011I-1502J-24D01*
G03X1248420Y211641I0J-1501D01*
G01X1248392Y211617D01*
X1248359Y211605D01*
G02X1248289Y211592I-71J187D01*
G01X1248025D01*
G02X1247955Y211605I1J200D01*
G01X1247922Y211617D01*
X1247894Y211641D01*
G03X1246907Y212011I-987J-1131D01*
G03X1245405Y210533I0J-1502D01*
G01Y210509D01*
G03X1245613Y209746I1502J0D01*
G01X1245627Y209723D01*
X1245641Y209671D01*
Y209645D01*
G02X1245615Y209546I-200J0D01*
G01X1245577Y209480D01*
X1245438Y209237D01*
G02X1245269Y209143I-170J106D01*
G01X1228411D01*
G02X1228289Y209185I1J200D01*
G01X1228264Y209205D01*
X1228228Y209260D01*
X1228219Y209295D01*
G03X1224719I-1750J-431D01*
G01Y209294D01*
G02X1224647Y209183I-194J47D01*
G01X1224623Y209164D01*
X1224560Y209143D01*
X1192851D01*
G02X1192735Y209181I1J200D01*
G01X1192710Y209198D01*
X1192674Y209247D01*
X1192663Y209278D01*
G03X1191947Y210202I-1706J-582D01*
G01X1191911Y210225D01*
X1191889Y210259D01*
G02X1191860Y210333I168J109D01*
G01X1191810Y210625D01*
G02X1191814Y210708I197J32D01*
G01X1191823Y210745D01*
X1191849Y210779D01*
G03X1192160Y211693I-1191J915D01*
G01Y211695D01*
G03X1190658Y213197I-1502J0D01*
G03X1189671Y212827I0J-1501D01*
G01X1189643Y212803D01*
X1189610Y212791D01*
G02X1189540Y212778I-71J187D01*
G01X1189276D01*
G02X1189206Y212791I1J200D01*
G01X1189173Y212803D01*
X1189145Y212827D01*
G03X1188158Y213197I-987J-1131D01*
G03X1186656Y211695I0J-1502D01*
G03X1187235Y210510I1502J0D01*
G02X1187310Y210382I-123J-158D01*
G02X1187312Y210352I-198J-28D01*
G01Y210038D01*
G02X1187310Y210008I-200J-2D01*
G02X1187241Y209885I-198J30D01*
G02X1187235Y209880I-131J151D01*
G03X1186769Y209267I923J-1185D01*
G01X1186752Y209226D01*
X1186720Y209196D01*
G02X1186694Y209176I-134J148D01*
G01X1186670Y209160D01*
X1186615Y209143D01*
X1185358D01*
X1185355D01*
G02X1185214Y209204I3J200D01*
G03X1185168Y209255I-1138J-980D01*
G03X1185164Y209259I-143J-139D01*
G02X1185112Y209350I141J141D01*
G02X1185105Y209400I193J52D01*
G01Y209526D01*
G02X1185121Y209603I200J-1D01*
G03X1185604Y210713I-1034J1110D01*
G03X1185180Y211766I-1520J0D01*
G01X1185169Y211795D01*
Y212095D01*
G02X1185182Y212165I200J-1D01*
G01X1185194Y212198D01*
X1185218Y212226D01*
G03Y214200I-1131J987D01*
G01X1185194Y214228D01*
X1185182Y214261D01*
G02X1185169Y214331I187J71D01*
G01Y214595D01*
G02X1185182Y214665I200J-1D01*
G01X1185194Y214698D01*
X1185218Y214726D01*
G03X1185588Y215713I-1131J987D01*
G03X1182584I-1502J0D01*
G03X1182954Y214726I1501J0D01*
G01X1182978Y214698D01*
X1182990Y214665D01*
G02X1183003Y214595I-187J-71D01*
G01Y214331D01*
G02X1182990Y214261I-200J1D01*
G01X1182978Y214228D01*
X1182954Y214200D01*
G03Y212226I1131J-987D01*
G01X1182978Y212198D01*
X1182990Y212165D01*
G02X1183003Y212095I-187J-71D01*
G01Y211795D01*
X1182992Y211766D01*
G03X1182568Y210713I1096J-1053D01*
G03X1183052Y209602I1517J0D01*
G02X1183067Y209527I-185J-76D01*
G01Y209401D01*
G02X1183064Y209365I-200J-1D01*
G02X1183060Y209350I-195J44D01*
G02X1183008Y209259I-193J50D01*
G03X1183004Y209255I139J-143D01*
G03X1182958Y209204I1092J-1031D01*
G02X1182817Y209143I-144J139D01*
G01X1175286D01*
G02X1175114Y209242I1J200D01*
G01X1174939Y209540D01*
G02X1174912Y209641I173J100D01*
G01Y209693D01*
X1174919Y209706D01*
X1174938Y209739D01*
G03X1175132Y210477I-1308J738D01*
G01Y210478D01*
G03X1174762Y211465I-1501J0D01*
G01X1174738Y211493D01*
X1174726Y211526D01*
G02X1174713Y211596I187J71D01*
G01Y211860D01*
G02X1174726Y211930I200J-1D01*
G01X1174738Y211963D01*
X1174762Y211991D01*
G03Y213965I-1131J987D01*
G01X1174738Y213993D01*
X1174726Y214026D01*
G02X1174713Y214096I187J71D01*
G01Y214360D01*
G02X1174726Y214430I200J-1D01*
G01X1174738Y214463D01*
X1174762Y214491D01*
G03X1175132Y215478I-1131J987D01*
G03X1172128I-1502J0D01*
G03X1172498Y214491I1501J0D01*
G01X1172522Y214463D01*
X1172534Y214430D01*
G02X1172547Y214360I-187J-71D01*
G01Y214096D01*
G02X1172534Y214026I-200J1D01*
G01X1172522Y213993D01*
X1172498Y213965D01*
G03Y211991I1131J-987D01*
G01X1172522Y211963D01*
X1172534Y211930D01*
G02X1172547Y211860I-187J-71D01*
G01Y211596D01*
G02X1172534Y211526I-200J1D01*
G01X1172522Y211493D01*
X1172498Y211465D01*
G03X1172128Y210478I1131J-987D01*
G01Y210477D01*
G03X1172322Y209739I1502J0D01*
G01X1172341Y209706D01*
X1172348Y209693D01*
Y209641D01*
G02X1172321Y209540I-200J-1D01*
G01X1172146Y209242D01*
G02X1171974Y209143I-173J101D01*
G01X1148683D01*
G02X1148514Y209237I1J200D01*
G01X1148375Y209480D01*
X1148337Y209546D01*
G02X1148311Y209645I174J99D01*
G01Y209699D01*
X1148339Y209746D01*
G03X1148547Y210509I-1294J763D01*
G01Y210533D01*
G03X1147045Y212011I-1502J-24D01*
G03X1146058Y211641I0J-1501D01*
G01X1146030Y211617D01*
X1145997Y211605D01*
G02X1145927Y211592I-71J187D01*
G01X1145663D01*
G02X1145593Y211605I1J200D01*
G01X1145560Y211617D01*
X1145532Y211641D01*
G03X1144545Y212011I-987J-1131D01*
G03X1143043Y210533I0J-1502D01*
G01Y210509D01*
G03X1143251Y209746I1502J0D01*
G01X1143265Y209723D01*
X1143279Y209671D01*
Y209645D01*
G02X1143253Y209546I-200J0D01*
G01X1143215Y209480D01*
X1143076Y209237D01*
G02X1142907Y209143I-170J106D01*
G01X1126049D01*
G02X1125927Y209185I1J200D01*
G01X1125902Y209205D01*
X1125866Y209260D01*
X1125857Y209295D01*
G03X1122357I-1750J-431D01*
G01Y209294D01*
G02X1122285Y209183I-194J47D01*
G01X1122261Y209164D01*
X1122198Y209143D01*
X1090489D01*
G02X1090373Y209181I1J200D01*
G01X1090348Y209198D01*
X1090312Y209247D01*
X1090301Y209278D01*
G03X1089585Y210202I-1706J-582D01*
G01X1089549Y210225D01*
X1089527Y210259D01*
G02X1089498Y210333I168J109D01*
G01X1089448Y210625D01*
G02X1089452Y210708I197J32D01*
G01X1089461Y210745D01*
X1089487Y210779D01*
G03X1089798Y211693I-1191J915D01*
G01Y211695D01*
G03X1088296Y213197I-1502J0D01*
G03X1087309Y212827I0J-1501D01*
G01X1087281Y212803D01*
X1087248Y212791D01*
G02X1087178Y212778I-71J187D01*
G01X1086914D01*
G02X1086844Y212791I1J200D01*
G01X1086811Y212803D01*
X1086783Y212827D01*
G03X1085796Y213197I-987J-1131D01*
G03X1084294Y211695I0J-1502D01*
G03X1084873Y210510I1502J0D01*
G02X1084948Y210382I-123J-158D01*
G02X1084950Y210352I-198J-28D01*
G01Y210038D01*
G02X1084948Y210008I-200J-2D01*
G02X1084879Y209885I-198J30D01*
G02X1084873Y209880I-131J151D01*
G03X1084407Y209267I923J-1185D01*
G01X1084390Y209226D01*
X1084358Y209196D01*
G02X1084332Y209176I-134J148D01*
G01X1084308Y209160D01*
X1084253Y209143D01*
X1082996D01*
X1082993D01*
G02X1082852Y209204I3J200D01*
G03X1082806Y209255I-1138J-980D01*
G03X1082802Y209259I-143J-139D01*
G02X1082750Y209350I141J141D01*
G02X1082743Y209400I193J52D01*
G01Y209526D01*
G02X1082759Y209603I200J-1D01*
G03X1083242Y210713I-1034J1110D01*
G03X1082818Y211766I-1520J0D01*
G01X1082807Y211795D01*
Y212095D01*
G02X1082820Y212165I200J-1D01*
G01X1082832Y212198D01*
X1082856Y212226D01*
G03Y214200I-1131J987D01*
G01X1082832Y214228D01*
X1082820Y214261D01*
G02X1082807Y214331I187J71D01*
G01Y214595D01*
G02X1082820Y214665I200J-1D01*
G01X1082832Y214698D01*
X1082856Y214726D01*
G03X1083226Y215713I-1131J987D01*
G03X1080222I-1502J0D01*
G03X1080592Y214726I1501J0D01*
G01X1080616Y214698D01*
X1080628Y214665D01*
G02X1080641Y214595I-187J-71D01*
G01Y214331D01*
G02X1080628Y214261I-200J1D01*
G01X1080616Y214228D01*
X1080592Y214200D01*
G03Y212226I1131J-987D01*
G01X1080616Y212198D01*
X1080628Y212165D01*
G02X1080641Y212095I-187J-71D01*
G01Y211795D01*
X1080630Y211766D01*
G03X1080206Y210713I1096J-1053D01*
G03X1080690Y209602I1517J0D01*
G02X1080705Y209527I-185J-76D01*
G01Y209401D01*
G02X1080702Y209365I-200J-1D01*
G02X1080698Y209350I-195J44D01*
G02X1080646Y209259I-193J50D01*
G03X1080642Y209255I139J-143D01*
G03X1080596Y209204I1092J-1031D01*
G02X1080455Y209143I-144J139D01*
G01X1072924D01*
G02X1072752Y209242I1J200D01*
G01X1072577Y209540D01*
G02X1072550Y209641I173J100D01*
G01Y209693D01*
X1072557Y209706D01*
X1072576Y209739D01*
G03X1072770Y210477I-1308J738D01*
G01Y210478D01*
G03X1072400Y211465I-1501J0D01*
G01X1072376Y211493D01*
X1072364Y211526D01*
G02X1072351Y211596I187J71D01*
G01Y211860D01*
G02X1072364Y211930I200J-1D01*
G01X1072376Y211963D01*
X1072400Y211991D01*
G03Y213965I-1131J987D01*
G01X1072376Y213993D01*
X1072364Y214026D01*
G02X1072351Y214096I187J71D01*
G01Y214360D01*
G02X1072364Y214430I200J-1D01*
G01X1072376Y214463D01*
X1072400Y214491D01*
G03X1072770Y215478I-1131J987D01*
G03X1069766I-1502J0D01*
G03X1070136Y214491I1501J0D01*
G01X1070160Y214463D01*
X1070172Y214430D01*
G02X1070185Y214360I-187J-71D01*
G01Y214096D01*
G02X1070172Y214026I-200J1D01*
G01X1070160Y213993D01*
X1070136Y213965D01*
G03Y211991I1131J-987D01*
G01X1070160Y211963D01*
X1070172Y211930D01*
G02X1070185Y211860I-187J-71D01*
G01Y211596D01*
G02X1070172Y211526I-200J1D01*
G01X1070160Y211493D01*
X1070136Y211465D01*
G03X1069766Y210478I1131J-987D01*
G01Y210477D01*
G03X1069960Y209739I1502J0D01*
G01X1069979Y209706D01*
X1069986Y209693D01*
Y209641D01*
G02X1069959Y209540I-200J-1D01*
G01X1069784Y209242D01*
G02X1069612Y209143I-173J101D01*
G01X1046321D01*
G02X1046152Y209237I1J200D01*
G01X1046013Y209480D01*
X1045975Y209546D01*
G02X1045949Y209645I174J99D01*
G01Y209699D01*
X1045977Y209746D01*
G03X1046185Y210509I-1294J763D01*
G01Y210533D01*
G03X1044683Y212011I-1502J-24D01*
G03X1043696Y211641I0J-1501D01*
G01X1043668Y211617D01*
X1043635Y211605D01*
G02X1043565Y211592I-71J187D01*
G01X1043301D01*
G02X1043231Y211605I1J200D01*
G01X1043198Y211617D01*
X1043170Y211641D01*
G03X1042183Y212011I-987J-1131D01*
G03X1040681Y210533I0J-1502D01*
G01Y210509D01*
G03X1040889Y209746I1502J0D01*
G01X1040903Y209723D01*
X1040917Y209671D01*
Y209645D01*
G02X1040891Y209546I-200J0D01*
G01X1040853Y209480D01*
X1040714Y209237D01*
G02X1040545Y209143I-170J106D01*
G01X1023378D01*
G02X1023258Y209183I0J200D01*
G01X1023231Y209203D01*
X1023196Y209255D01*
X1023186Y209287D01*
G03X1020304I-1441J-423D01*
G01Y209286D01*
G02X1020232Y209183I-192J57D01*
G01X1020206Y209163D01*
X1020145Y209143D01*
X988127D01*
G02X988011Y209181I1J200D01*
G01X987986Y209198D01*
X987950Y209247D01*
X987939Y209278D01*
G03X987223Y210202I-1706J-582D01*
G01X987187Y210225D01*
X987165Y210259D01*
G02X987136Y210333I168J109D01*
G01X987086Y210625D01*
G02X987090Y210708I197J32D01*
G01X987099Y210745D01*
X987125Y210779D01*
G03X987436Y211693I-1191J915D01*
G01Y211695D01*
G03X985934Y213197I-1502J0D01*
G03X984947Y212827I0J-1501D01*
G01X984919Y212803D01*
X984886Y212791D01*
G02X984816Y212778I-71J187D01*
G01X984552D01*
G02X984482Y212791I1J200D01*
G01X984449Y212803D01*
X984421Y212827D01*
G03X983434Y213197I-987J-1131D01*
G03X981932Y211695I0J-1502D01*
G03X982511Y210510I1502J0D01*
G02X982586Y210382I-123J-158D01*
G02X982588Y210352I-198J-28D01*
G01Y210038D01*
G02X982586Y210008I-200J-2D01*
G02X982517Y209885I-198J30D01*
G02X982511Y209880I-131J151D01*
G03X982045Y209267I923J-1185D01*
G01X982028Y209226D01*
X981996Y209196D01*
G02X981970Y209176I-134J148D01*
G01X981946Y209160D01*
X981891Y209143D01*
X980634D01*
X980631D01*
G02X980490Y209204I3J200D01*
G03X980444Y209255I-1138J-980D01*
G03X980440Y209259I-143J-139D01*
G02X980388Y209350I141J141D01*
G02X980381Y209400I193J52D01*
G01Y209526D01*
G02X980397Y209603I200J-1D01*
G03X980880Y210713I-1034J1110D01*
G03X980456Y211766I-1520J0D01*
G01X980445Y211795D01*
Y212095D01*
G02X980458Y212165I200J-1D01*
G01X980470Y212198D01*
X980494Y212226D01*
G03Y214200I-1131J987D01*
G01X980470Y214228D01*
X980458Y214261D01*
G02X980445Y214331I187J71D01*
G01Y214595D01*
G02X980458Y214665I200J-1D01*
G01X980470Y214698D01*
X980494Y214726D01*
G03X980864Y215713I-1131J987D01*
G03X977860I-1502J0D01*
G03X978230Y214726I1501J0D01*
G01X978254Y214698D01*
X978266Y214665D01*
G02X978279Y214595I-187J-71D01*
G01Y214331D01*
G02X978266Y214261I-200J1D01*
G01X978254Y214228D01*
X978230Y214200D01*
G03Y212226I1131J-987D01*
G01X978254Y212198D01*
X978266Y212165D01*
G02X978279Y212095I-187J-71D01*
G01Y211795D01*
X978268Y211766D01*
G03X977844Y210713I1096J-1053D01*
G03X978328Y209602I1517J0D01*
G02X978343Y209527I-185J-76D01*
G01Y209401D01*
G02X978340Y209365I-200J-1D01*
G02X978336Y209350I-195J44D01*
G02X978284Y209259I-193J50D01*
G03X978280Y209255I139J-143D01*
G03X978234Y209204I1092J-1031D01*
G02X978093Y209143I-144J139D01*
G01X970562D01*
G02X970390Y209242I1J200D01*
G01X970215Y209540D01*
G02X970188Y209641I173J100D01*
G01Y209693D01*
X970195Y209706D01*
X970214Y209739D01*
G03X970408Y210477I-1308J738D01*
G01Y210478D01*
G03X970038Y211465I-1501J0D01*
G01X970014Y211493D01*
X970002Y211526D01*
G02X969989Y211596I187J71D01*
G01Y211860D01*
G02X970002Y211930I200J-1D01*
G01X970014Y211963D01*
X970038Y211991D01*
G03Y213965I-1131J987D01*
G01X970014Y213993D01*
X970002Y214026D01*
G02X969989Y214096I187J71D01*
G01Y214360D01*
G02X970002Y214430I200J-1D01*
G01X970014Y214463D01*
X970038Y214491D01*
G03X970408Y215478I-1131J987D01*
G03X967404I-1502J0D01*
G03X967774Y214491I1501J0D01*
G01X967798Y214463D01*
X967810Y214430D01*
G02X967823Y214360I-187J-71D01*
G01Y214096D01*
G02X967810Y214026I-200J1D01*
G01X967798Y213993D01*
X967774Y213965D01*
G03Y211991I1131J-987D01*
G01X967798Y211963D01*
X967810Y211930D01*
G02X967823Y211860I-187J-71D01*
G01Y211596D01*
G02X967810Y211526I-200J1D01*
G01X967798Y211493D01*
X967774Y211465D01*
G03X967404Y210478I1131J-987D01*
G01Y210477D01*
G03X967598Y209739I1502J0D01*
G01X967617Y209706D01*
X967624Y209693D01*
Y209641D01*
G02X967597Y209540I-200J-1D01*
G01X967422Y209242D01*
G02X967250Y209143I-173J101D01*
G01X951210D01*
G02X951049Y209225I0J200D01*
G03X949443Y210108I-1606J-1019D01*
G03X948098Y209551I0J-1902D01*
G01X947748Y209201D01*
G02X947608Y209143I-141J142D01*
G01X939114D01*
G02X938988Y209187I-1J200D01*
G01X938962Y209208D01*
X938927Y209266D01*
X938919Y209302D01*
G03X938757Y209576I-490J-105D01*
G02X938755Y209578I140J142D01*
G01X938701Y209626D01*
X938690Y209648D01*
Y212511D01*
G02X938709Y212539I175J-98D01*
G03X939240Y213815I-1271J1278D01*
G01Y213817D01*
G03X935636I-1802J0D01*
G01Y213815D01*
G03X935647Y213617I1802J1D01*
G03X936113Y212594I1792J199D01*
G01X936165Y212538D01*
X936166Y212536D01*
Y212169D01*
G02X936121Y212115I-174J99D01*
G01X935856D01*
X935845Y212122D01*
X935792Y212218D01*
G03X934477Y212993I-1315J-728D01*
G03Y209989I0J-1502D01*
G03X935515Y210405I0J1503D01*
G01X935517Y210407D01*
X935538Y210427D01*
X935590Y210453D01*
X935617Y210458D01*
G02X935731Y210445I35J-197D01*
G01X936070Y210300D01*
G02X936166Y210214I-78J-184D01*
G01Y209648D01*
X936155Y209626D01*
X936101Y209578D01*
G02X936099Y209576I-142J140D01*
G03X935937Y209302I328J-379D01*
G01Y209301D01*
G02X935867Y209186I-196J41D01*
G01X935841Y209166D01*
X935777Y209143D01*
X873378D01*
G02X873258Y209183I0J200D01*
G01X873231Y209203D01*
X873196Y209255D01*
X873186Y209287D01*
G03X870304I-1441J-423D01*
G01Y209286D01*
G02X870232Y209183I-192J57D01*
G01X870206Y209163D01*
X870145Y209143D01*
X838127D01*
G02X838011Y209181I1J200D01*
G01X837986Y209198D01*
X837950Y209247D01*
X837939Y209278D01*
G03X837223Y210202I-1706J-582D01*
G01X837187Y210225D01*
X837165Y210259D01*
G02X837136Y210333I168J109D01*
G01X837086Y210625D01*
G02X837090Y210708I197J32D01*
G01X837099Y210745D01*
X837125Y210779D01*
G03X837436Y211693I-1191J915D01*
G01Y211695D01*
G03X835934Y213197I-1502J0D01*
G03X834947Y212827I0J-1501D01*
G01X834919Y212803D01*
X834886Y212791D01*
G02X834816Y212778I-71J187D01*
G01X834552D01*
G02X834482Y212791I1J200D01*
G01X834449Y212803D01*
X834421Y212827D01*
G03X833434Y213197I-987J-1131D01*
G03X831932Y211695I0J-1502D01*
G03X832511Y210510I1502J0D01*
G02X832586Y210382I-123J-158D01*
G02X832588Y210352I-198J-28D01*
G01Y210038D01*
G02X832586Y210008I-200J-2D01*
G02X832517Y209885I-198J30D01*
G02X832511Y209880I-131J151D01*
G03X832045Y209267I923J-1185D01*
G01X832028Y209226D01*
X831996Y209196D01*
G02X831970Y209176I-134J148D01*
G01X831946Y209160D01*
X831891Y209143D01*
X830634D01*
X830631D01*
G02X830490Y209204I3J200D01*
G03X830444Y209255I-1138J-980D01*
G03X830440Y209259I-143J-139D01*
G02X830388Y209350I141J141D01*
G02X830381Y209400I193J52D01*
G01Y209526D01*
G02X830397Y209603I200J-1D01*
G03X830880Y210713I-1034J1110D01*
G03X830456Y211766I-1520J0D01*
G01X830445Y211795D01*
Y212095D01*
G02X830458Y212165I200J-1D01*
G01X830470Y212198D01*
X830494Y212226D01*
G03Y214200I-1131J987D01*
G01X830470Y214228D01*
X830458Y214261D01*
G02X830445Y214331I187J71D01*
G01Y214595D01*
G02X830458Y214665I200J-1D01*
G01X830470Y214698D01*
X830494Y214726D01*
G03X830864Y215713I-1131J987D01*
G03X827860I-1502J0D01*
G03X828230Y214726I1501J0D01*
G01X828254Y214698D01*
X828266Y214665D01*
G02X828279Y214595I-187J-71D01*
G01Y214331D01*
G02X828266Y214261I-200J1D01*
G01X828254Y214228D01*
X828230Y214200D01*
G03Y212226I1131J-987D01*
G01X828254Y212198D01*
X828266Y212165D01*
G02X828279Y212095I-187J-71D01*
G01Y211795D01*
X828268Y211766D01*
G03X827844Y210713I1096J-1053D01*
G03X828328Y209602I1517J0D01*
G02X828343Y209527I-185J-76D01*
G01Y209401D01*
G02X828340Y209365I-200J-1D01*
G02X828336Y209350I-195J44D01*
G02X828284Y209259I-193J50D01*
G03X828280Y209255I139J-143D01*
G03X828234Y209204I1092J-1031D01*
G02X828093Y209143I-144J139D01*
G01X820562D01*
G02X820390Y209242I1J200D01*
G01X820215Y209540D01*
G02X820188Y209641I173J100D01*
G01Y209693D01*
X820195Y209706D01*
X820214Y209739D01*
G03X820408Y210477I-1308J738D01*
G01Y210478D01*
G03X820038Y211465I-1501J0D01*
G01X820014Y211493D01*
X820002Y211526D01*
G02X819989Y211596I187J71D01*
G01Y211860D01*
G02X820002Y211930I200J-1D01*
G01X820014Y211963D01*
X820038Y211991D01*
G03Y213965I-1131J987D01*
G01X820014Y213993D01*
X820002Y214026D01*
G02X819989Y214096I187J71D01*
G01Y214360D01*
G02X820002Y214430I200J-1D01*
G01X820014Y214463D01*
X820038Y214491D01*
G03X820408Y215478I-1131J987D01*
G03X817404I-1502J0D01*
G03X817774Y214491I1501J0D01*
G01X817798Y214463D01*
X817810Y214430D01*
G02X817823Y214360I-187J-71D01*
G01Y214096D01*
G02X817810Y214026I-200J1D01*
G01X817798Y213993D01*
X817774Y213965D01*
G03Y211991I1131J-987D01*
G01X817798Y211963D01*
X817810Y211930D01*
G02X817823Y211860I-187J-71D01*
G01Y211596D01*
G02X817810Y211526I-200J1D01*
G01X817798Y211493D01*
X817774Y211465D01*
G03X817404Y210478I1131J-987D01*
G01Y210477D01*
G03X817598Y209739I1502J0D01*
G01X817617Y209706D01*
X817624Y209693D01*
Y209641D01*
G02X817597Y209540I-200J-1D01*
G01X817422Y209242D01*
G02X817250Y209143I-173J101D01*
G01X793959D01*
G02X793790Y209237I1J200D01*
G01X793651Y209480D01*
X793613Y209546D01*
G02X793587Y209645I174J99D01*
G01Y209699D01*
X793615Y209746D01*
G03X793823Y210509I-1294J763D01*
G01Y210533D01*
G03X792321Y212011I-1502J-24D01*
G03X791334Y211641I0J-1501D01*
G01X791306Y211617D01*
X791273Y211605D01*
G02X791203Y211592I-71J187D01*
G01X790939D01*
G02X790869Y211605I1J200D01*
G01X790836Y211617D01*
X790808Y211641D01*
G03X789821Y212011I-987J-1131D01*
G03X788319Y210533I0J-1502D01*
G01Y210509D01*
G03X788527Y209746I1502J0D01*
G01X788541Y209723D01*
X788555Y209671D01*
Y209645D01*
G02X788529Y209546I-200J0D01*
G01X788491Y209480D01*
X788352Y209237D01*
G02X788183Y209143I-170J106D01*
G01X771325D01*
G02X771203Y209185I1J200D01*
G01X771178Y209205D01*
X771142Y209260D01*
X771133Y209295D01*
G03X767633I-1750J-431D01*
G01Y209294D01*
G02X767561Y209183I-194J47D01*
G01X767537Y209164D01*
X767474Y209143D01*
X735765D01*
G02X735649Y209181I1J200D01*
G01X735624Y209198D01*
X735588Y209247D01*
X735577Y209278D01*
G03X734861Y210202I-1706J-582D01*
G01X734825Y210225D01*
X734803Y210259D01*
G02X734774Y210333I168J109D01*
G01X734724Y210625D01*
G02X734728Y210708I197J32D01*
G01X734737Y210745D01*
X734763Y210779D01*
G03X735074Y211693I-1191J915D01*
G01Y211695D01*
G03X733572Y213197I-1502J0D01*
G03X732585Y212827I0J-1501D01*
G01X732557Y212803D01*
X732524Y212791D01*
G02X732454Y212778I-71J187D01*
G01X732190D01*
G02X732120Y212791I1J200D01*
G01X732087Y212803D01*
X732059Y212827D01*
G03X731072Y213197I-987J-1131D01*
G03X729570Y211695I0J-1502D01*
G03X730149Y210510I1502J0D01*
G02X730224Y210382I-123J-158D01*
G02X730226Y210352I-198J-28D01*
G01Y210038D01*
G02X730224Y210008I-200J-2D01*
G02X730155Y209885I-198J30D01*
G02X730149Y209880I-131J151D01*
G03X729683Y209267I923J-1185D01*
G01X729666Y209226D01*
X729634Y209196D01*
G02X729608Y209176I-134J148D01*
G01X729584Y209160D01*
X729529Y209143D01*
X728272D01*
X728269D01*
G02X728128Y209204I3J200D01*
G03X728082Y209255I-1138J-980D01*
G03X728078Y209259I-143J-139D01*
G02X728026Y209350I141J141D01*
G02X728019Y209400I193J52D01*
G01Y209525D01*
G02X728022Y209561I200J1D01*
G02X728076Y209665I197J-36D01*
G03X728502Y210713I-1076J1048D01*
G03X728132Y211700I-1501J0D01*
G01X728108Y211728D01*
X728096Y211761D01*
G02X728083Y211831I187J71D01*
G01Y212095D01*
G02X728096Y212165I200J-1D01*
G01X728108Y212198D01*
X728132Y212226D01*
G03Y214200I-1131J987D01*
G01X728108Y214228D01*
X728096Y214261D01*
G02X728083Y214331I187J71D01*
G01Y214595D01*
G02X728096Y214665I200J-1D01*
G01X728108Y214698D01*
X728132Y214726D01*
G03X728502Y215713I-1131J987D01*
G03X725498I-1502J0D01*
G03X725868Y214726I1501J0D01*
G01X725892Y214698D01*
X725904Y214665D01*
G02X725917Y214595I-187J-71D01*
G01Y214331D01*
G02X725904Y214261I-200J1D01*
G01X725892Y214228D01*
X725868Y214200D01*
G03Y212226I1131J-987D01*
G01X725892Y212198D01*
X725904Y212165D01*
G02X725917Y212095I-187J-71D01*
G01Y211831D01*
G02X725904Y211761I-200J1D01*
G01X725892Y211728D01*
X725868Y211700D01*
G03X725498Y210713I1131J-987D01*
G03X725511Y210513I1502J-3D01*
G03X725924Y209665I1489J200D01*
G01X725926Y209663D01*
G02X725979Y209556I-145J-138D01*
G02X725981Y209525I-198J-28D01*
G01Y209401D01*
G02X725978Y209365I-200J-1D01*
G02X725974Y209350I-195J44D01*
G02X725922Y209259I-193J50D01*
G03X725918Y209255I139J-143D01*
G03X725872Y209204I1092J-1031D01*
G02X725731Y209143I-144J139D01*
G01X718200D01*
G02X718028Y209242I1J200D01*
G01X717853Y209540D01*
G02X717826Y209641I173J100D01*
G01Y209693D01*
X717833Y209706D01*
X717852Y209739D01*
G03X718046Y210477I-1308J738D01*
G01Y210478D01*
G03X717676Y211465I-1501J0D01*
G01X717652Y211493D01*
X717640Y211526D01*
G02X717627Y211596I187J71D01*
G01Y211860D01*
G02X717640Y211930I200J-1D01*
G01X717652Y211963D01*
X717676Y211991D01*
G03Y213965I-1131J987D01*
G01X717652Y213993D01*
X717640Y214026D01*
G02X717627Y214096I187J71D01*
G01Y214360D01*
G02X717640Y214430I200J-1D01*
G01X717652Y214463D01*
X717676Y214491D01*
G03X718046Y215478I-1131J987D01*
G03X715042I-1502J0D01*
G03X715412Y214491I1501J0D01*
G01X715436Y214463D01*
X715448Y214430D01*
G02X715461Y214360I-187J-71D01*
G01Y214096D01*
G02X715448Y214026I-200J1D01*
G01X715436Y213993D01*
X715412Y213965D01*
G03Y211991I1131J-987D01*
G01X715436Y211963D01*
X715448Y211930D01*
G02X715461Y211860I-187J-71D01*
G01Y211596D01*
G02X715448Y211526I-200J1D01*
G01X715436Y211493D01*
X715412Y211465D01*
G03X715042Y210478I1131J-987D01*
G01Y210477D01*
G03X715236Y209739I1502J0D01*
G01X715255Y209706D01*
X715262Y209693D01*
Y209641D01*
G02X715235Y209540I-200J-1D01*
G01X715060Y209242D01*
G02X714888Y209143I-173J101D01*
G01X691597D01*
G02X691428Y209237I1J200D01*
G01X691289Y209480D01*
X691251Y209546D01*
G02X691225Y209645I174J99D01*
G01Y209699D01*
X691253Y209746D01*
G03X691461Y210509I-1294J763D01*
G01Y210533D01*
G03X689959Y212011I-1502J-24D01*
G03X688972Y211641I0J-1501D01*
G01X688944Y211617D01*
X688911Y211605D01*
G02X688841Y211592I-71J187D01*
G01X688577D01*
G02X688507Y211605I1J200D01*
G01X688474Y211617D01*
X688446Y211641D01*
G03X687459Y212011I-987J-1131D01*
G03X685957Y210533I0J-1502D01*
G01Y210509D01*
G03X686165Y209746I1502J0D01*
G01X686179Y209723D01*
X686193Y209671D01*
Y209645D01*
G02X686167Y209546I-200J0D01*
G01X686129Y209480D01*
X685990Y209237D01*
G02X685821Y209143I-170J106D01*
G01X668963D01*
G02X668841Y209185I1J200D01*
G01X668816Y209205D01*
X668780Y209260D01*
X668771Y209295D01*
G03X665271I-1750J-431D01*
G01Y209294D01*
G02X665199Y209183I-194J47D01*
G01X665175Y209164D01*
X665112Y209143D01*
X633403D01*
G02X633287Y209181I1J200D01*
G01X633262Y209198D01*
X633226Y209247D01*
X633215Y209278D01*
G03X632499Y210202I-1706J-582D01*
G01X632463Y210225D01*
X632441Y210259D01*
G02X632412Y210333I168J109D01*
G01X632362Y210625D01*
G02X632366Y210708I197J32D01*
G01X632375Y210745D01*
X632401Y210779D01*
G03X632712Y211693I-1191J915D01*
G01Y211695D01*
G03X631210Y213197I-1502J0D01*
G03X630223Y212827I0J-1501D01*
G01X630195Y212803D01*
X630162Y212791D01*
G02X630092Y212778I-71J187D01*
G01X629828D01*
G02X629758Y212791I1J200D01*
G01X629725Y212803D01*
X629697Y212827D01*
G03X628710Y213197I-987J-1131D01*
G03X627208Y211695I0J-1502D01*
G03X627787Y210510I1502J0D01*
G02X627862Y210382I-123J-158D01*
G02X627864Y210352I-198J-28D01*
G01Y210038D01*
G02X627862Y210008I-200J-2D01*
G02X627793Y209885I-198J30D01*
G02X627787Y209880I-131J151D01*
G03X627321Y209267I923J-1185D01*
G01X627304Y209226D01*
X627272Y209196D01*
G02X627246Y209176I-134J148D01*
G01X627222Y209160D01*
X627167Y209143D01*
X625910D01*
X625907D01*
G02X625766Y209204I3J200D01*
G03X625720Y209255I-1138J-980D01*
G03X625716Y209259I-143J-139D01*
G02X625664Y209350I141J141D01*
G02X625657Y209400I193J52D01*
G01Y209525D01*
G02X625660Y209561I200J1D01*
G02X625714Y209665I197J-36D01*
G03X626140Y210713I-1076J1048D01*
G03X625770Y211700I-1501J0D01*
G01X625746Y211728D01*
X625734Y211761D01*
G02X625721Y211831I187J71D01*
G01Y212095D01*
G02X625734Y212165I200J-1D01*
G01X625746Y212198D01*
X625770Y212226D01*
G03Y214200I-1131J987D01*
G01X625746Y214228D01*
X625734Y214261D01*
G02X625721Y214331I187J71D01*
G01Y214595D01*
G02X625734Y214665I200J-1D01*
G01X625746Y214698D01*
X625770Y214726D01*
G03X626140Y215713I-1131J987D01*
G03X623136I-1502J0D01*
G03X623506Y214726I1501J0D01*
G01X623530Y214698D01*
X623542Y214665D01*
G02X623555Y214595I-187J-71D01*
G01Y214331D01*
G02X623542Y214261I-200J1D01*
G01X623530Y214228D01*
X623506Y214200D01*
G03Y212226I1131J-987D01*
G01X623530Y212198D01*
X623542Y212165D01*
G02X623555Y212095I-187J-71D01*
G01Y211831D01*
G02X623542Y211761I-200J1D01*
G01X623530Y211728D01*
X623506Y211700D01*
G03X623136Y210713I1131J-987D01*
G03X623149Y210513I1502J-3D01*
G03X623562Y209665I1489J200D01*
G01X623564Y209663D01*
G02X623617Y209556I-145J-138D01*
G02X623619Y209525I-198J-28D01*
G01Y209401D01*
G02X623616Y209365I-200J-1D01*
G02X623612Y209350I-195J44D01*
G02X623560Y209259I-193J50D01*
G03X623556Y209255I139J-143D01*
G03X623510Y209204I1092J-1031D01*
G02X623369Y209143I-144J139D01*
G01X615838D01*
G02X615666Y209242I1J200D01*
G01X615491Y209540D01*
G02X615464Y209641I173J100D01*
G01Y209693D01*
X615471Y209706D01*
X615490Y209739D01*
G03X615684Y210477I-1308J738D01*
G01Y210478D01*
G03X615314Y211465I-1501J0D01*
G01X615290Y211493D01*
X615278Y211526D01*
G02X615265Y211596I187J71D01*
G01Y211860D01*
G02X615278Y211930I200J-1D01*
G01X615290Y211963D01*
X615314Y211991D01*
G03Y213965I-1131J987D01*
G01X615290Y213993D01*
X615278Y214026D01*
G02X615265Y214096I187J71D01*
G01Y214360D01*
G02X615278Y214430I200J-1D01*
G01X615290Y214463D01*
X615314Y214491D01*
G03X615684Y215478I-1131J987D01*
G03X612680I-1502J0D01*
G03X613050Y214491I1501J0D01*
G01X613074Y214463D01*
X613086Y214430D01*
G02X613099Y214360I-187J-71D01*
G01Y214096D01*
G02X613086Y214026I-200J1D01*
G01X613074Y213993D01*
X613050Y213965D01*
G03Y211991I1131J-987D01*
G01X613074Y211963D01*
X613086Y211930D01*
G02X613099Y211860I-187J-71D01*
G01Y211596D01*
G02X613086Y211526I-200J1D01*
G01X613074Y211493D01*
X613050Y211465D01*
G03X612680Y210478I1131J-987D01*
G01Y210477D01*
G03X612874Y209739I1502J0D01*
G01X612893Y209706D01*
X612900Y209693D01*
Y209641D01*
G02X612873Y209540I-200J-1D01*
G01X612698Y209242D01*
G02X612526Y209143I-173J101D01*
G01X589235D01*
G02X589066Y209237I1J200D01*
G01X588927Y209480D01*
X588889Y209546D01*
G02X588863Y209645I174J99D01*
G01Y209699D01*
X588891Y209746D01*
G03X589099Y210509I-1294J763D01*
G01Y210533D01*
G03X587597Y212011I-1502J-24D01*
G03X586610Y211641I0J-1501D01*
G01X586582Y211617D01*
X586549Y211605D01*
G02X586479Y211592I-71J187D01*
G01X586215D01*
G02X586145Y211605I1J200D01*
G01X586112Y211617D01*
X586084Y211641D01*
G03X585097Y212011I-987J-1131D01*
G03X583595Y210533I0J-1502D01*
G01Y210509D01*
G03X583803Y209746I1502J0D01*
G01X583817Y209723D01*
X583831Y209671D01*
Y209645D01*
G02X583805Y209546I-200J0D01*
G01X583767Y209480D01*
X583628Y209237D01*
G02X583459Y209143I-170J106D01*
G01X566601D01*
G02X566479Y209185I1J200D01*
G01X566454Y209205D01*
X566418Y209260D01*
X566409Y209295D01*
G03X562909I-1750J-431D01*
G01Y209294D01*
G02X562837Y209183I-194J47D01*
G01X562813Y209164D01*
X562750Y209143D01*
X531041D01*
G02X530925Y209181I1J200D01*
G01X530900Y209198D01*
X530864Y209247D01*
X530853Y209278D01*
G03X530137Y210202I-1706J-582D01*
G01X530101Y210225D01*
X530079Y210259D01*
G02X530050Y210333I168J109D01*
G01X530000Y210625D01*
G02X530004Y210708I197J32D01*
G01X530013Y210745D01*
X530039Y210779D01*
G03X530350Y211693I-1191J915D01*
G01Y211695D01*
G03X528848Y213197I-1502J0D01*
G03X527861Y212827I0J-1501D01*
G01X527833Y212803D01*
X527800Y212791D01*
G02X527730Y212778I-71J187D01*
G01X527466D01*
G02X527396Y212791I1J200D01*
G01X527363Y212803D01*
X527335Y212827D01*
G03X526348Y213197I-987J-1131D01*
G03X524846Y211695I0J-1502D01*
G03X525425Y210510I1502J0D01*
G02X525500Y210382I-123J-158D01*
G02X525502Y210352I-198J-28D01*
G01Y210038D01*
G02X525500Y210008I-200J-2D01*
G02X525431Y209885I-198J30D01*
G02X525425Y209880I-131J151D01*
G03X524959Y209267I923J-1185D01*
G01X524942Y209226D01*
X524910Y209196D01*
G02X524884Y209176I-134J148D01*
G01X524860Y209160D01*
X524805Y209143D01*
X523548D01*
X523545D01*
G02X523404Y209204I3J200D01*
G03X523358Y209255I-1138J-980D01*
G03X523354Y209259I-143J-139D01*
G02X523302Y209350I141J141D01*
G02X523295Y209400I193J52D01*
G01Y209525D01*
G02X523298Y209561I200J1D01*
G02X523352Y209665I197J-36D01*
G03X523778Y210713I-1076J1048D01*
G03X523408Y211700I-1501J0D01*
G01X523384Y211728D01*
X523372Y211761D01*
G02X523359Y211831I187J71D01*
G01Y212095D01*
G02X523372Y212165I200J-1D01*
G01X523384Y212198D01*
X523408Y212226D01*
G03Y214200I-1131J987D01*
G01X523384Y214228D01*
X523372Y214261D01*
G02X523359Y214331I187J71D01*
G01Y214595D01*
G02X523372Y214665I200J-1D01*
G01X523384Y214698D01*
X523408Y214726D01*
G03X523778Y215713I-1131J987D01*
G03X520774I-1502J0D01*
G03X521144Y214726I1501J0D01*
G01X521168Y214698D01*
X521180Y214665D01*
G02X521193Y214595I-187J-71D01*
G01Y214331D01*
G02X521180Y214261I-200J1D01*
G01X521168Y214228D01*
X521144Y214200D01*
G03Y212226I1131J-987D01*
G01X521168Y212198D01*
X521180Y212165D01*
G02X521193Y212095I-187J-71D01*
G01Y211831D01*
G02X521180Y211761I-200J1D01*
G01X521168Y211728D01*
X521144Y211700D01*
G03X520774Y210713I1131J-987D01*
G03X520787Y210513I1502J-3D01*
G03X521200Y209665I1489J200D01*
G01X521202Y209663D01*
G02X521255Y209556I-145J-138D01*
G02X521257Y209525I-198J-28D01*
G01Y209401D01*
G02X521254Y209365I-200J-1D01*
G02X521250Y209350I-195J44D01*
G02X521198Y209259I-193J50D01*
G03X521194Y209255I139J-143D01*
G03X521148Y209204I1092J-1031D01*
G02X521007Y209143I-144J139D01*
G01X513476D01*
G02X513304Y209242I1J200D01*
G01X513129Y209540D01*
G02X513102Y209641I173J100D01*
G01Y209693D01*
X513109Y209706D01*
X513128Y209739D01*
G03X513322Y210477I-1308J738D01*
G01Y210478D01*
G03X512952Y211465I-1501J0D01*
G01X512928Y211493D01*
X512916Y211526D01*
G02X512903Y211596I187J71D01*
G01Y211860D01*
G02X512916Y211930I200J-1D01*
G01X512928Y211963D01*
X512952Y211991D01*
G03Y213965I-1131J987D01*
G01X512928Y213993D01*
X512916Y214026D01*
G02X512903Y214096I187J71D01*
G01Y214360D01*
G02X512916Y214430I200J-1D01*
G01X512928Y214463D01*
X512952Y214491D01*
G03X513322Y215478I-1131J987D01*
G03X510318I-1502J0D01*
G03X510688Y214491I1501J0D01*
G01X510712Y214463D01*
X510724Y214430D01*
G02X510737Y214360I-187J-71D01*
G01Y214096D01*
G02X510724Y214026I-200J1D01*
G01X510712Y213993D01*
X510688Y213965D01*
G03Y211991I1131J-987D01*
G01X510712Y211963D01*
X510724Y211930D01*
G02X510737Y211860I-187J-71D01*
G01Y211596D01*
G02X510724Y211526I-200J1D01*
G01X510712Y211493D01*
X510688Y211465D01*
G03X510318Y210478I1131J-987D01*
G01Y210477D01*
G03X510512Y209739I1502J0D01*
G01X510531Y209706D01*
X510538Y209693D01*
Y209641D01*
G02X510511Y209540I-200J-1D01*
G01X510336Y209242D01*
G02X510164Y209143I-173J101D01*
G01X486873D01*
G02X486704Y209237I1J200D01*
G01X486565Y209480D01*
X486527Y209546D01*
G02X486501Y209645I174J99D01*
G01Y209699D01*
X486529Y209746D01*
G03X486737Y210509I-1294J763D01*
G01Y210533D01*
G03X485235Y212011I-1502J-24D01*
G03X484248Y211641I0J-1501D01*
G01X484220Y211617D01*
X484187Y211605D01*
G02X484117Y211592I-71J187D01*
G01X483853D01*
G02X483783Y211605I1J200D01*
G01X483750Y211617D01*
X483722Y211641D01*
G03X482735Y212011I-987J-1131D01*
G03X481233Y210533I0J-1502D01*
G01Y210509D01*
G03X481441Y209746I1502J0D01*
G01X481455Y209723D01*
X481469Y209671D01*
Y209645D01*
G02X481443Y209546I-200J0D01*
G01X481405Y209480D01*
X481266Y209237D01*
G02X481097Y209143I-170J106D01*
G01X416600D01*
G02X416478Y209185I1J200D01*
G01X416453Y209205D01*
X416417Y209260D01*
X416408Y209295D01*
G03X412908I-1750J-431D01*
G01Y209294D01*
G02X412836Y209183I-194J47D01*
G01X412812Y209164D01*
X412749Y209143D01*
X381040D01*
G02X380924Y209181I1J200D01*
G01X380899Y209198D01*
X380863Y209247D01*
X380852Y209278D01*
G03X380136Y210202I-1706J-582D01*
G01X380100Y210225D01*
X380078Y210259D01*
G02X380049Y210333I168J109D01*
G01X379999Y210625D01*
G02X380003Y210708I197J32D01*
G01X380012Y210745D01*
X380038Y210779D01*
G03X380349Y211693I-1191J915D01*
G01Y211695D01*
G03X378847Y213197I-1502J0D01*
G03X377860Y212827I0J-1501D01*
G01X377832Y212803D01*
X377799Y212791D01*
G02X377729Y212778I-71J187D01*
G01X377465D01*
G02X377395Y212791I1J200D01*
G01X377362Y212803D01*
X377334Y212827D01*
G03X376347Y213197I-987J-1131D01*
G03X374845Y211695I0J-1502D01*
G03X375424Y210510I1502J0D01*
G02X375499Y210382I-123J-158D01*
G02X375501Y210352I-198J-28D01*
G01Y210038D01*
G02X375499Y210008I-200J-2D01*
G02X375430Y209885I-198J30D01*
G02X375424Y209880I-131J151D01*
G03X374958Y209267I923J-1185D01*
G01X374941Y209226D01*
X374909Y209196D01*
G02X374883Y209176I-134J148D01*
G01X374859Y209160D01*
X374804Y209143D01*
X373547D01*
X373544D01*
G02X373403Y209204I3J200D01*
G03X373357Y209255I-1138J-980D01*
G03X373353Y209259I-143J-139D01*
G02X373301Y209350I141J141D01*
G02X373294Y209400I193J52D01*
G01Y209525D01*
G02X373297Y209561I200J1D01*
G02X373351Y209665I197J-36D01*
G03X373777Y210713I-1076J1048D01*
G03X373407Y211700I-1501J0D01*
G01X373383Y211728D01*
X373371Y211761D01*
G02X373358Y211831I187J71D01*
G01Y212095D01*
G02X373371Y212165I200J-1D01*
G01X373383Y212198D01*
X373407Y212226D01*
G03Y214200I-1131J987D01*
G01X373383Y214228D01*
X373371Y214261D01*
G02X373358Y214331I187J71D01*
G01Y214595D01*
G02X373371Y214665I200J-1D01*
G01X373383Y214698D01*
X373407Y214726D01*
G03X373777Y215713I-1131J987D01*
G03X370773I-1502J0D01*
G03X371143Y214726I1501J0D01*
G01X371167Y214698D01*
X371179Y214665D01*
G02X371192Y214595I-187J-71D01*
G01Y214331D01*
G02X371179Y214261I-200J1D01*
G01X371167Y214228D01*
X371143Y214200D01*
G03Y212226I1131J-987D01*
G01X371167Y212198D01*
X371179Y212165D01*
G02X371192Y212095I-187J-71D01*
G01Y211831D01*
G02X371179Y211761I-200J1D01*
G01X371167Y211728D01*
X371143Y211700D01*
G03X370773Y210713I1131J-987D01*
G03X370786Y210513I1502J-3D01*
G03X371199Y209665I1489J200D01*
G01X371201Y209663D01*
G02X371254Y209556I-145J-138D01*
G02X371256Y209525I-198J-28D01*
G01Y209401D01*
G02X371253Y209365I-200J-1D01*
G02X371249Y209350I-195J44D01*
G02X371197Y209259I-193J50D01*
G03X371193Y209255I139J-143D01*
G03X371147Y209204I1092J-1031D01*
G02X371006Y209143I-144J139D01*
G01X363475D01*
G02X363303Y209242I1J200D01*
G01X363128Y209540D01*
G02X363101Y209641I173J100D01*
G01Y209693D01*
X363108Y209706D01*
X363127Y209739D01*
G03X363321Y210477I-1308J738D01*
G01Y210478D01*
G03X362951Y211465I-1501J0D01*
G01X362927Y211493D01*
X362915Y211526D01*
G02X362902Y211596I187J71D01*
G01Y211860D01*
G02X362915Y211930I200J-1D01*
G01X362927Y211963D01*
X362951Y211991D01*
G03Y213965I-1131J987D01*
G01X362927Y213993D01*
X362915Y214026D01*
G02X362902Y214096I187J71D01*
G01Y214360D01*
G02X362915Y214430I200J-1D01*
G01X362927Y214463D01*
X362951Y214491D01*
G03X363321Y215478I-1131J987D01*
G03X360317I-1502J0D01*
G03X360687Y214491I1501J0D01*
G01X360711Y214463D01*
X360723Y214430D01*
G02X360736Y214360I-187J-71D01*
G01Y214096D01*
G02X360723Y214026I-200J1D01*
G01X360711Y213993D01*
X360687Y213965D01*
G03Y211991I1131J-987D01*
G01X360711Y211963D01*
X360723Y211930D01*
G02X360736Y211860I-187J-71D01*
G01Y211596D01*
G02X360723Y211526I-200J1D01*
G01X360711Y211493D01*
X360687Y211465D01*
G03X360317Y210478I1131J-987D01*
G01Y210477D01*
G03X360511Y209739I1502J0D01*
G01X360530Y209706D01*
X360537Y209693D01*
Y209641D01*
G02X360510Y209540I-200J-1D01*
G01X360335Y209242D01*
G02X360163Y209143I-173J101D01*
G01X336872D01*
G02X336703Y209237I1J200D01*
G01X336564Y209480D01*
X336526Y209546D01*
G02X336500Y209645I174J99D01*
G01Y209699D01*
X336528Y209746D01*
G03X336736Y210509I-1294J763D01*
G01Y210533D01*
G03X335234Y212011I-1502J-24D01*
G03X334247Y211641I0J-1501D01*
G01X334219Y211617D01*
X334186Y211605D01*
G02X334116Y211592I-71J187D01*
G01X333852D01*
G02X333782Y211605I1J200D01*
G01X333749Y211617D01*
X333721Y211641D01*
G03X332734Y212011I-987J-1131D01*
G03X331232Y210533I0J-1502D01*
G01Y210509D01*
G03X331440Y209746I1502J0D01*
G01X331454Y209723D01*
X331468Y209671D01*
Y209645D01*
G02X331442Y209546I-200J0D01*
G01X331404Y209480D01*
X331265Y209237D01*
G02X331096Y209143I-170J106D01*
G01X314238D01*
G02X314116Y209185I1J200D01*
G01X314091Y209205D01*
X314055Y209260D01*
X314046Y209295D01*
G03X310546I-1750J-431D01*
G01Y209294D01*
G02X310474Y209183I-194J47D01*
G01X310450Y209164D01*
X310387Y209143D01*
X278678D01*
G02X278562Y209181I1J200D01*
G01X278537Y209198D01*
X278501Y209247D01*
X278490Y209278D01*
G03X277774Y210202I-1706J-582D01*
G01X277738Y210225D01*
X277716Y210259D01*
G02X277687Y210333I168J109D01*
G01X277637Y210625D01*
G02X277641Y210708I197J32D01*
G01X277650Y210745D01*
X277676Y210779D01*
G03X277987Y211693I-1191J915D01*
G01Y211695D01*
G03X276485Y213197I-1502J0D01*
G03X275498Y212827I0J-1501D01*
G01X275470Y212803D01*
X275437Y212791D01*
G02X275367Y212778I-71J187D01*
G01X275103D01*
G02X275033Y212791I1J200D01*
G01X275000Y212803D01*
X274972Y212827D01*
G03X273985Y213197I-987J-1131D01*
G03X272483Y211695I0J-1502D01*
G03X273062Y210510I1502J0D01*
G02X273137Y210382I-123J-158D01*
G02X273139Y210352I-198J-28D01*
G01Y210038D01*
G02X273137Y210008I-200J-2D01*
G02X273068Y209885I-198J30D01*
G02X273062Y209880I-131J151D01*
G03X272596Y209267I923J-1185D01*
G01X272579Y209226D01*
X272547Y209196D01*
G02X272521Y209176I-134J148D01*
G01X272497Y209160D01*
X272442Y209143D01*
X271185D01*
X271182D01*
G02X271041Y209204I3J200D01*
G03X270995Y209255I-1138J-980D01*
G03X270991Y209259I-143J-139D01*
G02X270939Y209350I141J141D01*
G02X270932Y209400I193J52D01*
G01Y209525D01*
G02X270935Y209561I200J1D01*
G02X270989Y209665I197J-36D01*
G03X271415Y210713I-1076J1048D01*
G03X271045Y211700I-1501J0D01*
G01X271021Y211728D01*
X271009Y211761D01*
G02X270996Y211831I187J71D01*
G01Y212095D01*
G02X271009Y212165I200J-1D01*
G01X271021Y212198D01*
X271045Y212226D01*
G03Y214200I-1131J987D01*
G01X271021Y214228D01*
X271009Y214261D01*
G02X270996Y214331I187J71D01*
G01Y214595D01*
G02X271009Y214665I200J-1D01*
G01X271021Y214698D01*
X271045Y214726D01*
G03X271415Y215713I-1131J987D01*
G03X268411I-1502J0D01*
G03X268781Y214726I1501J0D01*
G01X268805Y214698D01*
X268817Y214665D01*
G02X268830Y214595I-187J-71D01*
G01Y214331D01*
G02X268817Y214261I-200J1D01*
G01X268805Y214228D01*
X268781Y214200D01*
G03Y212226I1131J-987D01*
G01X268805Y212198D01*
X268817Y212165D01*
G02X268830Y212095I-187J-71D01*
G01Y211831D01*
G02X268817Y211761I-200J1D01*
G01X268805Y211728D01*
X268781Y211700D01*
G03X268411Y210713I1131J-987D01*
G03X268424Y210513I1502J-3D01*
G03X268837Y209665I1489J200D01*
G01X268839Y209663D01*
G02X268892Y209556I-145J-138D01*
G02X268894Y209525I-198J-28D01*
G01Y209401D01*
G02X268891Y209365I-200J-1D01*
G02X268887Y209350I-195J44D01*
G02X268835Y209259I-193J50D01*
G03X268831Y209255I139J-143D01*
G03X268785Y209204I1092J-1031D01*
G02X268644Y209143I-144J139D01*
G01X261113D01*
G02X260941Y209242I1J200D01*
G01X260766Y209540D01*
G02X260739Y209641I173J100D01*
G01Y209693D01*
X260746Y209706D01*
X260765Y209739D01*
G03X260959Y210477I-1308J738D01*
G01Y210478D01*
G03X260589Y211465I-1501J0D01*
G01X260565Y211493D01*
X260553Y211526D01*
G02X260540Y211596I187J71D01*
G01Y211860D01*
G02X260553Y211930I200J-1D01*
G01X260565Y211963D01*
X260589Y211991D01*
G03Y213965I-1131J987D01*
G01X260565Y213993D01*
X260553Y214026D01*
G02X260540Y214096I187J71D01*
G01Y214360D01*
G02X260553Y214430I200J-1D01*
G01X260565Y214463D01*
X260589Y214491D01*
G03X260959Y215478I-1131J987D01*
G03X257955I-1502J0D01*
G03X258325Y214491I1501J0D01*
G01X258349Y214463D01*
X258361Y214430D01*
G02X258374Y214360I-187J-71D01*
G01Y214096D01*
G02X258361Y214026I-200J1D01*
G01X258349Y213993D01*
X258325Y213965D01*
G03Y211991I1131J-987D01*
G01X258349Y211963D01*
X258361Y211930D01*
G02X258374Y211860I-187J-71D01*
G01Y211596D01*
G02X258361Y211526I-200J1D01*
G01X258349Y211493D01*
X258325Y211465D01*
G03X257955Y210478I1131J-987D01*
G01Y210477D01*
G03X258149Y209739I1502J0D01*
G01X258168Y209706D01*
X258175Y209693D01*
Y209641D01*
G02X258148Y209540I-200J-1D01*
G01X257973Y209242D01*
G02X257801Y209143I-173J101D01*
G01X234510D01*
G02X234341Y209237I1J200D01*
G01X234202Y209480D01*
X234164Y209546D01*
G02X234138Y209645I174J99D01*
G01Y209699D01*
X234166Y209746D01*
G03X234374Y210509I-1294J763D01*
G01Y210533D01*
G03X232872Y212011I-1502J-24D01*
G03X231885Y211641I0J-1501D01*
G01X231857Y211617D01*
X231824Y211605D01*
G02X231754Y211592I-71J187D01*
G01X231490D01*
G02X231420Y211605I1J200D01*
G01X231387Y211617D01*
X231359Y211641D01*
G03X230372Y212011I-987J-1131D01*
G03X228870Y210533I0J-1502D01*
G01Y210509D01*
G03X229078Y209746I1502J0D01*
G01X229092Y209723D01*
X229106Y209671D01*
Y209645D01*
G02X229080Y209546I-200J0D01*
G01X229042Y209480D01*
X228903Y209237D01*
G02X228734Y209143I-170J106D01*
G01X211876D01*
G02X211754Y209185I1J200D01*
G01X211729Y209205D01*
X211693Y209260D01*
X211684Y209295D01*
G03X208184I-1750J-431D01*
G01Y209294D01*
G02X208112Y209183I-194J47D01*
G01X208088Y209164D01*
X208025Y209143D01*
X176316D01*
G02X176200Y209181I1J200D01*
G01X176175Y209198D01*
X176139Y209247D01*
X176128Y209278D01*
G03X175412Y210202I-1706J-582D01*
G01X175376Y210225D01*
X175354Y210259D01*
G02X175325Y210333I168J109D01*
G01X175275Y210625D01*
G02X175279Y210708I197J32D01*
G01X175288Y210745D01*
X175314Y210779D01*
G03X175625Y211693I-1191J915D01*
G01Y211695D01*
G03X174123Y213197I-1502J0D01*
G03X173136Y212827I0J-1501D01*
G01X173108Y212803D01*
X173075Y212791D01*
G02X173005Y212778I-71J187D01*
G01X172741D01*
G02X172671Y212791I1J200D01*
G01X172638Y212803D01*
X172610Y212827D01*
G03X171623Y213197I-987J-1131D01*
G03X170121Y211695I0J-1502D01*
G03X170700Y210510I1502J0D01*
G02X170775Y210382I-123J-158D01*
G02X170777Y210352I-198J-28D01*
G01Y210038D01*
G02X170775Y210008I-200J-2D01*
G02X170706Y209885I-198J30D01*
G02X170700Y209880I-131J151D01*
G03X170234Y209267I923J-1185D01*
G01X170217Y209226D01*
X170185Y209196D01*
G02X170159Y209176I-134J148D01*
G01X170135Y209160D01*
X170080Y209143D01*
X168823D01*
X168820D01*
G02X168679Y209204I3J200D01*
G03X168633Y209255I-1138J-980D01*
G03X168629Y209259I-143J-139D01*
G02X168577Y209350I141J141D01*
G02X168570Y209400I193J52D01*
G01Y209525D01*
G02X168573Y209561I200J1D01*
G02X168627Y209665I197J-36D01*
G03X169053Y210713I-1076J1048D01*
G03X168683Y211700I-1501J0D01*
G01X168659Y211728D01*
X168647Y211761D01*
G02X168634Y211831I187J71D01*
G01Y212095D01*
G02X168647Y212165I200J-1D01*
G01X168659Y212198D01*
X168683Y212226D01*
G03Y214200I-1131J987D01*
G01X168659Y214228D01*
X168647Y214261D01*
G02X168634Y214331I187J71D01*
G01Y214595D01*
G02X168647Y214665I200J-1D01*
G01X168659Y214698D01*
X168683Y214726D01*
G03X169053Y215713I-1131J987D01*
G03X166049I-1502J0D01*
G03X166419Y214726I1501J0D01*
G01X166443Y214698D01*
X166455Y214665D01*
G02X166468Y214595I-187J-71D01*
G01Y214331D01*
G02X166455Y214261I-200J1D01*
G01X166443Y214228D01*
X166419Y214200D01*
G03Y212226I1131J-987D01*
G01X166443Y212198D01*
X166455Y212165D01*
G02X166468Y212095I-187J-71D01*
G01Y211831D01*
G02X166455Y211761I-200J1D01*
G01X166443Y211728D01*
X166419Y211700D01*
G03X166049Y210713I1131J-987D01*
G03X166062Y210513I1502J-3D01*
G03X166475Y209665I1489J200D01*
G01X166477Y209663D01*
G02X166530Y209556I-145J-138D01*
G02X166532Y209525I-198J-28D01*
G01Y209401D01*
G02X166529Y209365I-200J-1D01*
G02X166525Y209350I-195J44D01*
G02X166473Y209259I-193J50D01*
G03X166469Y209255I139J-143D01*
G03X166423Y209204I1092J-1031D01*
G02X166282Y209143I-144J139D01*
G01X158751D01*
G02X158579Y209242I1J200D01*
G01X158404Y209540D01*
G02X158377Y209641I173J100D01*
G01Y209693D01*
X158384Y209706D01*
X158403Y209739D01*
G03X158597Y210477I-1308J738D01*
G01Y210478D01*
G03X158227Y211465I-1501J0D01*
G01X158203Y211493D01*
X158191Y211526D01*
G02X158178Y211596I187J71D01*
G01Y211860D01*
G02X158191Y211930I200J-1D01*
G01X158203Y211963D01*
X158227Y211991D01*
G03Y213965I-1131J987D01*
G01X158203Y213993D01*
X158191Y214026D01*
G02X158178Y214096I187J71D01*
G01Y214360D01*
G02X158191Y214430I200J-1D01*
G01X158203Y214463D01*
X158227Y214491D01*
G03X158597Y215478I-1131J987D01*
G03X155593I-1502J0D01*
G03X155963Y214491I1501J0D01*
G01X155987Y214463D01*
X155999Y214430D01*
G02X156012Y214360I-187J-71D01*
G01Y214096D01*
G02X155999Y214026I-200J1D01*
G01X155987Y213993D01*
X155963Y213965D01*
G03Y211991I1131J-987D01*
G01X155987Y211963D01*
X155999Y211930D01*
G02X156012Y211860I-187J-71D01*
G01Y211596D01*
G02X155999Y211526I-200J1D01*
G01X155987Y211493D01*
X155963Y211465D01*
G03X155593Y210478I1131J-987D01*
G01Y210477D01*
G03X155787Y209739I1502J0D01*
G01X155806Y209706D01*
X155813Y209693D01*
Y209641D01*
G02X155786Y209540I-200J-1D01*
G01X155611Y209242D01*
G02X155439Y209143I-173J101D01*
G01X132148D01*
G02X131979Y209237I1J200D01*
G01X131840Y209480D01*
X131802Y209546D01*
G02X131776Y209645I174J99D01*
G01Y209699D01*
X131804Y209746D01*
G03X132012Y210509I-1294J763D01*
G01Y210533D01*
G03X130510Y212011I-1502J-24D01*
G03X129523Y211641I0J-1501D01*
G01X129495Y211617D01*
X129462Y211605D01*
G02X129392Y211592I-71J187D01*
G01X129128D01*
G02X129058Y211605I1J200D01*
G01X129025Y211617D01*
X128997Y211641D01*
G03X128010Y212011I-987J-1131D01*
G03X126508Y210533I0J-1502D01*
G01Y210509D01*
G03X126716Y209746I1502J0D01*
G01X126730Y209723D01*
X126744Y209671D01*
Y209645D01*
G02X126718Y209546I-200J0D01*
G01X126680Y209480D01*
X126541Y209237D01*
G02X126372Y209143I-170J106D01*
G01X109514D01*
G02X109392Y209185I1J200D01*
G01X109367Y209205D01*
X109331Y209260D01*
X109322Y209295D01*
G03X105822I-1750J-431D01*
G01Y209294D01*
G02X105750Y209183I-194J47D01*
G01X105726Y209164D01*
X105663Y209143D01*
X73954D01*
G02X73838Y209181I1J200D01*
G01X73813Y209198D01*
X73777Y209247D01*
X73766Y209278D01*
G03X73050Y210202I-1706J-582D01*
G01X73014Y210225D01*
X72992Y210259D01*
G02X72963Y210333I168J109D01*
G01X72913Y210625D01*
G02X72917Y210708I197J32D01*
G01X72926Y210745D01*
X72952Y210779D01*
G03X73263Y211693I-1191J915D01*
G01Y211695D01*
G03X71761Y213197I-1502J0D01*
G03X70774Y212827I0J-1501D01*
G01X70746Y212803D01*
X70713Y212791D01*
G02X70643Y212778I-71J187D01*
G01X70379D01*
G02X70309Y212791I1J200D01*
G01X70276Y212803D01*
X70248Y212827D01*
G03X69261Y213197I-987J-1131D01*
G03X67759Y211695I0J-1502D01*
G03X68338Y210510I1502J0D01*
G02X68413Y210382I-123J-158D01*
G02X68415Y210352I-198J-28D01*
G01Y210038D01*
G02X68413Y210008I-200J-2D01*
G02X68344Y209885I-198J30D01*
G02X68338Y209880I-131J151D01*
G03X67872Y209267I923J-1185D01*
G01X67855Y209226D01*
X67823Y209196D01*
G02X67797Y209176I-134J148D01*
G01X67773Y209160D01*
X67718Y209143D01*
X66461D01*
X66458D01*
G02X66317Y209204I3J200D01*
G03X66271Y209255I-1138J-980D01*
G03X66267Y209259I-143J-139D01*
G02X66215Y209350I141J141D01*
G02X66208Y209400I193J52D01*
G01Y209525D01*
G02X66211Y209561I200J1D01*
G02X66265Y209665I197J-36D01*
G03X66691Y210713I-1076J1048D01*
G03X66321Y211700I-1501J0D01*
G01X66297Y211728D01*
X66285Y211761D01*
G02X66272Y211831I187J71D01*
G01Y212095D01*
G02X66285Y212165I200J-1D01*
G01X66297Y212198D01*
X66321Y212226D01*
G03Y214200I-1131J987D01*
G01X66297Y214228D01*
X66285Y214261D01*
G02X66272Y214331I187J71D01*
G01Y214595D01*
G02X66285Y214665I200J-1D01*
G01X66297Y214698D01*
X66321Y214726D01*
G03X66691Y215713I-1131J987D01*
G03X63687I-1502J0D01*
G03X64057Y214726I1501J0D01*
G01X64081Y214698D01*
X64093Y214665D01*
G02X64106Y214595I-187J-71D01*
G01Y214331D01*
G02X64093Y214261I-200J1D01*
G01X64081Y214228D01*
X64057Y214200D01*
G03Y212226I1131J-987D01*
G01X64081Y212198D01*
X64093Y212165D01*
G02X64106Y212095I-187J-71D01*
G01Y211831D01*
G02X64093Y211761I-200J1D01*
G01X64081Y211728D01*
X64057Y211700D01*
G03X63687Y210713I1131J-987D01*
G03X63700Y210513I1502J-3D01*
G03X64113Y209665I1489J200D01*
G01X64115Y209663D01*
G02X64168Y209556I-145J-138D01*
G02X64170Y209525I-198J-28D01*
G01Y209401D01*
G02X64167Y209365I-200J-1D01*
G02X64163Y209350I-195J44D01*
G02X64111Y209259I-193J50D01*
G03X64107Y209255I139J-143D01*
G03X64061Y209204I1092J-1031D01*
G02X63920Y209143I-144J139D01*
G01X56389D01*
G02X56217Y209242I1J200D01*
G01X56042Y209540D01*
G02X56015Y209641I173J100D01*
G01Y209693D01*
X56022Y209706D01*
X56041Y209739D01*
G03X56235Y210477I-1308J738D01*
G01Y210478D01*
G03X55865Y211465I-1501J0D01*
G01X55841Y211493D01*
X55829Y211526D01*
G02X55816Y211596I187J71D01*
G01Y211860D01*
G02X55829Y211930I200J-1D01*
G01X55841Y211963D01*
X55865Y211991D01*
G03Y213965I-1131J987D01*
G01X55841Y213993D01*
X55829Y214026D01*
G02X55816Y214096I187J71D01*
G01Y214360D01*
G02X55829Y214430I200J-1D01*
G01X55841Y214463D01*
X55865Y214491D01*
G03X56235Y215478I-1131J987D01*
G03X53231I-1502J0D01*
G03X53601Y214491I1501J0D01*
G01X53625Y214463D01*
X53637Y214430D01*
G02X53650Y214360I-187J-71D01*
G01Y214096D01*
G02X53637Y214026I-200J1D01*
G01X53625Y213993D01*
X53601Y213965D01*
G03Y211991I1131J-987D01*
G01X53625Y211963D01*
X53637Y211930D01*
G02X53650Y211860I-187J-71D01*
G01Y211596D01*
G02X53637Y211526I-200J1D01*
G01X53625Y211493D01*
X53601Y211465D01*
G03X53231Y210478I1131J-987D01*
G01Y210477D01*
G03X53425Y209739I1502J0D01*
G01X53444Y209706D01*
X53451Y209693D01*
Y209641D01*
G02X53424Y209540I-200J-1D01*
G01X53249Y209242D01*
G02X53077Y209143I-173J101D01*
G01X29786D01*
G02X29617Y209237I1J200D01*
G01X29478Y209480D01*
X29440Y209546D01*
G02X29414Y209645I174J99D01*
G01Y209699D01*
X29442Y209746D01*
G03X29650Y210509I-1294J763D01*
G01Y210533D01*
G03X28148Y212011I-1502J-24D01*
G03X27161Y211641I0J-1501D01*
G01X27133Y211617D01*
X27100Y211605D01*
G02X27030Y211592I-71J187D01*
G01X26766D01*
G02X26696Y211605I1J200D01*
G01X26663Y211617D01*
X26635Y211641D01*
G03X25648Y212011I-987J-1131D01*
G03X24146Y210533I0J-1502D01*
G01Y210509D01*
G03X24354Y209746I1502J0D01*
G01X24368Y209723D01*
X24382Y209671D01*
Y209645D01*
G02X24356Y209546I-200J0D01*
G01X24318Y209480D01*
X24179Y209237D01*
G02X24010Y209143I-170J106D01*
G01X11522D01*
G02X11322Y209343I0J200D01*
G01Y216532D01*
Y216541D01*
G02X11391Y216683I200J-9D01*
G03X11585Y216864I-1129J1405D01*
G01X11612Y216893D01*
X11644Y216909D01*
G02X11715Y216928I86J-181D01*
G01X11900Y216943D01*
X11987Y216950D01*
G02X12063Y216941I15J-199D01*
G01X12096Y216931D01*
X12127Y216907D01*
G03X13059Y216583I932J1178D01*
G03Y219587I0J1502D01*
G01X13057D01*
G03X12126Y219263I1J-1502D01*
G01X12095Y219238D01*
X12026Y219217D01*
X11975Y219221D01*
X11715Y219242D01*
G02X11644Y219261I15J200D01*
G01X11612Y219277D01*
X11585Y219306D01*
G03X11391Y219487I-1323J-1224D01*
G02X11322Y219629I131J151D01*
G01Y252670D01*
G02X11522Y252870I200J0D01*
G01X12965D01*
G03X14380Y253456I0J2001D01*
G01X18347Y257423D01*
G02X18366Y257440I143J-140D01*
G02X18488Y257482I123J-158D01*
G01X23456D01*
G02X23513Y257474I1J-200D01*
G02X23617Y257401I-57J-192D01*
G01X23641Y257368D01*
X23809Y257136D01*
G02X23844Y257050I-163J-116D01*
G01X23852Y257002D01*
X23837Y256957D01*
G03X23747Y256404I1712J-562D01*
G01Y256379D01*
G03X25549Y254592I1802J15D01*
G03X27351Y256376I0J1802D01*
G01Y256396D01*
G03X27216Y257079I-1802J-1D01*
G02X27205Y257115I185J76D01*
G01X27193Y257173D01*
G02X27223Y257279I200J1D01*
G01X27271Y257354D01*
Y257356D01*
X27315Y257426D01*
X27402Y257475D01*
X27422Y257476D01*
G03X27538Y257481I-28J2002D01*
G01X27545Y257482D01*
X31177D01*
G03X32592Y258068I0J2001D01*
G01X32854Y258329D01*
X33569Y259044D01*
G02X33709Y259102I141J-142D01*
G01X55985D01*
G02X56185Y258902I0J-200D01*
G01Y258880D01*
G03X59789I1802J0D01*
G01Y258902D01*
G02X59989Y259102I200J0D01*
G01X158347D01*
G02X158547Y258902I0J-200D01*
G01Y258880D01*
G03X162151I1802J0D01*
G01Y258902D01*
G02X162351Y259102I200J0D01*
G01X261009D01*
G02X261209Y258902I0J-200D01*
G01Y258880D01*
G03X264213I1502J0D01*
G01Y258902D01*
G02X264413Y259102I200J0D01*
G01X363371D01*
G02X363571Y258902I0J-200D01*
G01Y258880D01*
G03X366575I1502J0D01*
G01Y258902D01*
G02X366775Y259102I200J0D01*
G01X513072D01*
G02X513272Y258902I0J-200D01*
G01Y258880D01*
G03X516876I1802J0D01*
G01Y258902D01*
G02X517076Y259102I200J0D01*
G01X615734D01*
G02X615934Y258902I0J-200D01*
G01Y258880D01*
G03X618938I1502J0D01*
G01Y258902D01*
G02X619138Y259102I200J0D01*
G01X718096D01*
G02X718296Y258902I0J-200D01*
G01Y258880D01*
G03X721300I1502J0D01*
G01Y258902D01*
G02X721500Y259102I200J0D01*
G01X820158D01*
G02X820358Y258902I0J-200D01*
G01Y258880D01*
G03X823962I1802J0D01*
G01Y258902D01*
G02X824162Y259102I200J0D01*
G01X892088D01*
X892108Y259098D01*
G03X892484Y259058I378J1762D01*
G03X892618Y259063I0J1802D01*
G02X892648I15J-200D01*
G03X892780Y259058I134J1797D01*
G03X893156Y259098I-2J1802D01*
G01X893176Y259102D01*
X895468D01*
G02X895500Y259100I4J-200D01*
G02X895645Y258996I-32J-198D01*
G01X895691Y258911D01*
G02X895664Y258684I-177J-94D01*
G01X895663Y258683D01*
G03X895202Y257480I1341J-1204D01*
G03X897004Y255678I1802J0D01*
G01X897006D01*
G03X897137Y255683I-3J1802D01*
G02X897167I15J-200D01*
G03X897298Y255678I134J1797D01*
G01X897300D01*
G03X898490Y256126I1J1802D01*
G02X898492Y256128I142J-140D01*
G01X898520Y256152D01*
X898635Y256168D01*
X899019Y255992D01*
G02X899136Y255811I-83J-182D01*
G01Y254842D01*
G02X899075Y254698I-200J0D01*
G01X898928Y254557D01*
G03X898872Y254558I-55J-1501D01*
G03X898741Y254553I-8J-1502D01*
G02X898707I-17J199D01*
G03X898576Y254558I-123J-1497D01*
G03Y251554I0J-1502D01*
G03X898707Y251559I8J1502D01*
G02X898741I17J-199D01*
G03X898872Y251554I123J1497D01*
G03X898928Y251555I1J1502D01*
G01X899075Y251414D01*
G02X899136Y251270I-139J-144D01*
G01Y247567D01*
G02X899082Y247430I-200J0D01*
G01X898893Y247230D01*
G02X898760Y247168I-145J138D01*
G03Y244170I91J-1499D01*
G01X898799Y244168D01*
X898866Y244136D01*
X899082Y243908D01*
G02X899136Y243771I-146J-137D01*
G01Y240481D01*
G02X899082Y240344I-200J0D01*
G01X898893Y240144D01*
G02X898760Y240082I-145J138D01*
G03X897365Y238802I91J-1499D01*
G01X897357Y238746D01*
X897286Y238661D01*
X897225Y238640D01*
G02X897125Y238632I-65J189D01*
G01X897074Y238641D01*
X897033Y238675D01*
G03X896076Y239019I-957J-1159D01*
G01X896074D01*
G03X895693Y238970I-1J-1502D01*
G02X895659Y238964I-52J193D01*
G03X895227Y238860I120J-1447D01*
G02X895025Y238889I-77J185D01*
G03X893284Y239506I-1742J-2150D01*
G03X890518Y236739I0J-2766D01*
G03X891017Y235154I2766J0D01*
G02Y234924I-164J-115D01*
G03X890518Y233341I2267J-1585D01*
G01Y233339D01*
G03X892567Y230667I2767J0D01*
G02X892698Y230554I-52J-193D01*
G01X892842Y230225D01*
X892839Y230135D01*
X892817Y230094D01*
G03X892482Y228741I2567J-1354D01*
G01Y228740D01*
G03X898286I2902J0D01*
G03X898182Y229509I-2902J-1D01*
G02X898225Y229695I193J53D01*
G01X898482Y229984D01*
X898576Y230019D01*
X898627Y230011D01*
G03X898851Y229994I225J1485D01*
G03X898982Y229999I8J1502D01*
G02X899016I17J-199D01*
G03X899147Y229994I123J1497D01*
G03X900649Y231496I0J1502D01*
G01Y231497D01*
Y231504D01*
G02X900694Y231632I200J2D01*
G01X900770Y231723D01*
G02X900890Y231794I155J-126D01*
G03X902375Y232564I-471J2726D01*
G01X904938Y235127D01*
G03X905748Y237083I-1957J1956D01*
G01Y258902D01*
G02X905948Y259102I200J0D01*
G01X909816D01*
X909821D01*
G02X909984Y259010I-5J-200D01*
G02X909997Y258986I-169J-107D01*
G01X910056Y258861D01*
G02X910004Y258624I-181J-84D01*
G03X909475Y257480I972J-1144D01*
G03X910977Y255978I1502J0D01*
G03X911108Y255983I8J1502D01*
G02X911142I17J-199D01*
G03X911273Y255978I123J1497D01*
G03X912775Y257480I0J1502D01*
G03X912424Y258445I-1502J0D01*
G02X912378Y258548I152J130D01*
G01X912375Y258576D01*
X912383Y258631D01*
X912549Y258986D01*
G02X912562Y259010I182J-83D01*
G02X912725Y259102I168J-108D01*
G01X918105D01*
G02X918199Y259078I-1J-200D01*
G01X918320Y259014D01*
X918331Y258998D01*
G03X918345Y258979I1216J881D01*
G01X918347Y258975D01*
G03X919575Y258341I1226J868D01*
G03X920805Y258978I2J1502D01*
G01X920818Y258997D01*
X920853Y259028D01*
X920947Y259078D01*
G02X921041Y259102I95J-176D01*
G01X970458D01*
G02X970658Y258902I0J-200D01*
G01Y258880D01*
G03X973662I1502J0D01*
G01Y258902D01*
G02X973862Y259102I200J0D01*
G01X978884D01*
G02X979019Y259050I0J-200D01*
G03X980875Y258334I1857J2050D01*
G01X989650D01*
G02X989837Y258206I0J-200D01*
G01X989972Y257858D01*
G02X989922Y257640I-187J-72D01*
G01X989921Y257639D01*
G03X989437Y256535I1017J-1104D01*
G03X992441I1502J0D01*
G03X991957Y257639I-1501J0D01*
G01X991956Y257640D01*
G02X991906Y257858I137J146D01*
G01X992041Y258206D01*
G02X992228Y258334I187J-72D01*
G01X997650D01*
G02X997837Y258206I0J-200D01*
G01X997972Y257858D01*
G02X997922Y257640I-187J-72D01*
G01X997921Y257639D01*
G03X997437Y256535I1017J-1104D01*
G03X1000441I1502J0D01*
G03X999957Y257639I-1501J0D01*
G01X999956Y257640D01*
G02X999906Y257858I137J146D01*
G01X1000041Y258206D01*
G02X1000228Y258334I187J-72D01*
G01X1029655D01*
G03X1030710Y258544I-2J2766D01*
G01X1032020Y259087D01*
G02X1032097Y259102I76J-185D01*
G01X1072820D01*
G02X1073020Y258902I0J-200D01*
G01Y258880D01*
G03X1076024I1502J0D01*
G01Y258902D01*
G02X1076224Y259102I200J0D01*
G01X1175302D01*
G02X1175462Y259021I-1J-200D01*
G01X1175469Y259011D01*
X1175652Y258728D01*
G02X1175684Y258633I-168J-109D01*
G01X1175687Y258584D01*
X1175666Y258537D01*
G03X1175533Y257919I1369J-618D01*
G03X1178537I1502J0D01*
G03X1178404Y258537I-1502J0D01*
G01X1178403Y258538D01*
G02X1178386Y258634I183J82D01*
G01X1178390Y258685D01*
X1178601Y259011D01*
X1178608Y259021D01*
G02X1178768Y259102I161J-119D01*
G01X1277544D01*
G02X1277744Y258902I0J-200D01*
G01Y258880D01*
G03X1280748I1502J0D01*
G01Y258902D01*
G02X1280948Y259102I200J0D01*
G01X1427545D01*
G02X1427745Y258902I0J-200D01*
G01Y258880D01*
G03X1430749I1502J0D01*
G01Y258902D01*
G02X1430949Y259102I200J0D01*
G01X1529907D01*
G02X1530107Y258902I0J-200D01*
G01Y258880D01*
G03X1533111I1502J0D01*
G01Y258902D01*
G02X1533311Y259102I200J0D01*
G01X1632269D01*
G02X1632469Y258902I0J-200D01*
G01Y258880D01*
G03X1635473I1502J0D01*
G01Y258902D01*
G02X1635673Y259102I200J0D01*
G01X1734631D01*
G02X1734831Y258902I0J-200D01*
G01Y258880D01*
G03X1737835I1502J0D01*
G01Y258902D01*
G02X1738035Y259102I200J0D01*
G01X1772363D01*
G02X1772401Y259098I-2J-200D01*
G02X1772503Y259045I-37J-196D01*
G01X1795592Y235956D01*
G02X1795645Y235854I-143J-139D01*
G02X1795649Y235816I-196J-40D01*
G01Y220751D01*
G02X1795627Y220660I-200J0D01*
G02X1795591Y220610I-178J90D01*
G37*
G36*
G01X896575Y269096D02*
G03X898048Y267885I1473J290D01*
G03X898176Y267890I5J1502D01*
G02X898210I17J-199D01*
G03X898344Y267884I134J1499D01*
G01X898346D01*
G03X898689Y267924I-1J1503D01*
G02X898709Y267927I40J-196D01*
G02X899111Y267726I53J-397D01*
G02X899123Y267699I-176J-95D01*
G02X899136Y267635I-187J-71D01*
G01Y265762D01*
G02X899078Y265621I-200J0D01*
G01X898820Y265362D01*
G03X898761Y265221I141J-142D01*
G01Y264216D01*
G03X898760Y264168I2740J-81D01*
G01Y262428D01*
G03X898761Y262380I2741J33D01*
G01Y261520D01*
G02X898596Y261323I-200J0D01*
G01X898595D01*
G03X898077Y261130I256J-1480D01*
G01X898023Y261129D01*
X894728D01*
G02X894608Y261169I0J200D01*
G01X894579Y261191D01*
X894540Y261249D01*
X894532Y261283D01*
G03X894429Y261589I-1753J-420D01*
G03X892640Y262657I-1649J-729D01*
G02X892609I-15J199D01*
G03X892484Y262662I-134J-1797D01*
G03X890732Y261282I0J-1802D01*
G02X890538Y261129I-194J47D01*
G01X885002D01*
G02X884860Y261188I0J200D01*
G01X884836Y261212D01*
X884816Y261232D01*
X884647Y261537D01*
G02X884652Y261739I175J97D01*
G03X884921Y262685I-1533J947D01*
G01Y262687D01*
G03X881315I-1803J0D01*
G03X881572Y261759I1804J0D01*
G01X881587Y261735D01*
X881601Y261681D01*
G02X881606Y261659I-192J-55D01*
G01Y261655D01*
G02X881584Y261529I-198J-30D01*
G01X881420Y261232D01*
X881400Y261212D01*
X881376Y261188D01*
G02X881234Y261129I-142J141D01*
G01X36137D01*
G02X35952Y261252I0J200D01*
G01X35928Y261309D01*
X35952Y261427D01*
X36581Y262056D01*
Y262057D01*
X36645Y262120D01*
X36646Y262121D01*
X36647Y262122D01*
G02X36786Y262178I139J-144D01*
G01X58065D01*
G03X59546Y262835I-2J2002D01*
G01X59549Y262839D01*
X59556Y262846D01*
G02X59750Y262898I142J-141D01*
G01X59802Y262884D01*
X59824Y262872D01*
G03X60561Y262678I738J1308D01*
G01X60562D01*
G03Y265682I0J1502D01*
G01X60561D01*
G03X59803Y265477I0J-1502D01*
G02X59553Y265516I-101J172D01*
G03X58066Y266182I-1491J-1336D01*
G01X35873D01*
G03X34458Y265595I1J-2002D01*
G01X30406Y261543D01*
G02X30359Y261508I-142J141D01*
G01X30358D01*
G02X30264Y261484I-95J176D01*
G01X28218D01*
G02X28197Y261485I-1J200D01*
G01X28148Y261490D01*
X28107Y261517D01*
G02X28069Y261550I111J166D01*
G01X27871Y261769D01*
G02X27829Y261841I148J135D01*
G01X27815Y261884D01*
X27819Y261926D01*
G03X27827Y262070I-1494J155D01*
G01Y262091D01*
G03X24823I-1502J-13D01*
G01Y262078D01*
G03X24831Y261926I1501J3D01*
G01X24835Y261884D01*
X24821Y261841D01*
G02X24779Y261769I-190J63D01*
G01X24581Y261550D01*
G02X24543Y261517I-149J133D01*
G02X24453Y261485I-110J167D01*
G01X24442Y261484D01*
X17575D01*
G03X16487Y261161I2J-2001D01*
G02X16378Y261129I-109J168D01*
G01X12435D01*
G02X12293Y261188I0J200D01*
G01X5511Y267970D01*
G02X5452Y268112I141J142D01*
G01Y270882D01*
G02X5564Y271062I200J0D01*
G01X5769Y271162D01*
X5888Y271219D01*
G02X5996Y271238I87J-180D01*
G02X6099Y271196I-21J-199D01*
G03X7035Y270869I936J1176D01*
G01X7036D01*
G03X8538Y272371I0J1502D01*
G03X7212Y273863I-1502J0D01*
G01X7155Y273869D01*
G03X7036Y273874I-123J-1498D01*
G01X7034D01*
G03X6099Y273546I2J-1503D01*
G01X6054Y273510D01*
X5939Y273498D01*
X5565Y273680D01*
G02X5452Y273860I87J180D01*
G01Y305191D01*
G02X5511Y305333I200J0D01*
G01X10045Y309867D01*
G02X10187Y309926I142J-141D01*
G01X162297D01*
G02X162442Y309864I0J-200D01*
G01X162642Y309653D01*
G02X162684Y309586I-145J-138D01*
G01X162699Y309545D01*
X162697Y309503D01*
G03X162694Y309405I1799J-104D01*
G03X166298I1802J0D01*
G03X166295Y309503I-1802J-6D01*
G01Y309505D01*
G02X166350Y309653I200J10D01*
G01X166550Y309864D01*
G02X166695Y309926I145J-138D01*
G01X199795D01*
G02X199937Y309867I0J-200D01*
G01X212040Y297764D01*
G03X212182Y297705I142J141D01*
G01X330866D01*
G03X331008Y297764I0J200D01*
G01X343111Y309867D01*
G02X343253Y309926I142J-141D01*
G01X421264D01*
X421375Y309829D01*
X421386Y309754D01*
G03X422000Y308744I1487J212D01*
G02X422079Y308624I-116J-163D01*
G01X422114Y308468D01*
X422103Y308394D01*
X422085Y308362D01*
G03X421848Y307470I1566J-893D01*
G03X423649Y305668I1802J0D01*
G01X427051D01*
G03X428854Y307470I0J1803D01*
G03X428617Y308362I-1803J-1D01*
G01X428599Y308394D01*
X428588Y308468D01*
X428631Y308662D01*
X428672Y308722D01*
X428702Y308744D01*
G03X429316Y309754I-873J1222D01*
G01X429327Y309829D01*
X429439Y309926D01*
X510340D01*
G02X510399Y309917I0J-200D01*
G01X510483Y309891D01*
X510507Y309875D01*
G03X510898Y309689I834J1249D01*
G03X511913Y309734I445J1435D01*
G03X512175Y309874I-574J1389D01*
G01X512199Y309890D01*
X512313Y309926D01*
X591203D01*
G02X591339Y309873I0J-200D01*
G01X591340Y309872D01*
G02X591403Y309746I-136J-147D01*
G01Y309741D01*
G03X594397Y309743I1497J129D01*
G01X594400Y309781D01*
X594432Y309846D01*
X594461Y309873D01*
G02X594597Y309926I136J-147D01*
G01X807667D01*
G02X807846Y309814I-1J-200D01*
G03X811086I1620J791D01*
G02X811265Y309926I180J-88D01*
G01X820281D01*
G02X820427Y309862I-1J-200D01*
G01X820656Y309616D01*
X820683Y309538D01*
X820680Y309496D01*
G03X820675Y309368I1797J-134D01*
G03X824279I1802J0D01*
G03X824274Y309496I-1802J-6D01*
G01X824271Y309538D01*
X824298Y309616D01*
X824444Y309773D01*
X824527Y309862D01*
G02X824531Y309866I143J-139D01*
G01X824532Y309867D01*
G02X824674Y309926I142J-141D01*
G01X861234D01*
G02X861380Y309862I-1J-200D01*
G01X861609Y309616D01*
X861636Y309538D01*
X861633Y309496D01*
G03X861628Y309368I1797J-134D01*
G03X865232I1802J0D01*
G03X865227Y309496I-1802J-6D01*
G01X865224Y309538D01*
X865251Y309616D01*
X865397Y309773D01*
X865480Y309862D01*
G02X865484Y309866I143J-139D01*
G01X865485Y309867D01*
G02X865627Y309926I142J-141D01*
G01X876082D01*
G02X876229Y309861I-1J-200D01*
G01X876455Y309616D01*
X876482Y309538D01*
X876479Y309495D01*
G03X876474Y309368I1498J-123D01*
G03X877977Y307865I1503J0D01*
G03X879353Y308764I0J1503D01*
G02X880002Y308886I366J-161D01*
G01X886125Y302763D01*
G02Y302481I-142J-141D01*
G01X886030Y302386D01*
G03X885971Y302244I141J-142D01*
G01Y295050D01*
G02X885912Y294908I-200J0D01*
G01X883942Y292938D01*
G03X883883Y292796I141J-142D01*
G01Y277141D01*
G03X883942Y276999I200J0D01*
G01X890472Y270469D01*
G03X890614Y270410I142J141D01*
G01X891436D01*
G02X891578Y270351I0J-200D01*
G01X892613Y269316D01*
G03X892755Y269257I142J141D01*
G01X896451D01*
X896561Y269167D01*
X896575Y269096D01*
G37*
G36*
G01X60067Y1004863D02*
X58601Y1003397D01*
X58573Y1003368D01*
X58535Y1003353D01*
G02X58460Y1003338I-76J185D01*
G01X11122D01*
G02X11002Y1003378I0J200D01*
G02X10980Y1003397I119J160D01*
G01X7648Y1006729D01*
G02X7629Y1006751I141J141D01*
G02X7589Y1006871I160J120D01*
G01Y1060105D01*
G02X7629Y1060225I200J0D01*
G02X7648Y1060247I160J-119D01*
G01X9128Y1061727D01*
G02X9150Y1061746I141J-141D01*
G02X9270Y1061786I120J-160D01*
G01X17756D01*
G02X17956Y1061586I0J-200D01*
G01Y1022773D01*
G03X18308Y1021924I1202J1D01*
G01X18389Y1021843D01*
G02X18448Y1021702I-141J-142D01*
G01Y1020355D01*
G03X18507Y1020213I200J0D01*
G01X19646Y1019074D01*
G03X19788Y1019015I142J141D01*
G01X45131D01*
G03X45273Y1019074I0J200D01*
G01X47230Y1021031D01*
G03X47289Y1021173I-141J142D01*
G01Y1061703D01*
G02X47348Y1061845I200J0D01*
G01X47449Y1061946D01*
G02X47471Y1061965I141J-141D01*
G02X47591Y1062005I120J-160D01*
G01X58950D01*
G02X59092Y1061946I0J-200D01*
G01X60067Y1060971D01*
G02X60086Y1060949I-141J-141D01*
G02X60126Y1060829I-160J-120D01*
G01Y1005005D01*
G02X60067Y1004863I-200J0D01*
G37*
G36*
G01X34427Y1089070D02*
X35363Y1088134D01*
G02X35382Y1088112I-141J-141D01*
G02X35422Y1087992I-160J-120D01*
G01Y1077718D01*
G03X35481Y1077576I200J0D01*
G01X39332Y1073725D01*
G03X39474Y1073666I142J141D01*
G01X41159D01*
G02X41279Y1073626I0J-200D01*
G02X41301Y1073607I-119J-160D01*
G01X41352Y1073556D01*
G02X41371Y1073534I-141J-141D01*
G02X41411Y1073414I-160J-120D01*
G01Y1071729D01*
G03X41470Y1071587I200J0D01*
G01X45204Y1067852D01*
G03X45346Y1067793I142J141D01*
G01X47020D01*
G02X47140Y1067753I0J-200D01*
G02X47162Y1067734I-119J-160D01*
G01X48665Y1066231D01*
G02X48684Y1066209I-141J-141D01*
G02X48724Y1066089I-160J-120D01*
G01Y1063703D01*
G02X48684Y1063583I-200J0D01*
G02X48665Y1063561I-160J119D01*
G01X48553Y1063449D01*
G02X48531Y1063430I-141J141D01*
G02X48411Y1063390I-120J160D01*
G01X46189D01*
G03X46047Y1063331I0J-200D01*
G01X45381Y1062665D01*
G03X45322Y1062523I141J-142D01*
G01Y1022411D01*
G02X45263Y1022269I-200J0D01*
G01X44660Y1021666D01*
X44632Y1021637D01*
X44594Y1021622D01*
G02X44519Y1021607I-76J185D01*
G01X20124D01*
G02X20049Y1021622I1J200D01*
G01X20011Y1021637D01*
X19983Y1021666D01*
X19016Y1022633D01*
G02X18959Y1022743I141J143D01*
G02X18957Y1022775I198J28D01*
G01Y1062099D01*
G03X18901Y1062237I-200J-1D01*
G01X18899Y1062239D01*
X18882Y1062258D01*
G02X18830Y1062392I148J134D01*
G01Y1062440D01*
G03X18771Y1062582I-200J0D01*
G01X17584Y1063769D01*
G03X17442Y1063828I-142J-141D01*
G01X12570D01*
G02X12450Y1063868I0J200D01*
G02X12428Y1063887I119J160D01*
G01X12416Y1063899D01*
Y1093849D01*
G02X12456Y1093969I200J0D01*
G02X12475Y1093991I160J-119D01*
G01X12974Y1094490D01*
G02X12996Y1094509I141J-141D01*
G02X13116Y1094549I120J-160D01*
G01X34017D01*
G02X34137Y1094509I0J-200D01*
G02X34159Y1094490I-119J-160D01*
G01X34309Y1094340D01*
G02X34328Y1094318I-141J-141D01*
G02X34368Y1094198I-160J-120D01*
G01Y1089212D01*
G03X34427Y1089070I200J0D01*
G37*
G36*
G01X5499Y1095691D02*
X9006D01*
G02X9148Y1095632I0J-200D01*
G01X10381Y1094399D01*
G02X10440Y1094257I-141J-142D01*
G01Y1063149D01*
G02X10381Y1063007I-200J0D01*
G01X10220Y1062846D01*
G02X10079Y1062788I-141J142D01*
G01X8855D01*
G03X8714Y1062729I1J-200D01*
G01X8622Y1062638D01*
G02X8481Y1062579I-142J141D01*
G01X5930D01*
G02X5788Y1062638I0J200D01*
G01X5246Y1063180D01*
G02X5187Y1063322I141J142D01*
G01Y1095378D01*
G02X5245Y1095520I200J1D01*
G01X5357Y1095632D01*
G02X5499Y1095691I142J-141D01*
G37*
G36*
G01X19295Y1144968D02*
X21042Y1146715D01*
G02X21184Y1146774I142J-141D01*
G01X52102D01*
G02X52244Y1146715I0J-200D01*
G01X52448Y1146511D01*
G02X52507Y1146369I-141J-142D01*
G01Y1097281D01*
G02X52448Y1097139I-200J0D01*
G01X51610Y1096301D01*
X51582Y1096272D01*
X51508Y1096242D01*
X11316D01*
G02X11174Y1096301I0J200D01*
G01X9599Y1097876D01*
X9570Y1097904D01*
X9540Y1097978D01*
Y1105739D01*
G02X9599Y1105881I200J0D01*
G01X11035Y1107317D01*
G02X11177Y1107376I142J-141D01*
G01X17246D01*
G03X17388Y1107435I0J200D01*
G01X19177Y1109224D01*
G03X19236Y1109366I-141J142D01*
G01Y1144826D01*
G02X19295Y1144968I200J0D01*
G37*
G36*
G01X12971Y1256520D02*
X63540D01*
G02X63682Y1256461I0J-200D01*
G01X67076Y1253067D01*
G02X67135Y1252925I-141J-142D01*
G01Y1224116D01*
G02X66935Y1223916I-200J0D01*
G01X65110D01*
X65062Y1223928D01*
X65039Y1223941D01*
G03X64596Y1224056I-438J-775D01*
G01X63418D01*
G03X62522Y1223166I-6J-890D01*
G01Y1222312D01*
G03X62722Y1222112I200J0D01*
G01X62758D01*
Y1220246D01*
G02X62558Y1220046I-200J0D01*
G01X62522D01*
Y1218992D01*
G03X62704Y1218452I890J-1D01*
G02X62746Y1218331I-158J-123D01*
G01Y1216666D01*
G02X62546Y1216466I-200J0D01*
G01X55367D01*
X55258Y1216555D01*
X55243Y1216625D01*
G03X53479Y1218058I-1764J-369D01*
G03X51677Y1216256I0J-1802D01*
G03X53420Y1214455I1802J0D01*
G01X53459Y1214454D01*
X53527Y1214424D01*
X53639Y1214312D01*
G03X54531Y1213942I893J892D01*
G01X58554D01*
G02X58742Y1213811I0J-200D01*
G01X58777Y1213716D01*
G02X58726Y1213503I-188J-68D01*
G03X58692Y1213469I1398J-1432D01*
G01X57557Y1212334D01*
G03X57282Y1211992I1413J-1418D01*
G01X57260Y1211956D01*
X57190Y1211910D01*
X56815Y1211844D01*
X56733Y1211864D01*
X56700Y1211890D01*
G03X55596Y1212268I-1104J-1423D01*
G03Y1208664I0J-1802D01*
G03X56394Y1208850I1J1802D01*
G01X56440Y1208873D01*
X56543Y1208868D01*
X56876Y1208661D01*
G02X56970Y1208491I-106J-169D01*
G01Y1206893D01*
G02X56857Y1206712I-200J-1D01*
G01X56479Y1206532D01*
X56365Y1206545D01*
X56319Y1206582D01*
G03X55188Y1206981I-1131J-1403D01*
G03Y1203377I0J-1802D01*
G03X56319Y1203776I0J1802D01*
G01X56365Y1203813D01*
X56479Y1203826D01*
X56857Y1203646D01*
G02X56970Y1203465I-87J-180D01*
G01Y1203351D01*
G02X56912Y1203209I-200J-1D01*
G01X52229Y1198526D01*
G02X52087Y1198468I-141J142D01*
G01X34728D01*
G02X34586Y1198526I-1J200D01*
G01X33046Y1200066D01*
G03X31631Y1200652I-1415J-1415D01*
G03X29630Y1198651I0J-2001D01*
G03X30216Y1197236I2001J0D01*
G01X32401Y1195051D01*
G03X33816Y1194464I1416J1415D01*
G01X52999D01*
G03X54414Y1195051I-1J2002D01*
G01X57867Y1198504D01*
G02X58059Y1198556I141J-142D01*
G01X58445Y1198455D01*
X58520Y1198381D01*
X58535Y1198330D01*
G03X60269Y1197018I1734J490D01*
G03X62071Y1198820I0J1802D01*
G03X60440Y1200614I-1802J0D01*
G01X60406Y1200617D01*
X60343Y1200647D01*
X60318Y1200671D01*
G02Y1200954I141J141D01*
G01X60387Y1201024D01*
G03X60974Y1202439I-1415J1416D01*
G01Y1206230D01*
G02X61107Y1206419I200J1D01*
G01X61524Y1206564D01*
X61646Y1206529D01*
X61686Y1206479D01*
G03X63094Y1205802I1408J1126D01*
G03Y1209406I0J1802D01*
G03X61686Y1208729I0J-1803D01*
G01X61646Y1208679D01*
X61524Y1208644D01*
X61107Y1208789D01*
G02X60974Y1208978I67J188D01*
G01Y1209852D01*
G02X61174Y1210052I199J0D01*
G01X63981D01*
G03X65982Y1212054I0J2001D01*
G03X65299Y1213560I-2002J0D01*
G02X65230Y1213711I131J151D01*
G01Y1214462D01*
G02X65430Y1214662I200J0D01*
G01X65466D01*
Y1215716D01*
G03X65305Y1216227I-890J0D01*
G01X65287Y1216252D01*
X65268Y1216311D01*
Y1218331D01*
G02X65310Y1218452I200J-2D01*
G03X65492Y1218992I-708J539D01*
G01Y1219846D01*
G03X65292Y1220046I-200J0D01*
G01X65256D01*
Y1221192D01*
G02X65456Y1221392I200J0D01*
G01X66365D01*
G02X66506Y1221334I0J-200D01*
G01X67076Y1220764D01*
G02X67135Y1220622I-141J-142D01*
G01Y1213141D01*
G02X67089Y1213013I-200J0D01*
G03Y1211095I1156J-959D01*
G02X67135Y1210967I-154J-128D01*
G01Y1192006D01*
G02X67119Y1191927I-200J-1D01*
G03X66029Y1186654I12212J-5274D01*
G03X67119Y1181381I13302J1D01*
G02X67135Y1181302I-184J-78D01*
G01Y1160895D01*
G03X67194Y1160753I200J0D01*
G01X71458Y1156489D01*
G02X71517Y1156347I-141J-142D01*
G01Y1077237D01*
G02X71411Y1077060I-200J0D01*
G01X71051Y1076868D01*
X70941Y1076873D01*
X70895Y1076904D01*
G03X70059Y1077158I-836J-1249D01*
G03Y1074154I0J-1502D01*
G03X70895Y1074408I0J1503D01*
G01X70941Y1074439D01*
X71051Y1074444D01*
X71411Y1074252D01*
G02X71517Y1074075I-94J-177D01*
G01Y1069374D01*
G02X71424Y1069205I-200J0D01*
G01X71094Y1068997D01*
X70993Y1068991D01*
X70946Y1069013D01*
G03X70302Y1069158I-644J-1358D01*
G03X68800Y1067656I0J-1502D01*
G03X70291Y1066154I1502J0D01*
G01X70352D01*
X70451Y1066086D01*
X70614Y1065689D01*
G02X70570Y1065471I-185J-76D01*
G01X69944Y1064845D01*
X69839Y1064818D01*
X69786Y1064833D01*
G03X69373Y1064891I-413J-1444D01*
G03X67877Y1063518I0J-1502D01*
G01X67870Y1063440D01*
X67756Y1063335D01*
X51737D01*
G02X51595Y1063394I0J200D01*
G01X50794Y1064195D01*
G02X50735Y1064337I141J142D01*
G01Y1065493D01*
X49784Y1066444D01*
G02X49726Y1066585I142J141D01*
G01Y1066587D01*
X47576Y1068736D01*
G03X47435Y1068794I-141J-142D01*
G01X47434D01*
X44324Y1071904D01*
G03X44182Y1071963I-142J-141D01*
G01X43001D01*
G02X42859Y1072022I0J200D01*
G01X42471Y1072410D01*
G02X42412Y1072551I141J142D01*
G01Y1073829D01*
G03X42354Y1073970I-200J0D01*
G01X41715Y1074609D01*
G03X41574Y1074668I-142J-141D01*
G01X41561D01*
X36516Y1079712D01*
G02X36457Y1079854I141J142D01*
G01Y1088613D01*
G03X36398Y1088755I-200J0D01*
G01X35428Y1089725D01*
G02X35370Y1089866I142J141D01*
G01Y1094536D01*
G02X35428Y1094677I200J0D01*
G01X35564Y1094813D01*
G02X35706Y1094872I142J-141D01*
G01X37574D01*
X37577Y1094875D01*
X44405D01*
G02X44571Y1094787I0J-200D01*
G01X44784Y1094469D01*
X44794Y1094371D01*
X44775Y1094324D01*
G03X44664Y1093757I1391J-567D01*
G03X47668I1502J0D01*
G03X47557Y1094324I-1502J0D01*
G01X47538Y1094371D01*
X47548Y1094469D01*
X47761Y1094787D01*
G02X47927Y1094875I166J-112D01*
G01X52211D01*
G03X52353Y1094934I0J200D01*
G01X53732Y1096313D01*
G03X53791Y1096455I-141J142D01*
G01Y1096647D01*
X53788Y1096650D01*
Y1146802D01*
G03X53729Y1146944I-200J0D01*
G01X52321Y1148352D01*
G03X52179Y1148411I-142J-141D01*
G01X20470D01*
G03X20328Y1148352I0J-200D01*
G01X17806Y1145830D01*
G03X17747Y1145688I141J-142D01*
G01Y1110889D01*
G02X17688Y1110747I-200J0D01*
G01X17065Y1110124D01*
G02X16923Y1110065I-142J141D01*
G01X5505D01*
G02X5305Y1110265I0J200D01*
G01Y1153233D01*
G02X5364Y1153375I200J0D01*
G01X11651Y1159662D01*
G03X11710Y1159804I-141J142D01*
G01Y1255259D01*
G02X11767Y1255399I200J0D01*
G01X11768Y1255400D01*
X12829Y1256461D01*
G02X12831Y1256463I142J-140D01*
G02X12971Y1256520I140J-143D01*
G37*
G36*
G01X17856Y1495644D02*
X22289D01*
G02X22489Y1495444I0J-200D01*
G01Y1476594D01*
G02X22289Y1476394I-200J0D01*
G01X7489D01*
G02X7289Y1476594I0J200D01*
G01Y1495335D01*
X7346Y1495429D01*
X7395Y1495456D01*
G03X7618Y1495601I-704J1327D01*
G01X7645Y1495622D01*
X7708Y1495644D01*
X8122D01*
G02X8292Y1495549I0J-200D01*
G01X8499Y1495214D01*
X8503Y1495111D01*
X8479Y1495064D01*
G03X8287Y1494254I1610J-809D01*
G03X11891I1802J0D01*
G03X11699Y1495064I-1802J1D01*
G01X11675Y1495111D01*
X11679Y1495214D01*
X11886Y1495549D01*
G02X12056Y1495644I170J-105D01*
G01X13922D01*
G02X14092Y1495549I0J-200D01*
G01X14299Y1495214D01*
X14303Y1495111D01*
X14279Y1495064D01*
G03X14087Y1494254I1610J-809D01*
G03X17691I1802J0D01*
G03X17499Y1495064I-1802J1D01*
G01X17475Y1495111D01*
X17479Y1495214D01*
X17686Y1495549D01*
G02X17856Y1495644I170J-105D01*
G37*
G36*
G01X14188Y1505834D02*
Y1501551D01*
X14180Y1501543D01*
Y1500725D01*
X13689Y1500234D01*
X6194D01*
X5389Y1501039D01*
Y1505442D01*
X5981Y1506034D01*
X13988D01*
X14188Y1505834D01*
G37*
G36*
G01X8531Y1513494D02*
X22329D01*
X23046Y1512777D01*
Y1511147D01*
X23062Y1511130D01*
Y1508330D01*
X21155Y1506423D01*
Y1501324D01*
X20677Y1500846D01*
X15846D01*
X15354Y1501338D01*
Y1504398D01*
Y1507469D01*
X14997Y1507826D01*
X8388D01*
X8138Y1508076D01*
Y1513101D01*
X8531Y1513494D01*
G37*
G36*
G01X22721Y1535276D02*
X39547D01*
X39789Y1535034D01*
Y1534234D01*
X41850Y1532173D01*
X47050D01*
X50388Y1528835D01*
Y1514666D01*
Y1510293D01*
X50236Y1510141D01*
X42696D01*
X31908D01*
X30941Y1509174D01*
Y1500595D01*
X31938Y1499598D01*
X32188Y1499348D01*
X32269Y1499267D01*
X50334D01*
X50415Y1499348D01*
X50665Y1499598D01*
X56803D01*
X56812Y1499607D01*
X57359D01*
X59535Y1501783D01*
Y1509105D01*
X61019Y1510589D01*
Y1512644D01*
X62565Y1514190D01*
Y1534179D01*
X62995Y1534609D01*
X66038D01*
X66567Y1534080D01*
Y1501600D01*
X63963Y1498996D01*
X60701Y1495734D01*
X58089D01*
X24728D01*
X22639Y1497823D01*
Y1505927D01*
X23935Y1507223D01*
X24680Y1507968D01*
Y1508522D01*
X24689Y1508531D01*
Y1511339D01*
Y1513003D01*
Y1513385D01*
X24691Y1513387D01*
X23518Y1514560D01*
X16629D01*
X16274Y1514915D01*
Y1517905D01*
X16721Y1518352D01*
X25641D01*
X27790Y1520501D01*
Y1531288D01*
X26302Y1532776D01*
X22347D01*
X22189Y1532934D01*
Y1534744D01*
X22721Y1535276D01*
G37*
G36*
G01X26790Y1530733D02*
Y1526860D01*
X25933Y1526003D01*
X19820D01*
X18752Y1527071D01*
Y1531087D01*
X19619Y1531954D01*
X21139D01*
X21659Y1531434D01*
X26089D01*
X26790Y1530733D01*
G37*
G36*
G01X49019Y1500598D02*
X49012D01*
X48718Y1500304D01*
X45396D01*
X44762D01*
X32893D01*
X32249Y1500948D01*
Y1508470D01*
X32898Y1509119D01*
X43500D01*
X43522Y1509141D01*
X50989D01*
X51588Y1509740D01*
Y1530169D01*
X48323Y1533434D01*
X42289D01*
X41089Y1534634D01*
Y1535712D01*
X40525Y1536276D01*
X22223D01*
X21189Y1535242D01*
X19231Y1533284D01*
Y1533263D01*
X17607Y1531639D01*
Y1526616D01*
X19233Y1524991D01*
X26509D01*
X26772Y1524728D01*
Y1521847D01*
X24574Y1519649D01*
X19674D01*
X19415D01*
X17570Y1521494D01*
X15728Y1523336D01*
X14097Y1524967D01*
Y1533442D01*
X15728Y1535073D01*
X20308Y1539653D01*
X55470D01*
X57824D01*
X61549Y1535928D01*
Y1516595D01*
Y1514628D01*
X60787Y1513866D01*
X60781D01*
X60002Y1513086D01*
Y1510998D01*
X58026Y1509022D01*
X55636D01*
X49183Y1502569D01*
Y1500762D01*
X49019Y1500598D01*
G37*
G36*
G01X82580Y174205D02*
X86132D01*
G02X86274Y174146I0J-200D01*
G01X88475Y171945D01*
G02X88534Y171803I-141J-142D01*
G01Y147989D01*
G02X88424Y147811I-200J1D01*
G01X88054Y147624D01*
X87942Y147634D01*
X87896Y147668D01*
G03X87002Y147963I-894J-1207D01*
G03Y144959I0J-1502D01*
G03X87896Y145254I0J1502D01*
G01X87942Y145288D01*
X88054Y145298D01*
X88424Y145111D01*
G02X88534Y144933I-90J-179D01*
G01Y138227D01*
X88461Y138124D01*
X88401Y138103D01*
G03X87680Y137560I502J-1416D01*
G02X87561Y137481I-163J116D01*
G01X87442Y137454D01*
G02X87299Y137475I-44J195D01*
G03X86407Y137712I-893J-1566D01*
G03X85515Y137475I1J-1803D01*
G02X85372Y137454I-99J174D01*
G01X85253Y137481D01*
G02X85134Y137560I44J195D01*
G03X83911Y138189I-1222J-873D01*
G03Y135185I0J-1502D01*
G03X84143Y135203I0J1502D01*
G01X84186Y135210D01*
X84270Y135186D01*
X84535Y134960D01*
G02X84604Y134808I-131J-151D01*
G01Y133610D01*
G02X84535Y133458I-200J-1D01*
G01X84270Y133232D01*
X84186Y133208D01*
X84143Y133215D01*
G03X83911Y133233I-232J-1484D01*
G03Y130229I0J-1502D01*
G03X85134Y130858I1J1502D01*
G02X85253Y130937I163J-116D01*
G01X85372Y130964D01*
G02X85515Y130943I44J-195D01*
G03X86407Y130706I893J1566D01*
G03X87299Y130943I-1J1803D01*
G02X87442Y130964I99J-174D01*
G01X87561Y130937D01*
G02X87680Y130858I-44J-195D01*
G03X88401Y130315I1223J873D01*
G01X88461Y130294D01*
X88534Y130191D01*
Y124053D01*
X88461Y123950D01*
X88401Y123929D01*
G03X87680Y123386I502J-1416D01*
G02X87561Y123307I-163J116D01*
G01X87442Y123280D01*
G02X87299Y123301I-44J195D01*
G03X86407Y123538I-893J-1566D01*
G03X85515Y123301I1J-1803D01*
G02X85372Y123280I-99J174D01*
G01X85253Y123307D01*
G02X85134Y123386I44J195D01*
G03X83911Y124015I-1222J-873D01*
G03Y121011I0J-1502D01*
G03X84143Y121029I0J1502D01*
G01X84186Y121036D01*
X84270Y121012D01*
X84535Y120786D01*
G02X84604Y120634I-131J-151D01*
G01Y119436D01*
G02X84535Y119284I-200J-1D01*
G01X84270Y119058D01*
X84186Y119034D01*
X84143Y119041D01*
G03X83911Y119059I-232J-1484D01*
G03Y116055I0J-1502D01*
G03X85134Y116684I1J1502D01*
G02X85253Y116763I163J-116D01*
G01X85372Y116790D01*
G02X85515Y116769I44J-195D01*
G03X86407Y116532I893J1566D01*
G03X87299Y116769I-1J1803D01*
G02X87442Y116790I99J-174D01*
G01X87561Y116763D01*
G02X87680Y116684I-44J-195D01*
G03X88401Y116141I1223J873D01*
G01X88461Y116120D01*
X88534Y116017D01*
Y105504D01*
G02X88473Y105361I-200J1D01*
G01X88238Y105132D01*
X88164Y105103D01*
X88123Y105104D01*
G03X88080Y105105I-56J-1501D01*
G03Y102101I0J-1502D01*
G03X88123Y102102I-13J1502D01*
G01X88164Y102103D01*
X88238Y102074D01*
X88473Y101845D01*
G02X88534Y101702I-139J-144D01*
G01Y95656D01*
G02X88475Y95514I-200J0D01*
G01X61755Y68794D01*
G02X61592Y68737I-141J142D01*
G01X61237Y68775D01*
X61160Y68823D01*
X61136Y68861D01*
G03X54589Y65001I-3202J-2050D01*
G01X54614Y64954D01*
X54612Y64849D01*
X54409Y64508D01*
G02X54237Y64410I-172J102D01*
G01X47393D01*
G03Y57008I0J-3701D01*
G01X49486D01*
G02X49671Y56884I0J-200D01*
G01X49694Y56827D01*
X49671Y56710D01*
X48609Y55648D01*
G02X48468Y55590I-141J142D01*
G01X35295D01*
G03X31157Y54574I1J-8937D01*
G01X31135Y54562D01*
X31089Y54551D01*
X26740D01*
G02X26540Y54751I0J200D01*
G01Y72976D01*
G02X26615Y73132I200J0D01*
G01X26893Y73356D01*
X26981Y73376D01*
X27025Y73367D01*
G03X28819Y73173I1795J8208D01*
G03X37221Y81575I0J8402D01*
G03X31883Y89398I-8401J0D01*
G01X31836Y89417D01*
X31771Y89493D01*
X31692Y89871D01*
G02X31746Y90053I196J41D01*
G01X37516Y95823D01*
G03X37575Y95965I-141J142D01*
G01Y100421D01*
G02X37634Y100563I200J0D01*
G01X37864Y100791D01*
X37937Y100821D01*
X37978D01*
X37988D01*
G03Y103825I0J1502D01*
G01X37937D01*
X37864Y103855D01*
X37634Y104083D01*
G02X37575Y104225I141J142D01*
G01Y107508D01*
G02X37634Y107650I200J0D01*
G01X37864Y107878D01*
X37937Y107908D01*
X37978D01*
X37988D01*
G03Y110912I0J1502D01*
G01X37937D01*
X37864Y110942D01*
X37634Y111170D01*
G02X37575Y111312I141J142D01*
G01Y114594D01*
G02X37634Y114736I200J0D01*
G01X37864Y114964D01*
X37937Y114994D01*
X37978D01*
X37988D01*
G03Y117998I0J1502D01*
G01X37937D01*
X37864Y118028D01*
X37634Y118256D01*
G02X37575Y118398I141J142D01*
G01Y121681D01*
G02X37634Y121823I200J0D01*
G01X37864Y122051D01*
X37937Y122081D01*
X37978D01*
X37988D01*
G03Y125085I0J1502D01*
G01X37937D01*
X37864Y125115D01*
X37634Y125343D01*
G02X37575Y125485I141J142D01*
G01Y128768D01*
G02X37634Y128910I200J0D01*
G01X37864Y129138D01*
X37937Y129168D01*
X37978D01*
X37988D01*
G03Y132172I0J1502D01*
G01X37937D01*
X37864Y132202D01*
X37634Y132430D01*
G02X37575Y132572I141J142D01*
G01Y135854D01*
G02X37634Y135996I200J0D01*
G01X37864Y136224D01*
X37937Y136254D01*
X37978D01*
X37988D01*
G03Y139258I0J1502D01*
G01X37937D01*
X37864Y139288D01*
X37634Y139516D01*
G02X37575Y139658I141J142D01*
G01Y172123D01*
G02X37634Y172265I200J0D01*
G01X39515Y174146D01*
G02X39657Y174205I142J-141D01*
G01X79586D01*
G02X79772Y174078I0J-200D01*
G01X79931Y173673D01*
X79904Y173554D01*
X79858Y173512D01*
G03X79281Y172190I1226J-1322D01*
G03X82885I1802J0D01*
G03X82308Y173512I-1803J0D01*
G01X82262Y173554D01*
X82235Y173673D01*
X82394Y174078D01*
G02X82580Y174205I186J-73D01*
G37*
G36*
G01X169063Y559473D02*
X180586D01*
G02X180727Y559415I0J-200D01*
G01X180961Y559182D01*
G02X180979Y559161I-143J-140D01*
G01X180999Y559136D01*
X181020Y559073D01*
Y549446D01*
G02X180961Y549304I-200J0D01*
G01X180807Y549150D01*
X180779Y549121D01*
X180705Y549091D01*
X174909D01*
G03X174767Y549032I0J-200D01*
G01X166822Y541087D01*
X166794Y541058D01*
X166720Y541028D01*
X136854D01*
G03X136712Y540969I0J-200D01*
G01X123148Y527405D01*
G03X123089Y527263I141J-142D01*
G01Y474821D01*
G02X123030Y474679I-200J0D01*
G01X102382Y454031D01*
X102354Y454002D01*
X102342Y453997D01*
X72121D01*
X68186Y457932D01*
Y462532D01*
X68050Y462669D01*
G02X68057Y462800I192J55D01*
G01X68157Y463041D01*
X68219Y463100D01*
X68260Y463114D01*
G03X69473Y464818I-590J1704D01*
G03X67670Y466621I-1803J0D01*
G03X65993Y465480I0J-1803D01*
G01X65974Y465432D01*
X65897Y465368D01*
X65522Y465290D01*
X65519D01*
G02X65424Y465294I-39J196D01*
G01X63485Y467233D01*
Y472229D01*
X63491Y472238D01*
G03X63726Y473043I-1267J807D01*
G01Y473045D01*
G03X60722I-1502J0D01*
G01Y473043D01*
G03X60957Y472238I1502J2D01*
G01X60963Y472229D01*
Y466189D01*
X62578Y464573D01*
G02X62583Y464482I-192J-56D01*
G01X62515Y464111D01*
X62455Y464034D01*
X62410Y464013D01*
G03X61351Y462371I743J-1642D01*
G03X63154Y460568I1803J0D01*
G03X64796Y461627I0J1802D01*
G01X64817Y461672D01*
X64894Y461732D01*
X65262Y461800D01*
G02X65357Y461795I37J-197D01*
G01X65664Y461488D01*
Y456888D01*
X68012Y454540D01*
G02X67650Y453971I-362J-169D01*
G01X38763D01*
G02X38621Y454030I0J200D01*
G01X34228Y458423D01*
X34199Y458451D01*
X34169Y458525D01*
Y477417D01*
G02X34276Y477594I200J0D01*
G01X34639Y477785D01*
X34750Y477778D01*
X34796Y477746D01*
G03X35649Y477480I853J1236D01*
G01X35650D01*
G03Y480484I0J1502D01*
G01X35649D01*
G03X34796Y480218I0J-1502D01*
G01X34750Y480186D01*
X34639Y480179D01*
X34276Y480370D01*
G02X34169Y480547I93J177D01*
G01Y482417D01*
G02X34276Y482594I200J0D01*
G01X34639Y482785D01*
X34750Y482778D01*
X34796Y482746D01*
G03X35649Y482480I853J1236D01*
G01X35650D01*
G03Y485484I0J1502D01*
G01X35649D01*
G03X34796Y485218I0J-1502D01*
G01X34750Y485186D01*
X34639Y485179D01*
X34276Y485370D01*
G02X34169Y485547I93J177D01*
G01Y486417D01*
G02X34276Y486594I200J0D01*
G01X34639Y486785D01*
X34750Y486778D01*
X34796Y486746D01*
G03X35649Y486480I853J1236D01*
G01X35650D01*
G03Y489484I0J1502D01*
G01X35649D01*
G03X34796Y489218I0J-1502D01*
G01X34750Y489186D01*
X34639Y489179D01*
X34276Y489370D01*
G02X34169Y489547I93J177D01*
G01Y490417D01*
G02X34276Y490594I200J0D01*
G01X34639Y490785D01*
X34750Y490778D01*
X34796Y490746D01*
G03X35649Y490480I853J1236D01*
G01X35650D01*
G03Y493484I0J1502D01*
G01X35649D01*
G03X34796Y493218I0J-1502D01*
G01X34750Y493186D01*
X34639Y493179D01*
X34276Y493370D01*
G02X34169Y493547I93J177D01*
G01Y498417D01*
G02X34276Y498594I200J0D01*
G01X34639Y498785D01*
X34750Y498778D01*
X34796Y498746D01*
G03X35649Y498480I853J1236D01*
G01X35650D01*
G03Y501484I0J1502D01*
G01X35645D01*
G02X35460Y501607I0J200D01*
G01X35318Y501949D01*
G02X35361Y502167I185J77D01*
G01X35561Y502367D01*
G02X35703Y502426I142J-141D01*
G01X83020D01*
G03X83162Y502485I0J200D01*
G01X84347Y503670D01*
G03X84406Y503812I-141J142D01*
G01Y528321D01*
G02X84465Y528463I200J0D01*
G01X107110Y551108D01*
G02X107252Y551167I142J-141D01*
G01X141218D01*
G02X141313Y551143I0J-200D01*
G03X142735I711J1323D01*
G02X142830Y551167I95J-176D01*
G01X160591D01*
G03X160733Y551226I0J200D01*
G01X168921Y559414D01*
G02X169063Y559473I142J-141D01*
G37*
G36*
G01X32090Y682324D02*
Y663416D01*
Y662483D01*
X30916Y661309D01*
X23475D01*
X22144Y662640D01*
Y682302D01*
X23059Y683217D01*
X24431D01*
X29974D01*
X29990Y683200D01*
X31214D01*
X31426Y682988D01*
X32090Y682324D01*
G37*
G36*
G01X49161Y661414D02*
X36543D01*
X34629D01*
X33357Y662686D01*
Y683065D01*
X31207Y685215D01*
Y699012D01*
X33040Y700845D01*
X49850D01*
X50492Y700203D01*
Y682248D01*
Y662745D01*
X49161Y661414D01*
G37*
G36*
G01X42737Y615351D02*
X42762Y615376D01*
X42835Y615406D01*
X57553D01*
G02X57695Y615347I0J-200D01*
G01X58106Y614936D01*
G02X58165Y614794I-141J-142D01*
G01Y585419D01*
G03X58224Y585277I200J0D01*
G01X59898Y583603D01*
G03X60040Y583544I142J141D01*
G01X62548D01*
G02X62703Y583470I0J-200D01*
G01X62928Y583193D01*
X62949Y583105D01*
X62939Y583061D01*
G03X62906Y582747I1469J-313D01*
G03X65910I1502J0D01*
G03X65877Y583061I-1502J1D01*
G01X65867Y583105D01*
X65888Y583193D01*
X66113Y583470D01*
G02X66268Y583544I155J-126D01*
G01X88550D01*
G02X88692Y583485I0J-200D01*
G01X89334Y582843D01*
G02X89393Y582701I-141J-142D01*
G01Y577618D01*
G02X89334Y577476I-200J0D01*
G01X87907Y576049D01*
G02X87765Y575990I-142J141D01*
G01X81978D01*
G03X81836Y575931I0J-200D01*
G01X74501Y568596D01*
G03X74442Y568454I141J-142D01*
G01Y556856D01*
X74471Y556827D01*
Y551474D01*
G03X74530Y551332I200J0D01*
G01X76177Y549685D01*
G03X76319Y549626I142J141D01*
G01X79480D01*
G02X79622Y549567I0J-200D01*
G01X80507Y548682D01*
G02X80566Y548540I-141J-142D01*
G01Y536820D01*
G02X80507Y536678I-200J0D01*
G01X79877Y536048D01*
G02X79735Y535989I-142J141D01*
G01X53044D01*
G03X52902Y535930I0J-200D01*
G01X51012Y534040D01*
G02X50870Y533981I-142J141D01*
G01X49394D01*
G02X49252Y534040I0J200D01*
G01X48978Y534314D01*
G02X48919Y534456I141J142D01*
G01Y542712D01*
G02X48978Y542854I200J0D01*
G01X49068Y542944D01*
G02X49210Y543003I142J-141D01*
G01X50388D01*
X50461Y542973D01*
X50483Y542951D01*
X50792D01*
G03X50934Y543010I0J200D01*
G01X51937Y544013D01*
G03X51996Y544155I-141J142D01*
G01Y548298D01*
X51990D01*
X51181Y549107D01*
G03X51039Y549166I-142J-141D01*
G01X44080D01*
G02X43938Y549225I0J200D01*
G01X42814Y550349D01*
G02X42755Y550491I141J142D01*
G01Y554389D01*
X42737Y554407D01*
Y615351D01*
G37*
G36*
G01X65849Y839318D02*
Y820418D01*
X65149Y819718D01*
X45449D01*
X44949Y820218D01*
Y828618D01*
X45149Y828818D01*
X52149D01*
X52749Y828218D01*
Y826318D01*
X53599Y825468D01*
X58299D01*
X59249Y826418D01*
Y839418D01*
Y842118D01*
X59449Y842318D01*
X59849Y842718D01*
X65449D01*
X65849Y842318D01*
Y839318D01*
G37*
G36*
G01X45549Y839618D02*
X52149D01*
X53149Y838618D01*
Y837118D01*
X54149Y836118D01*
X57849D01*
X58149Y835818D01*
Y831618D01*
X57949Y831418D01*
X45349D01*
X45049Y831718D01*
Y839118D01*
X45549Y839618D01*
G37*
G36*
G01X56150Y1508020D02*
X58341D01*
G02X58482Y1507962I0J-200D01*
G01X58503Y1507941D01*
X58534Y1507868D01*
Y1502281D01*
G02X58475Y1502139I-200J0D01*
G01X57003Y1500667D01*
G02X56861Y1500608I-142J141D01*
G01X56397D01*
X56388Y1500600D01*
X50707D01*
G02X50566Y1500658I0J200D01*
G01X50525Y1500699D01*
G02X50466Y1500841I141J142D01*
G01Y1502336D01*
G02X50525Y1502478I200J0D01*
G01X56009Y1507962D01*
G02X56150Y1508020I141J-142D01*
G37*
G36*
G01X77412Y833955D02*
X77949Y833418D01*
Y820418D01*
X77249Y819718D01*
X75649D01*
X67549D01*
X66949Y820318D01*
Y833196D01*
Y833918D01*
X67249Y834218D01*
X77149D01*
X77412Y833955D01*
G37*
G36*
G01X54599Y1545247D02*
X55174Y1545822D01*
G02X55316Y1545881I142J-141D01*
G01X66734D01*
G02X66876Y1545822I0J-200D01*
G01X67438Y1545260D01*
G02X67497Y1545118I-141J-142D01*
G01Y1541207D01*
G02X67438Y1541065I-200J0D01*
G01X67179Y1540806D01*
G02X67037Y1540747I-142J141D01*
G01X55202D01*
G02X55060Y1540806I0J200D01*
G01X54599Y1541267D01*
G02X54540Y1541409I141J142D01*
G01Y1545105D01*
G02X54599Y1545247I200J0D01*
G37*
G36*
G01X137657Y54588D02*
X166715D01*
X166891Y54412D01*
Y52762D01*
X166720Y52591D01*
X137657D01*
G03X131720Y46654I0J-5937D01*
G01Y7874D01*
G02X125846Y2000I-5874J0D01*
G01X78602D01*
G02X72728Y7874I0J5874D01*
G01Y45793D01*
X74726D01*
Y7874D01*
G03X78602Y3998I3876J0D01*
G01X125846D01*
G03X129722Y7874I0J3876D01*
G01Y46654D01*
G02X137657Y54588I7935J-1D01*
G37*
G36*
G01X98220Y581389D02*
X160319D01*
X166228D01*
X169746Y577871D01*
X179331D01*
G02X179473Y577812I0J-200D01*
G01X180060Y577225D01*
G02X180119Y577083I-141J-142D01*
G01Y576817D01*
G02X180060Y576676I-200J1D01*
G01X180058Y576673D01*
G03X180000Y576532I142J-141D01*
G01Y561393D01*
G02X179941Y561252I-200J1D01*
G01X179932Y561243D01*
G02X179790Y561184I-142J141D01*
G01X168004D01*
G03X167862Y561125I0J-200D01*
G01X159143Y552406D01*
G02X159001Y552347I-142J141D01*
G01X143643D01*
X143528Y552457D01*
X143524Y552537D01*
G03X140524I-1500J-71D01*
G01X140520Y552457D01*
X140405Y552347D01*
X77731D01*
G02X77589Y552406I0J200D01*
G01X76403Y553592D01*
G02X76344Y553734I141J142D01*
G01Y567086D01*
G02X76403Y567228I200J0D01*
G01X82311Y573136D01*
G02X82453Y573195I142J-141D01*
G01X89860D01*
G03X90002Y573254I0J200D01*
G01X98078Y581330D01*
G02X98220Y581389I142J-141D01*
G37*
G36*
G01X93524Y675592D02*
Y667417D01*
X93014Y666907D01*
X89014D01*
X88014Y667907D01*
Y669141D01*
X84902Y672253D01*
X83725Y673430D01*
X80023D01*
X74621D01*
X71991D01*
X70716Y674705D01*
Y680326D01*
Y684627D01*
Y685268D01*
X71059Y685611D01*
X76212D01*
X76741Y685082D01*
Y684480D01*
Y681466D01*
Y681407D01*
X77741Y680407D01*
X78711Y679437D01*
X80125Y678023D01*
X85206D01*
X86620Y679437D01*
X92465D01*
X93524Y678378D01*
Y675592D01*
G37*
G36*
G01X82243Y1348187D02*
G03I-491J0D01*
G37*
G36*
G01X74363D02*
G03I-491J0D01*
G37*
G36*
G01X82243Y1360099D02*
G03I-491J0D01*
G37*
G36*
G01X74363D02*
G03I-491J0D01*
G37*
G36*
G01X82243Y1372385D02*
G03I-491J0D01*
G37*
G36*
G01X74363D02*
G03I-491J0D01*
G37*
G36*
G01X82243Y1384297D02*
G03I-491J0D01*
G37*
G36*
G01X74363D02*
G03I-491J0D01*
G37*
G36*
G01X91710Y880804D02*
X96556D01*
X96750Y880610D01*
Y874249D01*
X96191Y873690D01*
X90641D01*
X89950Y874381D01*
Y879997D01*
X90757Y880804D01*
X91710D01*
G37*
G36*
G01X98527Y880998D02*
X103276D01*
X104245Y880029D01*
Y872469D01*
Y871203D01*
X103408Y870366D01*
X98044D01*
X97881Y870529D01*
Y872112D01*
Y880352D01*
X98527Y880998D01*
G37*
G36*
G01X97500Y1036612D02*
X101415D01*
G02X101557Y1036553I0J-200D01*
G01X102393Y1035717D01*
G02X102452Y1035575I-141J-142D01*
G01Y1033567D01*
G02X102393Y1033425I-200J0D01*
G01X98354Y1029386D01*
G03X98295Y1029244I141J-142D01*
G01Y1026929D01*
G03X98354Y1026787I200J0D01*
G01X98378Y1026763D01*
X98362Y1026746D01*
G03X98304Y1026605I142J-141D01*
G01Y1020479D01*
G02X98104Y1020279I-200J0D01*
G01X94971D01*
G02X94829Y1020338I0J200D01*
G01X93165Y1022002D01*
G02X93106Y1022144I141J142D01*
G01Y1022334D01*
G02X93213Y1022511I200J0D01*
G01X93576Y1022702D01*
X93687Y1022695D01*
X93733Y1022664D01*
G03X94586Y1022398I853J1235D01*
G03Y1025402I0J1502D01*
G03X93733Y1025136I0J-1501D01*
G01X93687Y1025105D01*
X93576Y1025098D01*
X93213Y1025289D01*
G02X93106Y1025466I93J177D01*
G01Y1032218D01*
G02X93165Y1032360I200J0D01*
G01X97358Y1036553D01*
G02X97500Y1036612I142J-141D01*
G37*
G36*
G01X99364Y1026332D02*
X100105Y1027073D01*
G02X100247Y1027132I142J-141D01*
G01X106642D01*
G02X106784Y1027073I0J-200D01*
G01X107314Y1026543D01*
G02X107373Y1026401I-141J-142D01*
G01Y1023973D01*
G02X107314Y1023831I-200J0D01*
G01X103821Y1020338D01*
G02X103679Y1020279I-142J141D01*
G01X99505D01*
G02X99305Y1020479I0J200D01*
G01Y1026190D01*
G02X99364Y1026332I200J0D01*
G37*
G36*
G01X134431Y1066535D02*
G02I-17700J0D01*
G37*
G36*
G01Y1263386D02*
G02I-17700J0D01*
G37*
G36*
G01X98843Y1348187D02*
G03I-491J0D01*
G37*
G36*
G01X94483D02*
G03I-491J0D01*
G37*
G36*
G01X86603D02*
G03I-491J0D01*
G37*
G36*
G01X98843Y1360099D02*
G03I-491J0D01*
G37*
G36*
G01X94483D02*
G03I-491J0D01*
G37*
G36*
G01X86603D02*
G03I-491J0D01*
G37*
G36*
G01X98843Y1372385D02*
G03I-491J0D01*
G37*
G36*
G01X94483D02*
G03I-491J0D01*
G37*
G36*
G01X86603D02*
G03I-491J0D01*
G37*
G36*
G01X98843Y1396583D02*
G03I-491J0D01*
G37*
G36*
G01X94483D02*
G03I-491J0D01*
G37*
G36*
G01X86603D02*
G03I-491J0D01*
G37*
G36*
G01X98843Y1384297D02*
G03I-491J0D01*
G37*
G36*
G01X94483D02*
G03I-491J0D01*
G37*
G36*
G01X86603D02*
G03I-491J0D01*
G37*
G36*
G01X98843Y1408495D02*
G03I-491J0D01*
G37*
G36*
G01X94483D02*
G03I-491J0D01*
G37*
G36*
G01X86603D02*
G03I-491J0D01*
G37*
G36*
G01X111083Y1348187D02*
G03I-491J0D01*
G37*
G36*
G01X106723D02*
G03I-491J0D01*
G37*
G36*
G01X111083Y1360099D02*
G03I-491J0D01*
G37*
G36*
G01X106723D02*
G03I-491J0D01*
G37*
G36*
G01X111083Y1372385D02*
G03I-491J0D01*
G37*
G36*
G01X106723D02*
G03I-491J0D01*
G37*
G36*
G01X111083Y1396583D02*
G03I-491J0D01*
G37*
G36*
G01X106723D02*
G03I-491J0D01*
G37*
G36*
G01X111083Y1384297D02*
G03I-491J0D01*
G37*
G36*
G01X106723D02*
G03I-491J0D01*
G37*
G36*
G01X111083Y1408495D02*
G03I-491J0D01*
G37*
G36*
G01X106723D02*
G03I-491J0D01*
G37*
G36*
G01X116821Y1460782D02*
G03I-491J0D01*
G37*
G36*
G01X108160Y1456451D02*
G03I-491J0D01*
G37*
G36*
G01Y1461182D02*
G03I-491J0D01*
G37*
G36*
G01Y1465913D02*
G03I-491J0D01*
G37*
G36*
G01X116821Y1465513D02*
G03I-491J0D01*
G37*
G36*
G01Y1470244D02*
G03I-491J0D01*
G37*
G36*
G01X108160Y1471805D02*
G03I-491J0D01*
G37*
G36*
G01Y1481267D02*
G03I-491J0D01*
G37*
G36*
G01X116821Y1480867D02*
G03I-491J0D01*
G37*
G36*
G01X108160Y1476536D02*
G03I-491J0D01*
G37*
G36*
G01X116821Y1476136D02*
G03I-491J0D01*
G37*
G36*
G01Y1491491D02*
G03I-491J0D01*
G37*
G36*
G01Y1485598D02*
G03I-491J0D01*
G37*
G36*
G01X108160Y1487160D02*
G03I-491J0D01*
G37*
G36*
G01Y1496622D02*
G03I-491J0D01*
G37*
G36*
G01X116821Y1496222D02*
G03I-491J0D01*
G37*
G36*
G01X108160Y1491891D02*
G03I-491J0D01*
G37*
G36*
G01X116821Y1506845D02*
G03I-491J0D01*
G37*
G36*
G01Y1500953D02*
G03I-491J0D01*
G37*
G36*
G01X108160Y1502514D02*
G03I-491J0D01*
G37*
G36*
G01X116821Y1511576D02*
G03I-491J0D01*
G37*
G36*
G01X108160Y1511976D02*
G03I-491J0D01*
G37*
G36*
G01Y1507245D02*
G03I-491J0D01*
G37*
G36*
G01X116821Y1516307D02*
G03I-491J0D01*
G37*
G36*
G01X108160Y1558813D02*
G03I-491J0D01*
G37*
G36*
G01Y1563544D02*
G03I-491J0D01*
G37*
G36*
G01X116821Y1563144D02*
G03I-491J0D01*
G37*
G36*
G01X108160Y1568275D02*
G03I-491J0D01*
G37*
G36*
G01X116821Y1567875D02*
G03I-491J0D01*
G37*
G36*
G01Y1578498D02*
G03I-491J0D01*
G37*
G36*
G01Y1572606D02*
G03I-491J0D01*
G37*
G36*
G01X108160Y1574167D02*
G03I-491J0D01*
G37*
G36*
G01Y1578898D02*
G03I-491J0D01*
G37*
G36*
G01X116821Y1587960D02*
G03I-491J0D01*
G37*
G36*
G01X108160Y1589522D02*
G03I-491J0D01*
G37*
G36*
G01Y1583629D02*
G03I-491J0D01*
G37*
G36*
G01X116821Y1583229D02*
G03I-491J0D01*
G37*
G36*
G01X108160Y1594253D02*
G03I-491J0D01*
G37*
G36*
G01X116821Y1593853D02*
G03I-491J0D01*
G37*
G36*
G01Y1609207D02*
G03I-491J0D01*
G37*
G36*
G01X108160Y1598984D02*
G03I-491J0D01*
G37*
G36*
G01X116821Y1598584D02*
G03I-491J0D01*
G37*
G36*
G01Y1603315D02*
G03I-491J0D01*
G37*
G36*
G01X108160Y1604876D02*
G03I-491J0D01*
G37*
G36*
G01Y1609607D02*
G03I-491J0D01*
G37*
G36*
G01Y1614338D02*
G03I-491J0D01*
G37*
G36*
G01X116821Y1613938D02*
G03I-491J0D01*
G37*
G36*
G01Y1618669D02*
G03I-491J0D01*
G37*
G36*
G01X131203Y1348187D02*
G03I-491J0D01*
G37*
G36*
G01X123323D02*
G03I-491J0D01*
G37*
G36*
G01X118963D02*
G03I-491J0D01*
G37*
G36*
G01X131203Y1360099D02*
G03I-491J0D01*
G37*
G36*
G01X123323D02*
G03I-491J0D01*
G37*
G36*
G01X118963D02*
G03I-491J0D01*
G37*
G36*
G01X131203Y1372385D02*
G03I-491J0D01*
G37*
G36*
G01X123323D02*
G03I-491J0D01*
G37*
G36*
G01X118963D02*
G03I-491J0D01*
G37*
G36*
G01X131203Y1396583D02*
G03I-491J0D01*
G37*
G36*
G01X123323D02*
G03I-491J0D01*
G37*
G36*
G01X118963D02*
G03I-491J0D01*
G37*
G36*
G01X131203Y1384297D02*
G03I-491J0D01*
G37*
G36*
G01X123323D02*
G03I-491J0D01*
G37*
G36*
G01X118963D02*
G03I-491J0D01*
G37*
G36*
G01X131203Y1408495D02*
G03I-491J0D01*
G37*
G36*
G01X123323D02*
G03I-491J0D01*
G37*
G36*
G01X118963D02*
G03I-491J0D01*
G37*
G36*
G01X125483Y1456451D02*
G03I-491J0D01*
G37*
G36*
G01Y1461182D02*
G03I-491J0D01*
G37*
G36*
G01Y1471805D02*
G03I-491J0D01*
G37*
G36*
G01Y1476536D02*
G03I-491J0D01*
G37*
G36*
G01Y1481267D02*
G03I-491J0D01*
G37*
G36*
G01Y1465913D02*
G03I-491J0D01*
G37*
G36*
G01Y1487160D02*
G03I-491J0D01*
G37*
G36*
G01Y1491891D02*
G03I-491J0D01*
G37*
G36*
G01Y1496622D02*
G03I-491J0D01*
G37*
G36*
G01Y1507245D02*
G03I-491J0D01*
G37*
G36*
G01Y1502514D02*
G03I-491J0D01*
G37*
G36*
G01Y1511976D02*
G03I-491J0D01*
G37*
G36*
G01Y1558813D02*
G03I-491J0D01*
G37*
G36*
G01Y1578898D02*
G03I-491J0D01*
G37*
G36*
G01Y1563544D02*
G03I-491J0D01*
G37*
G36*
G01Y1568275D02*
G03I-491J0D01*
G37*
G36*
G01Y1574167D02*
G03I-491J0D01*
G37*
G36*
G01Y1583629D02*
G03I-491J0D01*
G37*
G36*
G01Y1589522D02*
G03I-491J0D01*
G37*
G36*
G01Y1594253D02*
G03I-491J0D01*
G37*
G36*
G01Y1609607D02*
G03I-491J0D01*
G37*
G36*
G01Y1604876D02*
G03I-491J0D01*
G37*
G36*
G01Y1598984D02*
G03I-491J0D01*
G37*
G36*
G01Y1614338D02*
G03I-491J0D01*
G37*
G36*
G01X184942Y174205D02*
X188494D01*
G02X188634Y174148I0J-200D01*
G01X188635Y174147D01*
X190837Y171945D01*
G02X190839Y171943I-140J-142D01*
G02X190896Y171803I-143J-140D01*
G01Y147990D01*
G02X190786Y147811I-200J0D01*
G01X190468Y147650D01*
G02X190258Y147668I-90J178D01*
G03X189364Y147963I-894J-1207D01*
G03Y144959I0J-1502D01*
G03X190258Y145254I0J1502D01*
G02X190468Y145272I120J-160D01*
G01X190786Y145111D01*
G02X190896Y144932I-90J-179D01*
G01Y138227D01*
X190823Y138124D01*
X190763Y138103D01*
G03X190062Y137587I502J-1416D01*
G01X190041Y137559D01*
X189954Y137501D01*
G02X189887Y137473I-109J168D01*
G01X189768Y137446D01*
X189694Y137457D01*
X189661Y137475D01*
G03X189360Y137612I-894J-1565D01*
G03X188769Y137712I-592J-1703D01*
G03X188178Y137612I1J-1803D01*
G03X187877Y137475I593J-1702D01*
G01X187844Y137457D01*
X187770Y137446D01*
X187651Y137473D01*
G02X187584Y137501I42J196D01*
G01X187496Y137560D01*
X187476Y137588D01*
G03X186273Y138189I-1202J-901D01*
G01X186230D01*
X186229Y138188D01*
G03X184771Y136687I44J-1501D01*
G03X186273Y135185I1502J0D01*
G03X186505Y135203I0J1502D01*
G01X186548Y135210D01*
X186632Y135186D01*
X186930Y134932D01*
X186966Y134853D01*
Y133610D01*
Y133565D01*
X186930Y133486D01*
X186632Y133232D01*
X186548Y133208D01*
X186505Y133215D01*
G03X186270Y133233I-232J-1484D01*
G01X186269D01*
G03X184771Y131731I4J-1502D01*
G03X186273Y130229I1502J0D01*
G01X186274D01*
G03X187476Y130830I0J1502D01*
G01X187496Y130858D01*
X187584Y130917D01*
G02X187651Y130945I109J-168D01*
G01X187770Y130972D01*
X187844Y130961D01*
X187877Y130943D01*
G03X188178Y130806I894J1565D01*
G03X188769Y130706I592J1703D01*
G03X189360Y130806I-1J1803D01*
G03X189661Y130943I-593J1702D01*
G01X189694Y130961D01*
X189768Y130972D01*
X189887Y130945D01*
G02X189954Y130917I-42J-196D01*
G01X190041Y130859D01*
X190062Y130831D01*
G03X190763Y130315I1203J900D01*
G01X190823Y130294D01*
X190896Y130191D01*
Y124053D01*
X190823Y123950D01*
X190763Y123929D01*
G03X190062Y123413I502J-1416D01*
G01X190041Y123385D01*
X189954Y123327D01*
G02X189887Y123299I-109J168D01*
G01X189768Y123272D01*
X189694Y123283D01*
X189661Y123301D01*
G03X189360Y123438I-894J-1565D01*
G03X188769Y123538I-592J-1703D01*
G03X188178Y123438I1J-1803D01*
G03X187877Y123301I593J-1702D01*
G01X187844Y123283D01*
X187770Y123272D01*
X187651Y123299D01*
G02X187584Y123327I42J196D01*
G01X187496Y123386D01*
X187476Y123414D01*
G03X186273Y124015I-1202J-901D01*
G01X186230D01*
X186229Y124014D01*
G03X184771Y122513I44J-1501D01*
G03X186273Y121011I1502J0D01*
G03X186505Y121029I0J1502D01*
G01X186548Y121036D01*
X186632Y121012D01*
X186930Y120758D01*
X186966Y120679D01*
Y119436D01*
Y119391D01*
X186930Y119312D01*
X186632Y119058D01*
X186548Y119034D01*
X186505Y119041D01*
G03X186270Y119059I-232J-1484D01*
G01X186269D01*
G03X184771Y117557I4J-1502D01*
G03X186273Y116055I1502J0D01*
G01X186274D01*
G03X187476Y116656I0J1502D01*
G01X187496Y116684D01*
X187584Y116743D01*
G02X187651Y116771I109J-168D01*
G01X187770Y116798D01*
X187844Y116787D01*
X187877Y116769D01*
G03X188178Y116632I894J1565D01*
G03X188769Y116532I592J1703D01*
G03X189360Y116632I-1J1803D01*
G03X189661Y116769I-593J1702D01*
G01X189694Y116787D01*
X189768Y116798D01*
X189887Y116771D01*
G02X189954Y116743I-42J-196D01*
G01X190041Y116685D01*
X190062Y116657D01*
G03X190763Y116141I1203J900D01*
G01X190823Y116120D01*
X190896Y116017D01*
Y78102D01*
G02X190870Y78003I-200J0D01*
G01X190810Y77899D01*
X190778Y77865D01*
X190757Y77851D01*
G03X190319Y77421I811J-1264D01*
G01X190318Y77420D01*
Y77419D01*
G02X190184Y77334I-165J113D01*
G01X189895Y77288D01*
G02X189741Y77327I-32J197D01*
G03X188820Y77642I-920J-1187D01*
G01X188790D01*
G03X187318Y76140I30J-1502D01*
G03X188820Y74638I1502J0D01*
G01X188836D01*
X188896Y74639D01*
X188999Y74572D01*
X189166Y74174D01*
G02X189123Y73955I-184J-78D01*
G01X187669Y72501D01*
X187641Y72472D01*
X187567Y72442D01*
X141454D01*
G02X141312Y72501I0J200D01*
G01X139996Y73817D01*
X139967Y73845D01*
X139937Y73919D01*
Y100401D01*
G02X139941Y100441I200J0D01*
G01X139952Y100498D01*
X139968Y100535D01*
X140198Y100763D01*
G02X140339Y100821I141J-142D01*
G01X140350D01*
G03Y103825I0J1502D01*
G01X140339D01*
G02X140198Y103883I0J200D01*
G01X139996Y104083D01*
G02X139937Y104225I141J142D01*
G01Y107488D01*
G02X139941Y107528I200J0D01*
G01X139952Y107585D01*
X139968Y107622D01*
X140198Y107850D01*
G02X140339Y107908I141J-142D01*
G01X140350D01*
G03Y110912I0J1502D01*
G01X140339D01*
G02X140198Y110970I0J200D01*
G01X139996Y111170D01*
G02X139937Y111312I141J142D01*
G01Y114574D01*
G02X139941Y114614I200J0D01*
G01X139952Y114671D01*
X139968Y114708D01*
X140198Y114936D01*
G02X140339Y114994I141J-142D01*
G01X140350D01*
G03Y117998I0J1502D01*
G01X140339D01*
G02X140198Y118056I0J200D01*
G01X139996Y118256D01*
G02X139937Y118398I141J142D01*
G01Y121661D01*
G02X139941Y121701I200J0D01*
G01X139952Y121758D01*
X139968Y121795D01*
X140198Y122023D01*
G02X140339Y122081I141J-142D01*
G01X140350D01*
G03Y125085I0J1502D01*
G01X140339D01*
G02X140198Y125143I0J200D01*
G01X139996Y125343D01*
G02X139937Y125485I141J142D01*
G01Y128748D01*
G02X139941Y128788I200J0D01*
G01X139952Y128845D01*
X139968Y128882D01*
X140198Y129110D01*
G02X140339Y129168I141J-142D01*
G01X140350D01*
G03Y132172I0J1502D01*
G01X140339D01*
G02X140198Y132230I0J200D01*
G01X139996Y132430D01*
G02X139937Y132572I141J142D01*
G01Y135834D01*
G02X139941Y135874I200J0D01*
G01X139952Y135931D01*
X139968Y135968D01*
X140198Y136196D01*
G02X140339Y136254I141J-142D01*
G01X140350D01*
G03Y139258I0J1502D01*
G01X140339D01*
G02X140198Y139316I0J200D01*
G01X139996Y139516D01*
G02X139937Y139658I141J142D01*
G01Y172123D01*
G02X139994Y172263I200J0D01*
G01X139995Y172264D01*
X141877Y174146D01*
G02X141879Y174148I142J-140D01*
G02X142019Y174205I140J-143D01*
G01X181948D01*
G02X182134Y174078I0J-200D01*
G01X182293Y173673D01*
X182266Y173554D01*
X182220Y173512D01*
G03X181643Y172190I1226J-1322D01*
G03X185247I1802J0D01*
G03X184670Y173512I-1803J0D01*
G01X184624Y173554D01*
X184597Y173673D01*
X184756Y174078D01*
G02X184942Y174205I186J-73D01*
G37*
G36*
G01X149124Y1046476D02*
G03I-590J0D01*
G37*
G36*
G01X147803Y1348187D02*
G03I-491J0D01*
G37*
G36*
G01X143443D02*
G03I-491J0D01*
G37*
G36*
G01X135563D02*
G03I-491J0D01*
G37*
G36*
G01X147803Y1360099D02*
G03I-491J0D01*
G37*
G36*
G01X143443D02*
G03I-491J0D01*
G37*
G36*
G01X135563D02*
G03I-491J0D01*
G37*
G36*
G01X147803Y1372385D02*
G03I-491J0D01*
G37*
G36*
G01X143443D02*
G03I-491J0D01*
G37*
G36*
G01X135563D02*
G03I-491J0D01*
G37*
G36*
G01X147803Y1396583D02*
G03I-491J0D01*
G37*
G36*
G01Y1384297D02*
G03I-491J0D01*
G37*
G36*
G01X143443D02*
G03I-491J0D01*
G37*
G36*
G01X135563D02*
G03I-491J0D01*
G37*
G36*
G01X143443Y1396583D02*
G03I-491J0D01*
G37*
G36*
G01X135563D02*
G03I-491J0D01*
G37*
G36*
G01X147803Y1408495D02*
G03I-491J0D01*
G37*
G36*
G01X143443D02*
G03I-491J0D01*
G37*
G36*
G01X135563D02*
G03I-491J0D01*
G37*
G36*
G01X142806Y1456451D02*
G03I-491J0D01*
G37*
G36*
G01Y1461182D02*
G03I-491J0D01*
G37*
G36*
G01X134144Y1460782D02*
G03I-491J0D01*
G37*
G36*
G01X142806Y1471805D02*
G03I-491J0D01*
G37*
G36*
G01Y1476536D02*
G03I-491J0D01*
G37*
G36*
G01Y1481267D02*
G03I-491J0D01*
G37*
G36*
G01X134144Y1465513D02*
G03I-491J0D01*
G37*
G36*
G01Y1476136D02*
G03I-491J0D01*
G37*
G36*
G01Y1470244D02*
G03I-491J0D01*
G37*
G36*
G01Y1480867D02*
G03I-491J0D01*
G37*
G36*
G01X142806Y1465913D02*
G03I-491J0D01*
G37*
G36*
G01Y1487160D02*
G03I-491J0D01*
G37*
G36*
G01Y1491891D02*
G03I-491J0D01*
G37*
G36*
G01Y1496622D02*
G03I-491J0D01*
G37*
G36*
G01X134144Y1491491D02*
G03I-491J0D01*
G37*
G36*
G01Y1485598D02*
G03I-491J0D01*
G37*
G36*
G01Y1496222D02*
G03I-491J0D01*
G37*
G36*
G01X142806Y1507245D02*
G03I-491J0D01*
G37*
G36*
G01Y1502514D02*
G03I-491J0D01*
G37*
G36*
G01Y1511976D02*
G03I-491J0D01*
G37*
G36*
G01X134144Y1506845D02*
G03I-491J0D01*
G37*
G36*
G01Y1500953D02*
G03I-491J0D01*
G37*
G36*
G01Y1511576D02*
G03I-491J0D01*
G37*
G36*
G01Y1516307D02*
G03I-491J0D01*
G37*
G36*
G01X142806Y1558813D02*
G03I-491J0D01*
G37*
G36*
G01X134144Y1567875D02*
G03I-491J0D01*
G37*
G36*
G01Y1578498D02*
G03I-491J0D01*
G37*
G36*
G01Y1572606D02*
G03I-491J0D01*
G37*
G36*
G01X142806Y1563544D02*
G03I-491J0D01*
G37*
G36*
G01Y1568275D02*
G03I-491J0D01*
G37*
G36*
G01Y1578898D02*
G03I-491J0D01*
G37*
G36*
G01Y1574167D02*
G03I-491J0D01*
G37*
G36*
G01X134144Y1563144D02*
G03I-491J0D01*
G37*
G36*
G01X142806Y1594253D02*
G03I-491J0D01*
G37*
G36*
G01Y1583629D02*
G03I-491J0D01*
G37*
G36*
G01X134144Y1583229D02*
G03I-491J0D01*
G37*
G36*
G01Y1593853D02*
G03I-491J0D01*
G37*
G36*
G01Y1587960D02*
G03I-491J0D01*
G37*
G36*
G01X142806Y1589522D02*
G03I-491J0D01*
G37*
G36*
G01Y1609607D02*
G03I-491J0D01*
G37*
G36*
G01Y1604876D02*
G03I-491J0D01*
G37*
G36*
G01Y1598984D02*
G03I-491J0D01*
G37*
G36*
G01X134144Y1609207D02*
G03I-491J0D01*
G37*
G36*
G01Y1598584D02*
G03I-491J0D01*
G37*
G36*
G01Y1603315D02*
G03I-491J0D01*
G37*
G36*
G01X142806Y1614338D02*
G03I-491J0D01*
G37*
G36*
G01X134144Y1613938D02*
G03I-491J0D01*
G37*
G36*
G01Y1618669D02*
G03I-491J0D01*
G37*
G36*
G01X164618Y1041468D02*
G03I-590J0D01*
G37*
G36*
G01X156103Y1065148D02*
G03I-590J0D01*
G37*
G36*
G01X175733Y1167797D02*
X177646D01*
G02X177679Y1167794I-2J-200D01*
G02X177786Y1167740I-32J-197D01*
G01X178296Y1167230D01*
G02X178355Y1167088I-141J-142D01*
G01Y1147528D01*
G03X178414Y1147386I200J0D01*
G01X179341Y1146459D01*
G03X179483Y1146400I142J141D01*
G01X184817D01*
G02X184957Y1146343I0J-200D01*
G01X184958Y1146342D01*
X185480Y1145820D01*
G02X185482Y1145818I-140J-142D01*
G02X185539Y1145678I-143J-140D01*
G01Y1142043D01*
G02X185439Y1141870I-200J0D01*
G01X185143Y1141698D01*
X185036D01*
X184989Y1141726D01*
G03X184351Y1141901I-638J-1077D01*
G01X184350D01*
G03Y1139397I0J-1252D01*
G01X184351D01*
G03X184989Y1139572I0J1252D01*
G01X185036Y1139600D01*
X185143D01*
X185439Y1139429D01*
G02X185513Y1139353I-101J-173D01*
G01X185514Y1139352D01*
G02X185539Y1139255I-175J-97D01*
G01Y1138303D01*
G02X185439Y1138130I-200J0D01*
G01X185143Y1137958D01*
X185036D01*
X184989Y1137986D01*
G03X184351Y1138161I-638J-1077D01*
G01X184350D01*
G03X183098Y1136909I0J-1252D01*
G03X183705Y1135836I1252J0D01*
G02X183802Y1135665I-103J-171D01*
G01Y1134413D01*
G02X183705Y1134242I-200J0D01*
G03X183098Y1133169I645J-1073D01*
G03X184350Y1131917I1252J0D01*
G01X184351D01*
G03X184989Y1132092I0J1252D01*
G01X185036Y1132120D01*
X185143D01*
X185439Y1131949D01*
G02X185513Y1131873I-101J-173D01*
G01X185514Y1131872D01*
G02X185539Y1131775I-175J-97D01*
G01Y1130823D01*
G02X185439Y1130650I-200J0D01*
G01X185143Y1130478D01*
X185036D01*
X184989Y1130506D01*
G03X184351Y1130681I-638J-1077D01*
G01X184350D01*
G03Y1128177I0J-1252D01*
G01X184351D01*
G03X184989Y1128352I0J1252D01*
G01X185036Y1128380D01*
X185143D01*
X185439Y1128209D01*
G02X185513Y1128133I-101J-173D01*
G01X185514Y1128132D01*
G02X185539Y1128035I-175J-97D01*
G01Y1127082D01*
G02X185439Y1126909I-200J0D01*
G01X185143Y1126737D01*
X185036D01*
X184989Y1126765D01*
G03X184351Y1126940I-638J-1077D01*
G01X184350D01*
G03Y1124436I0J-1252D01*
G01X184351D01*
G03X184989Y1124611I0J1252D01*
G01X185036Y1124639D01*
X185143D01*
X185439Y1124468D01*
G02X185513Y1124392I-101J-173D01*
G01X185514Y1124391D01*
G02X185539Y1124294I-175J-97D01*
G01Y1123537D01*
G03X185598Y1123395I200J0D01*
G01X185711Y1123282D01*
G02X185713Y1123280I-140J-142D01*
G02X185770Y1123140I-143J-140D01*
G01Y1122735D01*
G02X185627Y1122543I-200J0D01*
G01X185563Y1122524D01*
X185439Y1122570D01*
X185402Y1122627D01*
G03X184350Y1123200I-1052J-679D01*
G03Y1120696I0J-1252D01*
G03X185123Y1120963I0J1252D01*
G02X185334Y1120985I123J-157D01*
G01X185658Y1120828D01*
G02X185770Y1120648I-88J-180D01*
G01Y1119508D01*
G02X185658Y1119328I-200J0D01*
G01X185334Y1119171D01*
G02X185123Y1119193I-88J179D01*
G03X184350Y1119460I-773J-985D01*
G03Y1116956I0J-1252D01*
G03X185402Y1117529I0J1252D01*
G01X185403Y1117530D01*
G02X185627Y1117613I168J-109D01*
G01X185691Y1117593D01*
X185770Y1117488D01*
Y1117158D01*
G02X185711Y1117016I-200J0D01*
G01X184446Y1115751D01*
X184374Y1115720D01*
X184335D01*
G03X183136Y1114775I15J-1252D01*
G02X182942Y1114624I-194J49D01*
G01X182018D01*
G02X181824Y1114775I0J200D01*
G03X179396I-1214J-307D01*
G02X179202Y1114624I-194J49D01*
G01X178278D01*
G02X178084Y1114775I0J200D01*
G03X175656I-1214J-307D01*
G02X175462Y1114624I-194J49D01*
G01X170788D01*
G02X170712Y1114639I0J200D01*
G01X170686Y1114650D01*
G03X170610Y1114665I-76J-185D01*
G01X167046D01*
G02X166925Y1114706I0J200D01*
G01X166898Y1114726D01*
X166862Y1114779D01*
X166853Y1114811D01*
G03X164445I-1204J-342D01*
G01X164436Y1114779D01*
X164400Y1114726D01*
X164373Y1114706D01*
G02X164252Y1114665I-121J159D01*
G01X163306D01*
G02X163185Y1114706I0J200D01*
G01X163158Y1114726D01*
X163122Y1114779D01*
X163113Y1114811D01*
G03X161909Y1115720I-1204J-343D01*
G03X160984Y1115312I0J-1253D01*
G01X160981Y1115308D01*
X160978Y1115305D01*
G02X160695I-141J142D01*
G01X160559Y1115441D01*
X160530Y1115469D01*
X160500Y1115543D01*
Y1122350D01*
G02X160557Y1122490I200J0D01*
G01X160558Y1122491D01*
X160964Y1122897D01*
G02X161123Y1122955I142J-141D01*
G01X161126D01*
G03X161246Y1122948I130J1195D01*
G01X167633D01*
G03X167888Y1122976I-3J1202D01*
G01X167910Y1122981D01*
X167983D01*
X168011Y1123009D01*
X168052Y1123025D01*
G03X168087Y1123039I-429J1122D01*
G02X168319Y1122978I75J-185D01*
G01X168366Y1122919D01*
G02X168372Y1122678I-157J-124D01*
G03X168137Y1121948I1016J-730D01*
G03X169389Y1123200I1252J0D01*
G03X169213Y1123187I4J-1252D01*
G01X169211D01*
X169158Y1123180D01*
X169109Y1123200D01*
G02X169026Y1123262I74J186D01*
G01X168779Y1123579D01*
X168764Y1123685D01*
X168785Y1123735D01*
G03X168798Y1123771I-1123J426D01*
G01X168799Y1123772D01*
X168815Y1123813D01*
X168943Y1123941D01*
G03X169002Y1124083I-141J142D01*
G01Y1127726D01*
G02X169060Y1127867I200J0D01*
G01X169287Y1128096D01*
X169358Y1128126D01*
X169399D01*
G03X170691Y1129428I-10J1302D01*
G03X170477Y1130143I-1301J0D01*
G01X170460Y1130168D01*
X170444Y1130223D01*
Y1130621D01*
G03X170385Y1130763I-200J0D01*
G01X169773Y1131375D01*
G02X169718Y1131553I142J141D01*
G01X169779Y1131878D01*
G02X169892Y1132023I197J-37D01*
G01X169894Y1132024D01*
G03X170641Y1133169I-504J1145D01*
G03X168137I-1252J0D01*
G03X168311Y1132532I1253J0D01*
G02X168313Y1132331I-172J-102D01*
G01X168141Y1132029D01*
G02X167967Y1131928I-174J99D01*
G01X167131D01*
G02X166958Y1132027I0J200D01*
G01X166783Y1132325D01*
G02X166781Y1132523I173J101D01*
G01X166782Y1132525D01*
X166783Y1132526D01*
G03X166952Y1133167I-1134J642D01*
G03X165649Y1134470I-1303J0D01*
G01X162644D01*
G02X162444Y1134670I0J200D01*
G01Y1136060D01*
G02X162501Y1136200I200J0D01*
G01X162502Y1136201D01*
X162818Y1136517D01*
G02X162820Y1136519I142J-140D01*
G02X162960Y1136576I140J-143D01*
G01X164360D01*
X164461Y1136507D01*
X164484Y1136449D01*
G03X166814I1165J461D01*
G01X166837Y1136507D01*
X166938Y1136576D01*
X167984D01*
G02X168170Y1136449I0J-200D01*
G01X168171Y1136447D01*
Y1136446D01*
G03X169389Y1135604I1218J461D01*
G01X173129D01*
G03Y1138210I0J1303D01*
G01X170644D01*
G02X170444Y1138410I0J200D01*
G01Y1139824D01*
G02X170477Y1139934I200J0D01*
G03Y1141364I-1087J715D01*
G02X170444Y1141474I167J110D01*
G01Y1143564D01*
G02X170477Y1143674I200J0D01*
G03Y1145104I-1087J715D01*
G01X170460Y1145129D01*
X170444Y1145184D01*
Y1145307D01*
G02X170503Y1145449I200J0D01*
G01X171646Y1146592D01*
G02X171788Y1146651I142J-141D01*
G01X171857D01*
G03X171876Y1146650I73J1199D01*
G01X174024D01*
G03X174043Y1146651I-54J1200D01*
G01X174628D01*
G03X174770Y1146710I0J200D01*
G01X175391Y1147331D01*
G03X175450Y1147473I-141J142D01*
G01Y1167514D01*
G02X175509Y1167656I200J0D01*
G01X175591Y1167738D01*
G02X175733Y1167797I142J-141D01*
G37*
G36*
G01X161648Y1130635D02*
X167520D01*
G02X167662Y1130576I0J-200D01*
G01X167815Y1130423D01*
G02X167874Y1130281I-141J-142D01*
G01Y1124193D01*
G02X167815Y1124051I-200J0D01*
G01X167773Y1124009D01*
G02X167632Y1123950I-142J141D01*
G01X161247D01*
G02X161106Y1124009I1J200D01*
G01X160903Y1124212D01*
G02X160844Y1124354I141J142D01*
G01Y1129831D01*
G02X160903Y1129973I200J0D01*
G01X161506Y1130576D01*
G02X161648Y1130635I142J-141D01*
G37*
G36*
G01X160043Y1348187D02*
G03I-491J0D01*
G37*
G36*
G01X155683D02*
G03I-491J0D01*
G37*
G36*
G01X160043Y1360099D02*
G03I-491J0D01*
G37*
G36*
G01X155683D02*
G03I-491J0D01*
G37*
G36*
G01X160043Y1372385D02*
G03I-491J0D01*
G37*
G36*
G01X155683D02*
G03I-491J0D01*
G37*
G36*
G01X160043Y1384297D02*
G03I-491J0D01*
G37*
G36*
G01Y1396583D02*
G03I-491J0D01*
G37*
G36*
G01X155683D02*
G03I-491J0D01*
G37*
G36*
G01Y1384297D02*
G03I-491J0D01*
G37*
G36*
G01X160043Y1408495D02*
G03I-491J0D01*
G37*
G36*
G01X155683D02*
G03I-491J0D01*
G37*
G36*
G01X160128Y1461182D02*
G03I-491J0D01*
G37*
G36*
G01X151467Y1460782D02*
G03I-491J0D01*
G37*
G36*
G01X160128Y1456451D02*
G03I-491J0D01*
G37*
G36*
G01X151467Y1470244D02*
G03I-491J0D01*
G37*
G36*
G01Y1480867D02*
G03I-491J0D01*
G37*
G36*
G01X160128Y1471805D02*
G03I-491J0D01*
G37*
G36*
G01Y1476536D02*
G03I-491J0D01*
G37*
G36*
G01Y1481267D02*
G03I-491J0D01*
G37*
G36*
G01X151467Y1465513D02*
G03I-491J0D01*
G37*
G36*
G01X160128Y1465913D02*
G03I-491J0D01*
G37*
G36*
G01X151467Y1476136D02*
G03I-491J0D01*
G37*
G36*
G01X160128Y1487160D02*
G03I-491J0D01*
G37*
G36*
G01Y1491891D02*
G03I-491J0D01*
G37*
G36*
G01Y1496622D02*
G03I-491J0D01*
G37*
G36*
G01X151467Y1491491D02*
G03I-491J0D01*
G37*
G36*
G01Y1485598D02*
G03I-491J0D01*
G37*
G36*
G01Y1496222D02*
G03I-491J0D01*
G37*
G36*
G01Y1506845D02*
G03I-491J0D01*
G37*
G36*
G01Y1500953D02*
G03I-491J0D01*
G37*
G36*
G01Y1511576D02*
G03I-491J0D01*
G37*
G36*
G01X160128Y1507245D02*
G03I-491J0D01*
G37*
G36*
G01Y1502514D02*
G03I-491J0D01*
G37*
G36*
G01Y1511976D02*
G03I-491J0D01*
G37*
G36*
G01X151467Y1516307D02*
G03I-491J0D01*
G37*
G36*
G01X160128Y1558813D02*
G03I-491J0D01*
G37*
G36*
G01Y1578898D02*
G03I-491J0D01*
G37*
G36*
G01X151467Y1563144D02*
G03I-491J0D01*
G37*
G36*
G01X160128Y1563544D02*
G03I-491J0D01*
G37*
G36*
G01X151467Y1567875D02*
G03I-491J0D01*
G37*
G36*
G01Y1578498D02*
G03I-491J0D01*
G37*
G36*
G01Y1572606D02*
G03I-491J0D01*
G37*
G36*
G01X160128Y1568275D02*
G03I-491J0D01*
G37*
G36*
G01Y1574167D02*
G03I-491J0D01*
G37*
G36*
G01Y1589522D02*
G03I-491J0D01*
G37*
G36*
G01Y1594253D02*
G03I-491J0D01*
G37*
G36*
G01X151467Y1583229D02*
G03I-491J0D01*
G37*
G36*
G01Y1593853D02*
G03I-491J0D01*
G37*
G36*
G01Y1587960D02*
G03I-491J0D01*
G37*
G36*
G01X160128Y1583629D02*
G03I-491J0D01*
G37*
G36*
G01X151467Y1609207D02*
G03I-491J0D01*
G37*
G36*
G01Y1598584D02*
G03I-491J0D01*
G37*
G36*
G01Y1603315D02*
G03I-491J0D01*
G37*
G36*
G01X160128Y1609607D02*
G03I-491J0D01*
G37*
G36*
G01Y1604876D02*
G03I-491J0D01*
G37*
G36*
G01Y1598984D02*
G03I-491J0D01*
G37*
G36*
G01Y1614338D02*
G03I-491J0D01*
G37*
G36*
G01X151467Y1613938D02*
G03I-491J0D01*
G37*
G36*
G01Y1618669D02*
G03I-491J0D01*
G37*
G36*
G01X240020Y54588D02*
X268877D01*
X269414Y54051D01*
Y53128D01*
X268877Y52591D01*
X240020D01*
G03X234083Y46654I0J-5937D01*
G01Y7874D01*
G02X228209Y2000I-5874J0D01*
G01X180965D01*
G02X175091Y7874I0J5874D01*
G01Y46167D01*
X177088D01*
Y7874D01*
G03X180963Y3998I3876J0D01*
G01X228209D01*
G03X232086Y7874I0J3877D01*
G01Y46654D01*
G02X240020Y54588I7934J0D01*
G37*
G36*
G01X181050Y576249D02*
X184842D01*
X186283D01*
X187522D01*
X188381Y575390D01*
Y549500D01*
X187881Y549000D01*
X182521D01*
X182021Y549500D01*
Y559538D01*
X181001Y560558D01*
Y576200D01*
X181050Y576249D01*
G37*
G36*
G01X171833Y1167697D02*
X174067D01*
G02X174209Y1167638I0J-200D01*
G01X174390Y1167457D01*
G02X174448Y1167316I-142J-141D01*
G01Y1148078D01*
G02X174390Y1147937I-200J0D01*
G01X174164Y1147711D01*
G02X174023Y1147652I-142J141D01*
G01X171877D01*
G02X171736Y1147711I1J200D01*
G01X171209Y1148238D01*
G02X171150Y1148380I141J142D01*
G01Y1155227D01*
X171154Y1155247D01*
G03X171191Y1155610I-1765J363D01*
G03X171154Y1155973I-1802J0D01*
G01X171150Y1155993D01*
Y1167014D01*
G02X171209Y1167156I200J0D01*
G01X171691Y1167638D01*
G02X171833Y1167697I142J-141D01*
G37*
G36*
G01X185239Y1192000D02*
X186217D01*
G02X186359Y1191941I0J-200D01*
G01X186841Y1191459D01*
G02X186900Y1191317I-141J-142D01*
G01Y1187283D01*
G02X186841Y1187141I-200J0D01*
G01X186759Y1187059D01*
G02X186617Y1187000I-142J141D01*
G01X183283D01*
G03X183141Y1186941I0J-200D01*
G01X182259Y1186059D01*
G03X182200Y1185917I141J-142D01*
G01Y1176483D01*
G03X182259Y1176341I200J0D01*
G01X183641Y1174959D01*
G02X183700Y1174817I-141J-142D01*
G01Y1173083D01*
G02X183641Y1172941I-200J0D01*
G01X182159Y1171459D01*
G03X182100Y1171317I141J-142D01*
G01Y1150583D01*
G03X182159Y1150441I200J0D01*
G01X183541Y1149059D01*
G02X183600Y1148917I-141J-142D01*
G01Y1147602D01*
G02X183400Y1147402I-200J0D01*
G01X180081D01*
G02X179940Y1147460I0J200D01*
G01X179415Y1147985D01*
G02X179356Y1148126I141J142D01*
G01Y1167089D01*
G03X179308Y1167426I-1201J1D01*
G01X179300Y1167453D01*
Y1171854D01*
X179312Y1171888D01*
G03X179388Y1172305I-1126J421D01*
G01Y1182779D01*
G03X179312Y1183196I-1202J-4D01*
G01X179300Y1183230D01*
Y1186105D01*
G02X179399Y1186278I200J0D01*
G03Y1188524I-659J1123D01*
G02X179300Y1188697I101J173D01*
G01Y1189517D01*
G02X179359Y1189659I200J0D01*
G01X181641Y1191941D01*
G02X181783Y1192000I142J-141D01*
G01X183461D01*
G02X183580Y1191961I0J-200D01*
G03X185120I770J1050D01*
G02X185239Y1192000I119J-161D01*
G37*
G36*
G01X171733Y1182697D02*
X174067D01*
G02X174209Y1182638I0J-200D01*
G01X174390Y1182457D01*
G02X174448Y1182316I-142J-141D01*
G01Y1171465D01*
G03X174507Y1171324I200J1D01*
G01X174520Y1171311D01*
X174550Y1171238D01*
Y1170480D01*
G02X174491Y1170338I-200J0D01*
G01X173909Y1169756D01*
G02X173767Y1169697I-142J141D01*
G01X171933D01*
G02X171791Y1169756I0J200D01*
G01X171409Y1170138D01*
G02X171350Y1170280I141J142D01*
G01Y1182314D01*
G02X171409Y1182456I200J0D01*
G01X171591Y1182638D01*
G02X171733Y1182697I142J-141D01*
G37*
G36*
G01X175733Y1183097D02*
X178067D01*
G02X178209Y1183038I0J-200D01*
G01X178327Y1182920D01*
G02X178386Y1182778I-141J-142D01*
G01Y1172306D01*
G02X178327Y1172164I-200J0D01*
G01X177819Y1171656D01*
G02X177677Y1171597I-142J141D01*
G01X177670D01*
G03X176870Y1171872I-800J-1026D01*
G03X176119Y1171634I-1J-1302D01*
G01X176093Y1171615D01*
X176035Y1171597D01*
X175733D01*
G02X175591Y1171656I0J200D01*
G01X175509Y1171738D01*
G02X175450Y1171880I141J142D01*
G01Y1182814D01*
G02X175509Y1182956I200J0D01*
G01X175591Y1183038D01*
G02X175733Y1183097I142J-141D01*
G37*
G36*
G01X180163Y1348187D02*
G03I-491J0D01*
G37*
G36*
G01X172283D02*
G03I-491J0D01*
G37*
G36*
G01X167923D02*
G03I-491J0D01*
G37*
G36*
G01X180163Y1360099D02*
G03I-491J0D01*
G37*
G36*
G01X172283D02*
G03I-491J0D01*
G37*
G36*
G01X167923D02*
G03I-491J0D01*
G37*
G36*
G01X180163Y1372385D02*
G03I-491J0D01*
G37*
G36*
G01X172283D02*
G03I-491J0D01*
G37*
G36*
G01X167923D02*
G03I-491J0D01*
G37*
G36*
G01X180163Y1396583D02*
G03I-491J0D01*
G37*
G36*
G01X172283D02*
G03I-491J0D01*
G37*
G36*
G01X180163Y1384297D02*
G03I-491J0D01*
G37*
G36*
G01X172283D02*
G03I-491J0D01*
G37*
G36*
G01X167923D02*
G03I-491J0D01*
G37*
G36*
G01Y1396583D02*
G03I-491J0D01*
G37*
G36*
G01X180163Y1408495D02*
G03I-491J0D01*
G37*
G36*
G01X172283D02*
G03I-491J0D01*
G37*
G36*
G01X167923D02*
G03I-491J0D01*
G37*
G36*
G01X168790Y1460782D02*
G03I-491J0D01*
G37*
G36*
G01X177451Y1456452D02*
G03I-491J0D01*
G37*
G36*
G01Y1461183D02*
G03I-491J0D01*
G37*
G36*
G01X168790Y1480867D02*
G03I-491J0D01*
G37*
G36*
G01X177451Y1476537D02*
G03I-491J0D01*
G37*
G36*
G01Y1471806D02*
G03I-491J0D01*
G37*
G36*
G01Y1481268D02*
G03I-491J0D01*
G37*
G36*
G01X168790Y1465513D02*
G03I-491J0D01*
G37*
G36*
G01X177451Y1465914D02*
G03I-491J0D01*
G37*
G36*
G01X168790Y1476136D02*
G03I-491J0D01*
G37*
G36*
G01Y1470244D02*
G03I-491J0D01*
G37*
G36*
G01Y1491491D02*
G03I-491J0D01*
G37*
G36*
G01Y1485598D02*
G03I-491J0D01*
G37*
G36*
G01Y1496222D02*
G03I-491J0D01*
G37*
G36*
G01X177451Y1491891D02*
G03I-491J0D01*
G37*
G36*
G01Y1487160D02*
G03I-491J0D01*
G37*
G36*
G01Y1496622D02*
G03I-491J0D01*
G37*
G36*
G01Y1507246D02*
G03I-491J0D01*
G37*
G36*
G01Y1502515D02*
G03I-491J0D01*
G37*
G36*
G01X168790Y1506845D02*
G03I-491J0D01*
G37*
G36*
G01Y1500953D02*
G03I-491J0D01*
G37*
G36*
G01Y1511576D02*
G03I-491J0D01*
G37*
G36*
G01Y1516307D02*
G03I-491J0D01*
G37*
G36*
G01X177451Y1558813D02*
G03I-491J0D01*
G37*
G36*
G01Y1568275D02*
G03I-491J0D01*
G37*
G36*
G01X168790Y1578498D02*
G03I-491J0D01*
G37*
G36*
G01Y1572606D02*
G03I-491J0D01*
G37*
G36*
G01Y1567875D02*
G03I-491J0D01*
G37*
G36*
G01Y1563144D02*
G03I-491J0D01*
G37*
G36*
G01X177451Y1563544D02*
G03I-491J0D01*
G37*
G36*
G01X168790Y1583229D02*
G03I-491J0D01*
G37*
G36*
G01X177451Y1583629D02*
G03I-491J0D01*
G37*
G36*
G01X168790Y1593853D02*
G03I-491J0D01*
G37*
G36*
G01Y1587960D02*
G03I-491J0D01*
G37*
G36*
G01X177451Y1594253D02*
G03I-491J0D01*
G37*
G36*
G01Y1589522D02*
G03I-491J0D01*
G37*
G36*
G01Y1604876D02*
G03I-491J0D01*
G37*
G36*
G01X168790Y1609207D02*
G03I-491J0D01*
G37*
G36*
G01Y1598584D02*
G03I-491J0D01*
G37*
G36*
G01Y1603315D02*
G03I-491J0D01*
G37*
G36*
G01X177451Y1609607D02*
G03I-491J0D01*
G37*
G36*
G01Y1598984D02*
G03I-491J0D01*
G37*
G36*
G01X168790Y1613938D02*
G03I-491J0D01*
G37*
G36*
G01Y1618669D02*
G03I-491J0D01*
G37*
G36*
G01X177451Y1614338D02*
G03I-491J0D01*
G37*
G36*
G01X276443Y1127129D02*
X277599D01*
G02X277739Y1127072I0J-200D01*
G01X277740Y1127071D01*
X277780Y1127031D01*
X277781Y1127030D01*
G03X277795Y1127016I857J843D01*
G01X278485Y1126326D01*
X278691Y1126120D01*
G02X278693Y1126118I-140J-142D01*
G02X278750Y1125978I-143J-140D01*
G01Y1125091D01*
G02X278691Y1124949I-200J0D01*
G01X278626Y1124884D01*
X278544Y1124854D01*
X278500Y1124858D01*
G03X278400Y1124862I-100J-1258D01*
G01X250459D01*
G03X249625Y1124547I0J-1262D01*
G02X249493Y1124497I-132J150D01*
G01X246009D01*
G02X245877Y1124547I0J200D01*
G03X245043Y1124862I-834J-947D01*
G01X236200D01*
G03X235308Y1124492I1J-1262D01*
G01X234308Y1123492D01*
G03X233938Y1122600I892J-893D01*
G01Y1122298D01*
G02X233890Y1122292I-49J194D01*
G01X231360D01*
G02X231218Y1122351I0J200D01*
G01X229131Y1124438D01*
G03X228989Y1124497I-142J-141D01*
G01X196967D01*
G02X196825Y1124556I0J200D01*
G01X196681Y1124700D01*
G02X196632Y1124900I142J141D01*
G01X196650Y1124960D01*
X196665Y1124983D01*
G03X196872Y1125690I-1095J704D01*
G01Y1125715D01*
G03X196480Y1126619I-1302J-27D01*
G01X196451Y1126648D01*
X196420Y1126721D01*
Y1126806D01*
G02X196620Y1127006I200J0D01*
G01X269444D01*
G03X269581Y1127061I-1J200D01*
G01X269586Y1127066D01*
X269606Y1127083D01*
G02X269734Y1127129I128J-154D01*
G01X271555D01*
Y1127128D01*
X276410D01*
G03X276440Y1127129I-25J1201D01*
G01X276443D01*
G37*
G36*
G01X229569Y1131397D02*
X268538D01*
G02X268680Y1131338I0J-200D01*
G01X269168Y1130850D01*
G02X269227Y1130708I-141J-142D01*
G01Y1130072D01*
X269217Y1130028D01*
X269206Y1130007D01*
G03X269071Y1129429I1167J-577D01*
G03X269206Y1128851I1302J-1D01*
G01X269217Y1128830D01*
X269227Y1128786D01*
Y1128206D01*
G02X269168Y1128064I-200J0D01*
G01X269142Y1128038D01*
X269069Y1128008D01*
X196821D01*
G02X196679Y1128067I0J200D01*
G01X196663Y1128083D01*
Y1128692D01*
X196677Y1128743D01*
X196691Y1128766D01*
G03X196872Y1129429I-1121J662D01*
G03X196824Y1129779I-1302J0D01*
G02X196835Y1129916I193J53D01*
G01X196886Y1130027D01*
G02X196982Y1130125I182J-82D01*
G03X197326Y1130368I-531J1117D01*
G01X197970Y1131012D01*
G03X198181Y1131293I-873J875D01*
G01X198208Y1131342D01*
X198301Y1131397D01*
X229091D01*
X229108Y1131394D01*
G03X229330Y1131375I222J1283D01*
G03X229552Y1131394I0J1302D01*
G01X229569Y1131397D01*
G37*
G36*
G01X189881Y1186298D02*
X193100D01*
G02X193245Y1186236I0J-200D01*
G01X193474Y1185994D01*
X193502Y1185918D01*
X193499Y1185876D01*
G03X193498Y1185850I451J-30D01*
G01Y1184350D01*
G03X193950Y1183898I452J0D01*
G01X195150D01*
G03X195288Y1183920I-1J452D01*
G01X195317Y1183929D01*
X195348D01*
G02X195548Y1183729I0J-200D01*
G01Y1182719D01*
G03X195806Y1181977I1202J2D01*
G02X195871Y1181792I-236J-187D01*
G01X195870Y1181791D01*
X195871Y1181790D01*
G02X195806Y1181605I-301J2D01*
G03X195548Y1180863I944J-744D01*
G01Y1179652D01*
G02X195348Y1179452I-200J-1D01*
G01X194150D01*
G03X193698Y1179000I0J-452D01*
G01Y1177500D01*
G03X194150Y1177048I452J0D01*
G01X194756D01*
G02X194868Y1177014I1J-200D01*
G03X195570Y1176799I702J1037D01*
G03X196057Y1176898I-1J1252D01*
G01X196114Y1176921D01*
X196232Y1176898D01*
X196682Y1176448D01*
G03X197226Y1176135I851J849D01*
G01X197252Y1176128D01*
X197298Y1176102D01*
X197541Y1175859D01*
G03X197683Y1175800I142J141D01*
G01X198070D01*
G02X198252Y1175682I0J-200D01*
G01X198426Y1175297D01*
X198409Y1175180D01*
X198370Y1175136D01*
G03X198059Y1174310I941J-826D01*
G03X198103Y1173983I1252J2D01*
G01X198110Y1173957D01*
Y1172890D01*
G03X198561Y1172438I452J0D01*
G01X200061D01*
G03X200512Y1172890I0J451D01*
G01Y1173957D01*
X200519Y1173983D01*
G03X200563Y1174310I-1208J329D01*
G03X200252Y1175136I-1252J0D01*
G01X200213Y1175180D01*
X200196Y1175297D01*
X200370Y1175682D01*
G02X200552Y1175800I182J-82D01*
G01X205550D01*
G02X205732Y1175682I0J-200D01*
G01X205906Y1175297D01*
X205889Y1175180D01*
X205850Y1175136D01*
G03X205539Y1174310I941J-826D01*
G03X205583Y1173983I1252J2D01*
G01X205590Y1173957D01*
Y1172890D01*
G03X206041Y1172438I452J0D01*
G01X207541D01*
G03X207992Y1172890I0J451D01*
G01Y1173957D01*
X207999Y1173983D01*
G03X208043Y1174310I-1208J329D01*
G03X207732Y1175136I-1252J0D01*
G01X207693Y1175180D01*
X207676Y1175297D01*
X207850Y1175682D01*
G02X208032Y1175800I182J-82D01*
G01X213030D01*
G02X213212Y1175682I0J-200D01*
G01X213386Y1175297D01*
X213369Y1175180D01*
X213330Y1175136D01*
G03X213019Y1174310I941J-826D01*
G03X213063Y1173983I1252J2D01*
G01X213070Y1173957D01*
Y1172890D01*
G03X213521Y1172438I452J0D01*
G01X215021D01*
G03X215472Y1172890I0J451D01*
G01Y1173957D01*
X215479Y1173983D01*
G03X215523Y1174310I-1208J329D01*
G03X215212Y1175136I-1252J0D01*
G01X215173Y1175180D01*
X215156Y1175297D01*
X215330Y1175682D01*
G02X215512Y1175800I182J-82D01*
G01X220510D01*
G02X220692Y1175682I0J-200D01*
G01X220866Y1175297D01*
X220849Y1175180D01*
X220810Y1175136D01*
G03X220499Y1174310I941J-826D01*
G03X220543Y1173980I1252J-1D01*
G01X220550Y1173954D01*
Y1172890D01*
G03X221002Y1172438I452J0D01*
G01X222502D01*
G03X222954Y1172890I0J452D01*
G01Y1173960D01*
X222960Y1173986D01*
G03X223003Y1174310I-1209J325D01*
G03X222692Y1175136I-1252J0D01*
G01X222653Y1175180D01*
X222636Y1175297D01*
X222810Y1175682D01*
G02X222992Y1175800I182J-82D01*
G01X227991D01*
G02X228173Y1175682I0J-200D01*
G01X228347Y1175297D01*
X228330Y1175180D01*
X228291Y1175136D01*
G03X227980Y1174310I941J-826D01*
G03X228075Y1173831I1252J-1D01*
G01X228090Y1173794D01*
Y1172890D01*
G03X228542Y1172438I452J0D01*
G01X230042D01*
G03X230494Y1172890I0J452D01*
G01Y1174090D01*
G03X230485Y1174178I-452J-2D01*
G02X230481Y1174230I196J41D01*
G03X230484Y1174310I-1249J87D01*
G03X230173Y1175136I-1252J0D01*
G01X230134Y1175180D01*
X230117Y1175297D01*
X230291Y1175682D01*
G02X230473Y1175800I182J-82D01*
G01X239211D01*
G02X239393Y1175682I0J-200D01*
G01X239567Y1175297D01*
X239550Y1175180D01*
X239511Y1175136D01*
G03X239200Y1174310I941J-826D01*
G03X239244Y1173983I1252J2D01*
G01X239250Y1173957D01*
Y1172890D01*
G03X239702Y1172438I452J0D01*
G01X241202D01*
G03X241654Y1172890I0J452D01*
G01Y1173957D01*
X241660Y1173983D01*
G03X241704Y1174310I-1208J329D01*
G03X241393Y1175136I-1252J0D01*
G01X241354Y1175180D01*
X241337Y1175297D01*
X241511Y1175682D01*
G02X241693Y1175800I182J-82D01*
G01X246692D01*
G02X246874Y1175682I0J-200D01*
G01X247048Y1175297D01*
X247031Y1175180D01*
X246992Y1175136D01*
G03X246681Y1174310I941J-826D01*
G03X246725Y1173983I1252J2D01*
G01X246732Y1173957D01*
Y1172890D01*
G03X247183Y1172438I452J0D01*
G01X248683D01*
G03X249134Y1172890I0J451D01*
G01Y1173957D01*
X249141Y1173983D01*
G03X249185Y1174310I-1208J329D01*
G03X248874Y1175136I-1252J0D01*
G01X248835Y1175180D01*
X248818Y1175297D01*
X248992Y1175682D01*
G02X249174Y1175800I182J-82D01*
G01X254172D01*
G02X254354Y1175682I0J-200D01*
G01X254528Y1175297D01*
X254511Y1175180D01*
X254472Y1175136D01*
G03X254161Y1174310I941J-826D01*
G03X254205Y1173983I1252J2D01*
G01X254212Y1173957D01*
Y1172890D01*
G03X254663Y1172438I452J0D01*
G01X256163D01*
G03X256614Y1172890I0J451D01*
G01Y1173957D01*
X256621Y1173983D01*
G03X256665Y1174310I-1208J329D01*
G03X256354Y1175136I-1252J0D01*
G01X256315Y1175180D01*
X256298Y1175297D01*
X256472Y1175682D01*
G02X256654Y1175800I182J-82D01*
G01X259617D01*
G02X259759Y1175741I0J-200D01*
G01X260341Y1175159D01*
G02X260400Y1175017I-141J-142D01*
G01Y1172836D01*
G02X260333Y1172687I-200J0D01*
G01X260078Y1172459D01*
X259998Y1172434D01*
X259954Y1172439D01*
G03X259903Y1172442I-52J-449D01*
G01X258403D01*
G03X257952Y1171990I0J-451D01*
G01Y1170923D01*
X257945Y1170897D01*
G03X257901Y1170570I1208J-329D01*
G03X259153Y1169318I1252J0D01*
G03X259795Y1169495I0J1253D01*
G01X259842Y1169523D01*
X259949Y1169524D01*
X260299Y1169326D01*
G02X260400Y1169152I-99J-174D01*
G01Y1160768D01*
G02X260299Y1160594I-200J0D01*
G01X259949Y1160396D01*
X259842Y1160397D01*
X259795Y1160425D01*
G03X259153Y1160602I-642J-1076D01*
G03X257901Y1159350I0J-1252D01*
G03X257945Y1159023I1252J2D01*
G01X257952Y1158997D01*
Y1157930D01*
G03X258403Y1157478I452J0D01*
G01X259903D01*
G03X259954Y1157481I-1J452D01*
G01X259998Y1157486D01*
X260078Y1157461D01*
X260333Y1157233D01*
G02X260400Y1157084I-133J-149D01*
G01Y1155683D01*
G02X260341Y1155541I-200J0D01*
G01X259560Y1154760D01*
G02X259419Y1154702I-141J142D01*
G01X256985D01*
G02X256823Y1154784I-1J200D01*
G01X256604Y1155085D01*
X256589Y1155178D01*
X256604Y1155225D01*
G03X256665Y1155610I-1191J386D01*
G03X256621Y1155937I-1252J-2D01*
G01X256614Y1155963D01*
Y1157030D01*
G03X256163Y1157482I-452J0D01*
G01X254663D01*
G03X254212Y1157030I0J-451D01*
G01Y1155963D01*
X254205Y1155937D01*
G03X254161Y1155610I1208J-329D01*
G03X254222Y1155225I1252J1D01*
G01X254237Y1155178D01*
X254222Y1155085D01*
X254003Y1154784D01*
G02X253841Y1154702I-161J118D01*
G01X249505D01*
G02X249343Y1154784I-1J200D01*
G01X249124Y1155085D01*
X249109Y1155178D01*
X249124Y1155225D01*
G03X249185Y1155610I-1191J386D01*
G03X249141Y1155940I-1252J1D01*
G01X249134Y1155966D01*
Y1157030D01*
G03X248682Y1157482I-452J0D01*
G01X247182D01*
G03X246730Y1157030I0J-452D01*
G01Y1155960D01*
X246724Y1155934D01*
G03X246681Y1155610I1209J-325D01*
G03X246742Y1155225I1252J1D01*
G01X246757Y1155178D01*
X246742Y1155085D01*
X246523Y1154784D01*
G02X246361Y1154702I-161J118D01*
G01X242024D01*
G02X241862Y1154784I-1J200D01*
G01X241643Y1155085D01*
X241628Y1155178D01*
X241643Y1155225D01*
G03X241704Y1155610I-1191J386D01*
G03X241660Y1155937I-1252J-2D01*
G01X241654Y1155963D01*
Y1157030D01*
G03X241202Y1157482I-452J0D01*
G01X239702D01*
G03X239250Y1157030I0J-452D01*
G01Y1155963D01*
X239244Y1155937D01*
G03X239200Y1155610I1208J-329D01*
G03X239261Y1155225I1252J1D01*
G01X239276Y1155178D01*
X239261Y1155085D01*
X239042Y1154784D01*
G02X238880Y1154702I-161J118D01*
G01X230804D01*
G02X230642Y1154784I-1J200D01*
G01X230423Y1155085D01*
X230408Y1155178D01*
X230423Y1155225D01*
G03X230484Y1155610I-1191J386D01*
G03X230440Y1155937I-1252J-2D01*
G01X230434Y1155963D01*
Y1157030D01*
G03X229982Y1157482I-452J0D01*
G01X228482D01*
G03X228030Y1157030I0J-452D01*
G01Y1155963D01*
X228024Y1155937D01*
G03X227980Y1155610I1208J-329D01*
G03X228041Y1155225I1252J1D01*
G01X228056Y1155178D01*
X228041Y1155085D01*
X227822Y1154784D01*
G02X227660Y1154702I-161J118D01*
G01X223323D01*
G02X223161Y1154784I-1J200D01*
G01X222942Y1155085D01*
X222927Y1155178D01*
X222942Y1155225D01*
G03X223003Y1155610I-1191J386D01*
G03X222960Y1155934I-1252J-1D01*
G01X222954Y1155960D01*
Y1157030D01*
G03X222502Y1157482I-452J0D01*
G01X221002D01*
G03X220550Y1157030I0J-452D01*
G01Y1155966D01*
X220543Y1155940D01*
G03X220499Y1155610I1208J-329D01*
G03X220560Y1155225I1252J1D01*
G01X220575Y1155178D01*
X220560Y1155085D01*
X220341Y1154784D01*
G02X220179Y1154702I-161J118D01*
G01X215843D01*
G02X215681Y1154784I-1J200D01*
G01X215462Y1155085D01*
X215447Y1155178D01*
X215462Y1155225D01*
G03X215523Y1155610I-1191J386D01*
G03X215479Y1155937I-1252J-2D01*
G01X215472Y1155963D01*
Y1157030D01*
G03X215021Y1157482I-452J0D01*
G01X213521D01*
G03X213070Y1157030I0J-451D01*
G01Y1155963D01*
X213063Y1155937D01*
G03X213019Y1155610I1208J-329D01*
G03X213080Y1155225I1252J1D01*
G01X213095Y1155178D01*
X213080Y1155085D01*
X212861Y1154784D01*
G02X212699Y1154702I-161J118D01*
G01X208363D01*
G02X208201Y1154784I-1J200D01*
G01X207982Y1155085D01*
X207967Y1155178D01*
X207982Y1155225D01*
G03X208043Y1155610I-1191J386D01*
G03X207999Y1155937I-1252J-2D01*
G01X207992Y1155963D01*
Y1157030D01*
G03X207541Y1157482I-452J0D01*
G01X206041D01*
G03X205590Y1157030I0J-451D01*
G01Y1155963D01*
X205583Y1155937D01*
G03X205539Y1155610I1208J-329D01*
G03X205600Y1155225I1252J1D01*
G01X205615Y1155178D01*
X205600Y1155085D01*
X205381Y1154784D01*
G02X205219Y1154702I-161J118D01*
G01X200883D01*
G02X200721Y1154784I-1J200D01*
G01X200502Y1155085D01*
X200487Y1155178D01*
X200502Y1155225D01*
G03X200563Y1155610I-1191J386D01*
G03X200519Y1155937I-1252J-2D01*
G01X200512Y1155963D01*
Y1157030D01*
G03X200061Y1157482I-452J0D01*
G01X198561D01*
G03X198110Y1157030I0J-451D01*
G01Y1155963D01*
X198103Y1155937D01*
G03X198059Y1155610I1208J-329D01*
G03X198237Y1154967I1252J0D01*
G01X198272Y1154908D01*
X198255Y1154772D01*
X196408Y1152925D01*
X196272Y1152908D01*
X196213Y1152943D01*
G03X195570Y1153121I-643J-1074D01*
G03X195243Y1153077I2J-1252D01*
G01X195217Y1153070D01*
X194150D01*
G03X193698Y1152619I0J-452D01*
G01Y1151119D01*
G03X194150Y1150668I451J0D01*
G01X195217D01*
X195243Y1150661D01*
G03X195570Y1150617I329J1208D01*
G03X195971Y1150683I0J1251D01*
G01X196017Y1150698D01*
X196112Y1150684D01*
X196362Y1150504D01*
Y1145754D01*
X196112Y1145574D01*
X196017Y1145560D01*
X195971Y1145575D01*
G03X195570Y1145641I-401J-1185D01*
G03X195243Y1145597I2J-1252D01*
G01X195217Y1145590D01*
X194150D01*
G03X193698Y1145139I0J-452D01*
G01Y1143639D01*
G03X194150Y1143188I451J0D01*
G01X195217D01*
X195243Y1143181D01*
G03X195570Y1143137I329J1208D01*
G03X196198Y1143306I0J1251D01*
G01X196221Y1143319D01*
X196272Y1143333D01*
X196298D01*
G02X196498Y1143133I0J-200D01*
G01Y1142985D01*
X196500Y1142984D01*
Y1142683D01*
G02X196441Y1142541I-200J0D01*
G01X195830Y1141930D01*
X195757Y1141900D01*
X195732D01*
G03X195570Y1141910I-159J-1251D01*
G03X195419Y1141901I-1J-1261D01*
G01X195407Y1141900D01*
X191993D01*
X191981Y1141901D01*
G03X191830Y1141910I-150J-1252D01*
G03X191679Y1141901I-1J-1261D01*
G01X191667Y1141900D01*
X189783D01*
G02X189641Y1141959I0J200D01*
G01X189459Y1142141D01*
G02X189400Y1142283I141J142D01*
G01Y1185817D01*
G02X189459Y1185959I200J0D01*
G01X189740Y1186240D01*
G02X189881Y1186298I141J-142D01*
G37*
G36*
G01X262083Y1172100D02*
X271517D01*
G02X271659Y1172041I0J-200D01*
G01X271841Y1171859D01*
G02X271900Y1171717I-141J-142D01*
G01Y1158483D01*
G03X271959Y1158341I200J0D01*
G01X272891Y1157409D01*
G02X272950Y1157267I-141J-142D01*
G01Y1156072D01*
X272938Y1156039D01*
G03X272862Y1155610I1176J-430D01*
G03X272938Y1155181I1252J1D01*
G01X272950Y1155148D01*
Y1152331D01*
X272938Y1152298D01*
G03X272862Y1151869I1176J-430D01*
G03X272938Y1151440I1252J1D01*
G01X272950Y1151407D01*
Y1148591D01*
X272938Y1148558D01*
G03X272862Y1148129I1176J-430D01*
G03X272938Y1147700I1252J1D01*
G01X272950Y1147667D01*
Y1144851D01*
X272938Y1144818D01*
G03X272862Y1144389I1176J-430D01*
G03X272938Y1143960I1252J1D01*
G01X272950Y1143927D01*
Y1142833D01*
G02X272891Y1142691I-200J0D01*
G01X272659Y1142459D01*
G02X272517Y1142400I-142J141D01*
G01X268681D01*
X268581Y1142468D01*
X268570Y1142493D01*
X268419Y1142645D01*
G03X268010Y1142913I-849J-850D01*
G01X267971Y1142929D01*
X267959Y1142941D01*
G03X267817Y1143000I-142J-141D01*
G01X197983D01*
G02X197841Y1143059I0J200D01*
G01X197559Y1143341D01*
X197530Y1143369D01*
X197500Y1143443D01*
Y1152517D01*
G02X197559Y1152659I200J0D01*
G01X198541Y1153641D01*
G02X198683Y1153700I142J-141D01*
G01X261017D01*
G03X261159Y1153759I0J200D01*
G01X261742Y1154342D01*
G03X261785Y1154407I-142J141D01*
G01X261797Y1154434D01*
X261846Y1154488D01*
X262063Y1154594D01*
X262168Y1154588D01*
X262212Y1154559D01*
G03X262893Y1154358I680J1051D01*
G03X264145Y1155610I0J1252D01*
G03X264108Y1155912I-1251J0D01*
G01X264102Y1155936D01*
Y1157030D01*
G03X263650Y1157482I-452J0D01*
G01X262150D01*
G03X262089Y1157477I6J-451D01*
G01X262088D01*
G03X262046Y1157469I63J-447D01*
G01X261876Y1157604D01*
G02X261800Y1157761I124J157D01*
G01Y1165331D01*
G02X261893Y1165499I200J-1D01*
G01X262220Y1165708D01*
X262322Y1165715D01*
X262368Y1165693D01*
G03X262893Y1165578I524J1137D01*
G03X263219Y1165621I1J1252D01*
G01X263244Y1165628D01*
X263780D01*
X264313D01*
G03X264764Y1166080I0J451D01*
G01Y1166830D01*
X264765D01*
Y1167580D01*
G03X264314Y1168032I-452J0D01*
G01X263244D01*
X263219Y1168039D01*
G03X262893Y1168082I-325J-1209D01*
G03X262368Y1167967I-1J-1252D01*
G01X262322Y1167945D01*
X262220Y1167952D01*
X261893Y1168161D01*
G02X261800Y1168329I107J169D01*
G01Y1171817D01*
G02X261859Y1171959I200J0D01*
G01X261941Y1172041D01*
G02X262083Y1172100I142J-141D01*
G37*
G36*
G01X194969Y1190090D02*
X196693D01*
X196698Y1190084D01*
X266991D01*
G02X267132Y1190026I0J-200D01*
G01X267423Y1189735D01*
G02X267482Y1189593I-141J-142D01*
G01Y1188414D01*
G02X267423Y1188272I-200J0D01*
G01X267079Y1187928D01*
G02X266937Y1187869I-142J141D01*
G01X195063D01*
G02X194921Y1187928I0J200D01*
G01X194824Y1188025D01*
G02X194766Y1188166I142J141D01*
G01Y1189886D01*
G02X194824Y1190028I200J1D01*
G01X194827Y1190031D01*
G02X194969Y1190090I142J-141D01*
G37*
G36*
G01X267464Y1186897D02*
X268067D01*
G02X268209Y1186838I0J-200D01*
G01X269085Y1185962D01*
X269113Y1185864D01*
X269102Y1185814D01*
G03X269071Y1185531I1271J-282D01*
G03X269746Y1184390I1302J0D01*
G01X269795Y1184363D01*
X269850Y1184270D01*
Y1183052D01*
X269795Y1182959D01*
X269746Y1182932D01*
G03X269279Y1181086I627J-1141D01*
G01Y1178757D01*
G03X269071Y1178051I1094J-706D01*
G03X269117Y1177707I1302J-1D01*
G01X269132Y1177655D01*
X269104Y1177551D01*
X268984Y1177431D01*
G02X268842Y1177372I-142J141D01*
G01X266853D01*
G03X266455Y1177175I1J-502D01*
G01X266426Y1177138D01*
X266343Y1177097D01*
X197533D01*
G02X197391Y1177156I0J200D01*
G01X196871Y1177676D01*
X196842Y1177769D01*
X196851Y1177818D01*
G03X196872Y1178051I-1282J233D01*
G03X196593Y1178857I-1302J1D01*
G02X196550Y1178980I157J124D01*
G01Y1180862D01*
G02X196593Y1180985I200J-1D01*
G03X196872Y1181791I-1023J805D01*
G03X196593Y1182597I-1302J1D01*
G02X196550Y1182720I157J124D01*
G01Y1184602D01*
G02X196593Y1184725I200J-1D01*
G03X196872Y1185531I-1023J805D01*
G03X196593Y1186337I-1302J1D01*
G01X196572Y1186364D01*
X196550Y1186426D01*
Y1186714D01*
G02X196609Y1186856I200J0D01*
G01X196620Y1186868D01*
X267435D01*
X267464Y1186897D01*
G37*
G36*
G01X188533Y1191786D02*
X188561Y1191797D01*
G03X188593Y1191810I-474J1213D01*
G01X188690D01*
G03X189137Y1192198I0J451D01*
G02X189169Y1192282I198J-27D01*
G03X189392Y1193011I-1080J729D01*
G03X189169Y1193739I-1300J0D01*
G02X189137Y1193823I166J111D01*
G03X189130Y1193860I-447J-65D01*
G02X189169Y1194029I195J44D01*
G01X189365Y1194273D01*
G02X189521Y1194348I156J-125D01*
G01X194268D01*
G02X194468Y1194148I0J-200D01*
G01Y1193630D01*
X194458Y1193586D01*
X194447Y1193565D01*
G03X194318Y1193011I1123J-554D01*
G03X194447Y1192457I1252J0D01*
G01X194458Y1192436D01*
X194468Y1192392D01*
Y1192251D01*
G02X194409Y1192109I-200J0D01*
G01X193823Y1191523D01*
G03X193764Y1191381I141J-142D01*
G01Y1187649D01*
G02X193742Y1187558I-200J0D01*
G02X193706Y1187508I-178J90D01*
G01X193556Y1187358D01*
G02X193506Y1187322I-140J142D01*
G02X193415Y1187300I-91J178D01*
G01X189057D01*
G02X188966Y1187322I0J200D01*
G02X188916Y1187358I90J178D01*
G01X188491Y1187783D01*
G02X188455Y1187833I142J140D01*
G02X188433Y1187924I178J91D01*
G01Y1191611D01*
G02X188468Y1191724I200J0D01*
G01X188485Y1191749D01*
X188533Y1191786D01*
G37*
G36*
G01X270769Y1202824D02*
X270280D01*
X201070D01*
X194842D01*
X194756Y1202910D01*
Y1204954D01*
X195143Y1205341D01*
X201019D01*
X202072D01*
X229226D01*
G03X229368Y1205400I0J200D01*
G01X231476Y1207508D01*
G02X231618Y1207567I142J-141D01*
G01X234418D01*
G02X234560Y1207508I0J-200D01*
G01X236609Y1205459D01*
G03X236751Y1205400I142J141D01*
G01X270792D01*
X271300D01*
X271500Y1205200D01*
Y1203000D01*
X271324Y1202824D01*
X270769D01*
G37*
G36*
G01X195115Y1197625D02*
X195707D01*
G02X195849Y1197566I0J-200D01*
G01X195979Y1197435D01*
G03X196121Y1197376I142J141D01*
G01X267250D01*
G02X267450Y1197176I0J-200D01*
G01Y1196502D01*
G02X267391Y1196360I-200J0D01*
G01X266439Y1195408D01*
X266411Y1195379D01*
X266337Y1195349D01*
X189738D01*
G02X189596Y1195408I0J200D01*
G01X189460Y1195544D01*
Y1197370D01*
X189656Y1197566D01*
X194973D01*
G02X195115Y1197625I142J-141D01*
G37*
G36*
G01X267027Y1194497D02*
X267167D01*
G02X267309Y1194438I0J-200D01*
G01X268191Y1193556D01*
G02X268250Y1193414I-141J-142D01*
G01Y1191380D01*
G02X268191Y1191238I-200J0D01*
G01X268098Y1191145D01*
G02X267956Y1191086I-142J141D01*
G01X197700D01*
X197400Y1191386D01*
Y1194148D01*
X197600Y1194348D01*
X266712D01*
G03X266853Y1194406I0J200D01*
G01X266886Y1194438D01*
G02X267027Y1194497I142J-141D01*
G37*
G36*
G01X269054Y1199246D02*
X268244Y1198437D01*
X268216Y1198408D01*
X268142Y1198378D01*
X196537D01*
G02X196395Y1198437I0J200D01*
G01X196247Y1198585D01*
G02X196227Y1198608I141J142D01*
G02X196188Y1198727I161J119D01*
G01Y1199231D01*
G02X196279Y1199399I200J0D01*
G03X196872Y1200491I-709J1092D01*
G03X196659Y1201203I-1302J-2D01*
G01X196644Y1201226D01*
X196628Y1201278D01*
X196627Y1201306D01*
G02X196651Y1201408I200J7D01*
G01X196818Y1201718D01*
G02X196994Y1201823I176J-95D01*
G01X268700D01*
X269054Y1201469D01*
Y1199246D01*
G37*
G36*
G01X196763Y1348187D02*
G03I-491J0D01*
G37*
G36*
G01X192403D02*
G03I-491J0D01*
G37*
G36*
G01X184523D02*
G03I-491J0D01*
G37*
G36*
G01X196763Y1360099D02*
G03I-491J0D01*
G37*
G36*
G01X192403D02*
G03I-491J0D01*
G37*
G36*
G01X184523D02*
G03I-491J0D01*
G37*
G36*
G01X196763Y1372385D02*
G03I-491J0D01*
G37*
G36*
G01X192403D02*
G03I-491J0D01*
G37*
G36*
G01X184523D02*
G03I-491J0D01*
G37*
G36*
G01X196763Y1396583D02*
G03I-491J0D01*
G37*
G36*
G01Y1384297D02*
G03I-491J0D01*
G37*
G36*
G01X192403D02*
G03I-491J0D01*
G37*
G36*
G01X184523D02*
G03I-491J0D01*
G37*
G36*
G01X192403Y1396583D02*
G03I-491J0D01*
G37*
G36*
G01X184523D02*
G03I-491J0D01*
G37*
G36*
G01X196763Y1408495D02*
G03I-491J0D01*
G37*
G36*
G01X192403D02*
G03I-491J0D01*
G37*
G36*
G01X184523D02*
G03I-491J0D01*
G37*
G36*
G01X186113Y1460782D02*
G03I-491J0D01*
G37*
G36*
G01Y1480868D02*
G03I-491J0D01*
G37*
G36*
G01Y1476137D02*
G03I-491J0D01*
G37*
G36*
G01Y1470244D02*
G03I-491J0D01*
G37*
G36*
G01Y1465513D02*
G03I-491J0D01*
G37*
G36*
G01Y1485599D02*
G03I-491J0D01*
G37*
G36*
G01X198480Y1141927D02*
X198490Y1141937D01*
G02X198631Y1141996I142J-141D01*
G01X267569D01*
G02X267710Y1141937I-1J-200D01*
G01X267720Y1141927D01*
X267750Y1141854D01*
Y1139998D01*
G02X267550Y1139798I-200J0D01*
G01X198931D01*
G02X198790Y1139857I1J200D01*
G01X198509Y1140138D01*
G02X198450Y1140280I141J142D01*
G01Y1141854D01*
X198480Y1141927D01*
G37*
G36*
G01X198733Y1134697D02*
X267267D01*
G02X267409Y1134638I0J-200D01*
G01X267691Y1134356D01*
G02X267750Y1134214I-141J-142D01*
G01Y1132980D01*
G02X267691Y1132838I-200J0D01*
G01X267310Y1132457D01*
G02X267169Y1132398I-142J141D01*
G01X198831D01*
G02X198690Y1132457I1J200D01*
G01X198409Y1132738D01*
G02X198350Y1132880I141J142D01*
G01Y1134314D01*
G02X198409Y1134456I200J0D01*
G01X198591Y1134638D01*
G02X198733Y1134697I142J-141D01*
G37*
G36*
G01Y1138797D02*
X267467D01*
G02X267609Y1138738I0J-200D01*
G01X267891Y1138456D01*
G02X267950Y1138314I-141J-142D01*
G01Y1135980D01*
G02X267891Y1135838I-200J0D01*
G01X267810Y1135757D01*
G02X267669Y1135698I-142J141D01*
G01X198450D01*
G02X198250Y1135898I0J200D01*
G01Y1138314D01*
G02X198309Y1138456I200J0D01*
G01X198591Y1138738D01*
G02X198733Y1138797I142J-141D01*
G37*
G36*
G01X204643Y1348187D02*
G03I-491J0D01*
G37*
G36*
G01Y1360099D02*
G03I-491J0D01*
G37*
G36*
G01Y1372385D02*
G03I-491J0D01*
G37*
G36*
G01Y1396583D02*
G03I-491J0D01*
G37*
G36*
G01Y1384297D02*
G03I-491J0D01*
G37*
G36*
G01Y1408495D02*
G03I-491J0D01*
G37*
G36*
G01X211964Y1446675D02*
G03I-491J0D01*
G37*
G36*
G01X214460Y1445013D02*
G03I-491J0D01*
G37*
G36*
G01X211964Y1451631D02*
G03I-491J0D01*
G37*
G36*
G01Y1462631D02*
G03I-491J0D01*
G37*
G36*
G01Y1457675D02*
G03I-491J0D01*
G37*
G36*
G01X214460Y1453293D02*
G03I-491J0D01*
G37*
G36*
G01Y1456013D02*
G03I-491J0D01*
G37*
G36*
G01Y1464293D02*
G03I-491J0D01*
G37*
G36*
G01X342330Y514918D02*
X391558D01*
G02X391700Y514859I0J-200D01*
G01X402105Y504453D01*
G02X402107Y504451I-140J-142D01*
G02X402164Y504311I-143J-140D01*
G01Y500748D01*
G03X402165Y500712I1236J16D01*
G01Y451893D01*
X402135Y451819D01*
X402106Y451791D01*
X401070Y450755D01*
X401042Y450726D01*
X400968Y450696D01*
X397117D01*
G02X397090Y450698I1J200D01*
G01X397050Y450703D01*
X397026Y450710D01*
X397003Y450723D01*
X396898Y450783D01*
X396863Y450816D01*
X396850Y450838D01*
G03X396622Y451121I-1275J-794D01*
G01X396593Y451148D01*
X396546Y451255D01*
X396529Y451294D01*
Y451528D01*
G02X396533Y451566I200J-2D01*
G01X396539Y451599D01*
X396543Y451624D01*
X396593Y451734D01*
X396622Y451761D01*
G03X397079Y452840I-1045J1079D01*
G01Y452842D01*
G03X396622Y453921I-1502J0D01*
G01X396593Y453948D01*
X396546Y454055D01*
X396529Y454094D01*
Y454328D01*
G02X396533Y454366I200J-2D01*
G01X396539Y454399D01*
X396543Y454424D01*
X396593Y454534D01*
X396622Y454561D01*
G03X397079Y455640I-1045J1079D01*
G01Y455641D01*
G03X394075I-1502J0D01*
G01Y455640D01*
G03X394532Y454561I1502J0D01*
G01X394561Y454534D01*
X394608Y454428D01*
G02X394625Y454348I-183J-81D01*
G01Y454159D01*
G02X394621Y454120I-200J1D01*
G01X394613Y454080D01*
G02X394601Y454040I-197J37D01*
G01X394562Y453950D01*
X394533Y453922D01*
G03X394075Y452842I1044J-1080D01*
G01Y452840D01*
G03X394532Y451761I1502J0D01*
G01X394561Y451734D01*
X394608Y451628D01*
G02X394625Y451548I-183J-81D01*
G01Y451359D01*
G02X394621Y451320I-200J1D01*
G01X394613Y451280D01*
G02X394601Y451240I-197J37D01*
G01X394562Y451150D01*
X394533Y451122D01*
G03X394304Y450838I1046J-1078D01*
G01X394291Y450817D01*
X394256Y450783D01*
X394152Y450723D01*
X394150D01*
X394128Y450710D01*
X394077Y450696D01*
X387124D01*
G02X387097Y450698I1J200D01*
G01X387057Y450703D01*
X387033Y450710D01*
X387010Y450723D01*
X386905Y450783D01*
X386870Y450816D01*
X386857Y450838D01*
G03X386629Y451121I-1275J-794D01*
G01X386600Y451148D01*
X386553Y451255D01*
X386536Y451294D01*
Y451528D01*
G02X386540Y451566I200J-2D01*
G01X386546Y451599D01*
X386550Y451624D01*
X386600Y451734D01*
X386629Y451761D01*
G03X387086Y452840I-1045J1079D01*
G01Y452842D01*
G03X386629Y453921I-1502J0D01*
G01X386600Y453948D01*
X386553Y454055D01*
X386536Y454094D01*
Y454328D01*
G02X386540Y454366I200J-2D01*
G01X386546Y454399D01*
X386550Y454424D01*
X386600Y454534D01*
X386629Y454561D01*
G03X387086Y455640I-1045J1079D01*
G01Y455641D01*
G03X384082I-1502J0D01*
G01Y455640D01*
G03X384539Y454561I1502J0D01*
G01X384568Y454534D01*
X384615Y454428D01*
G02X384632Y454348I-183J-81D01*
G01Y454159D01*
G02X384628Y454120I-200J1D01*
G01X384620Y454080D01*
G02X384608Y454040I-197J37D01*
G01X384569Y453950D01*
X384540Y453922D01*
G03X384082Y452842I1044J-1080D01*
G01Y452840D01*
G03X384539Y451761I1502J0D01*
G01X384568Y451734D01*
X384615Y451628D01*
G02X384632Y451548I-183J-81D01*
G01Y451359D01*
G02X384628Y451320I-200J1D01*
G01X384620Y451280D01*
G02X384608Y451240I-197J37D01*
G01X384569Y451150D01*
X384540Y451122D01*
G03X384311Y450838I1046J-1078D01*
G01X384298Y450817D01*
X384263Y450783D01*
X384159Y450723D01*
X384157D01*
X384135Y450710D01*
X384084Y450696D01*
X366453D01*
G02X366360Y450719I0J200D01*
G01X366333Y450733D01*
X366291Y450775D01*
X366277Y450802D01*
G03X363631I-1323J-710D01*
G01X363617Y450775D01*
X363575Y450733D01*
X363504Y450696D01*
X363253D01*
G02X363160Y450719I0J200D01*
G01X363133Y450733D01*
X363091Y450775D01*
X363077Y450802D01*
G03X360445Y450826I-1323J-710D01*
G01X360431Y450801D01*
X360392Y450762D01*
G02X360120Y450752I-141J141D01*
G01X360088Y450780D01*
X360070Y450811D01*
G03X357431Y450801I-1317J-719D01*
G02X357255Y450696I-176J95D01*
G01X354386D01*
X354350Y450711D01*
G03X352976I-687J-1667D01*
G01X352940Y450696D01*
X297127D01*
G03X296985Y450637I0J-200D01*
G01X296137Y449789D01*
X296109Y449760D01*
X296035Y449730D01*
X289512D01*
X289438Y449760D01*
X289410Y449789D01*
X288991Y450208D01*
X288962Y450236D01*
X288932Y450310D01*
Y464268D01*
G03X288873Y464410I-200J0D01*
G01X286334Y466949D01*
G03X286192Y467008I-142J-141D01*
G01X284342D01*
G02X284142Y467208I0J200D01*
G01Y467215D01*
X284143Y467223D01*
G03X284148Y467367I-1896J138D01*
G01Y470137D01*
G03X284100Y470560I-1901J-1D01*
G01X284094Y470586D01*
G02X284133Y470755I195J44D01*
G01X284361Y471038D01*
X284444Y471077D01*
X284491Y471076D01*
G03X284514I12J1503D01*
G01X284517D01*
G03X286019Y472579I-1J1503D01*
G03X283013I-1503J0D01*
G03X283019Y472440I1503J-5D01*
G01X283023Y472393D01*
X282990Y472308D01*
X282690Y472030D01*
X282603Y472004D01*
X282556Y472012D01*
G03X282247Y472038I-313J-1876D01*
G01X282066D01*
Y472035D01*
X281902Y472005D01*
G03X280346Y470137I345J-1869D01*
G01Y468816D01*
G02X280146Y468616I-200J0D01*
G01X279838D01*
G02X279638Y468816I0J200D01*
G01Y468852D01*
X278583D01*
G03X278067Y468686I2J-890D01*
G01X278043Y468669D01*
X277923Y468628D01*
X277244D01*
G02X277192Y468635I0J200D01*
G01X277117Y468656D01*
X277094Y468669D01*
X277093D01*
G03X276345Y468870I-751J-1302D01*
G01X276343D01*
G03X276296Y468869I8J-1503D01*
G03X274906Y467804I48J-1502D01*
G01X274901Y467788D01*
X274884Y467753D01*
G02X274811Y467674I-178J91D01*
G01X274598Y467540D01*
G02X274492Y467509I-107J169D01*
G01X274454D01*
X274439Y467511D01*
G03X274205Y467530I-238J-1484D01*
G03X273147Y467095I0J-1504D01*
G01X273120Y467068D01*
X273017Y467024D01*
X272979Y467008D01*
X266004D01*
G02X265804Y467208I0J200D01*
G01Y467245D01*
G03X265808Y467337I-1798J124D01*
G01Y470737D01*
G03X265806Y470790I-1802J-41D01*
G01Y470822D01*
X265824Y470904D01*
X265842Y470945D01*
X265969Y471054D01*
G02X266055Y471098I131J-151D01*
G01X266101Y471108D01*
X266141Y471101D01*
G03X266404Y471077I267J1478D01*
G01X266405D01*
G03Y474081I0J1502D01*
G03X264922Y472815I0J-1502D01*
G01Y472814D01*
G02X264835Y472679I-198J32D01*
G01X264598Y472521D01*
G02X264487Y472488I-110J167D01*
G01X264432D01*
X264409Y472493D01*
G03X264006Y472540I-409J-1755D01*
G01X264004D01*
G03X263651Y472504I5J-1803D01*
G01X263650Y472503D01*
G03X263583Y472488I360J-1765D01*
G01X263487Y472470D01*
X263419Y472516D01*
X263175Y472679D01*
G02X263088Y472813I110J167D01*
G01Y472816D01*
G03X261605Y474081I-1483J-237D01*
G03X260619Y473712I0J-1502D01*
G01X260617Y473710D01*
G02X260487Y473662I-130J152D01*
G01X260223D01*
G02X260093Y473710I0J200D01*
G01X260092Y473711D01*
G03X259105Y474081I-987J-1131D01*
G01X259103D01*
G03X258853Y474060I0J-1502D01*
G01X258836Y474057D01*
X258794Y474049D01*
X258712Y474070D01*
X258678Y474096D01*
X258674Y474099D01*
X258576Y474182D01*
G02X258506Y474343I130J152D01*
G01Y474346D01*
G03X258508Y474424I-1801J85D01*
G01Y477824D01*
G03X258506Y477877I-1802J-41D01*
G01Y477909D01*
X258524Y477991D01*
X258542Y478032D01*
X258669Y478141D01*
G02X258755Y478185I131J-151D01*
G01X258801Y478195D01*
X258841Y478188D01*
G03X259104Y478164I267J1478D01*
G01X259105D01*
G03X260091Y478533I0J1502D01*
G01X260093Y478535D01*
G02X260223Y478583I130J-152D01*
G01X260487D01*
G02X260617Y478535I0J-200D01*
G01X260618Y478534D01*
G03X261605Y478164I987J1131D01*
G03X263089Y479433I0J1502D01*
G01X263097Y479483D01*
X263128Y479524D01*
G02X263177Y479569I158J-123D01*
G01X263459Y479755D01*
X263540Y479769D01*
X263581Y479759D01*
G03X264004Y479708I426J1751D01*
G01X264005D01*
G03X264431Y479759I0J1802D01*
G01X264472Y479769D01*
X264553Y479755D01*
X264870Y479544D01*
X264914Y479475D01*
X264921Y479432D01*
G03X266405Y478163I1484J233D01*
G03Y481167I0J1502D01*
G01X266403D01*
G03X266153Y481146I0J-1502D01*
G01X266136Y481143D01*
X266094Y481135D01*
X266012Y481156D01*
X265978Y481182D01*
X265974Y481185D01*
X265876Y481268D01*
G02X265806Y481429I130J152D01*
G01Y481432D01*
G03X265808Y481510I-1801J85D01*
G01Y484910D01*
G03X265806Y484963I-1802J-41D01*
G01Y484995D01*
X265824Y485077D01*
X265842Y485118D01*
X265969Y485227D01*
G02X266055Y485271I131J-151D01*
G01X266101Y485281D01*
X266141Y485274D01*
G03X266404Y485250I267J1478D01*
G01X266405D01*
G03Y488254I0J1502D01*
G03X264922Y486989I0J-1502D01*
G01Y486986D01*
G02X264835Y486852I-197J33D01*
G01X264591Y486689D01*
G02X264433Y486661I-111J166D01*
G01X264432D01*
G03X264006Y486712I-426J-1751D01*
G01X264004D01*
G03X263578Y486661I0J-1802D01*
G01X263577D01*
G02X263419Y486689I-47J194D01*
G01X263175Y486852D01*
G02X263088Y486986I110J167D01*
G01Y486989D01*
G03X261605Y488254I-1483J-237D01*
G03X260619Y487885I0J-1502D01*
G01X260617Y487883D01*
G02X260487Y487835I-130J152D01*
G01X260223D01*
G02X260093Y487883I0J200D01*
G01X260092Y487884D01*
G03X259105Y488254I-987J-1131D01*
G01X259103D01*
G03X258853Y488233I0J-1502D01*
G01X258836Y488230D01*
X258794Y488222D01*
X258712Y488243D01*
X258678Y488269D01*
X258674Y488272D01*
X258576Y488355D01*
G02X258506Y488516I130J152D01*
G01Y488519D01*
G03X258508Y488597I-1801J85D01*
G01Y491997D01*
G03X258506Y492050I-1802J-41D01*
G01Y492082D01*
X258524Y492164D01*
X258542Y492205D01*
X258669Y492314D01*
G02X258755Y492358I131J-151D01*
G01X258801Y492368D01*
X258841Y492361D01*
G03X259104Y492337I267J1478D01*
G01X259105D01*
G03Y495341I0J1502D01*
G03X257622Y494075I0J-1502D01*
G01Y494074D01*
G02X257535Y493939I-198J32D01*
G01X257298Y493781D01*
G02X257187Y493748I-110J167D01*
G01X257132D01*
X257109Y493753D01*
G03X256706Y493800I-409J-1755D01*
G01X256704D01*
G03X256351Y493764I5J-1803D01*
G01X256350Y493763D01*
G03X256283Y493748I360J-1765D01*
G01X256187Y493730D01*
X256119Y493776D01*
X255875Y493939D01*
G02X255788Y494073I110J167D01*
G01Y494076D01*
G03X254305Y495341I-1483J-237D01*
G03Y492337I0J-1502D01*
G01X254306D01*
G03X254560Y492359I-2J1502D01*
G01X254565Y492360D01*
X254573Y492361D01*
X254625Y492368D01*
X254667Y492355D01*
G02X254739Y492316I-57J-192D01*
G01X254740Y492315D01*
X254835Y492233D01*
G02X254886Y492165I-131J-151D01*
G01X254906Y492121D01*
X254904Y492072D01*
Y492059D01*
G03X254902Y491997I1800J-89D01*
G01Y488597D01*
G03X254904Y488519I1803J7D01*
G01Y488516D01*
G02X254834Y488355I-200J-9D01*
G01X254738Y488274D01*
G02X254574Y488230I-129J153D01*
G01X254573D01*
G03X254306Y488254I-267J-1478D01*
G01X254305D01*
G03Y485250I0J-1502D01*
G03X255789Y486519I0J1502D01*
G01X255796Y486562D01*
X255840Y486631D01*
X256113Y486813D01*
G02X256224Y486846I110J-167D01*
G01X256280D01*
X256303Y486841D01*
G03X256704Y486794I409J1755D01*
G01X256706D01*
G03X257119Y486843I-4J1803D01*
G01X257130Y486846D01*
X257156Y486849D01*
G02X257290Y486817I23J-198D01*
G01X257570Y486631D01*
X257614Y486562D01*
X257621Y486519D01*
G03X259105Y485250I1484J233D01*
G03X260091Y485619I0J1502D01*
G01X260093Y485621D01*
G02X260223Y485669I130J-152D01*
G01X260487D01*
G02X260617Y485621I0J-200D01*
G01X260618Y485620D01*
G03X261605Y485250I987J1131D01*
G01X261606D01*
G03X261860Y485272I-2J1502D01*
G01X261865Y485273D01*
X261873Y485274D01*
X261925Y485281D01*
X261967Y485268D01*
G02X262039Y485229I-57J-192D01*
G01X262040Y485228D01*
X262135Y485146D01*
G02X262186Y485078I-131J-151D01*
G01X262206Y485034D01*
X262204Y484985D01*
Y484972D01*
G03X262202Y484910I1800J-89D01*
G01Y481510D01*
G03X262204Y481433I1803J8D01*
G01Y481430D01*
G02X262134Y481269I-200J-9D01*
G01X262038Y481188D01*
G02X261874Y481144I-129J153D01*
G01X261873D01*
G03X261606Y481168I-267J-1478D01*
G01X261605D01*
G03X260619Y480799I0J-1502D01*
G01X260617Y480797D01*
G02X260487Y480749I-130J152D01*
G01X260223D01*
G02X260093Y480797I0J200D01*
G01X260092Y480798D01*
G03X259105Y481168I-987J-1131D01*
G03X257622Y479903I0J-1502D01*
G01Y479900D01*
G02X257535Y479766I-197J33D01*
G01X257291Y479603D01*
G02X257133Y479575I-111J166D01*
G01X257132D01*
G03X256706Y479626I-426J-1751D01*
G01X256704D01*
G03X256278Y479575I0J-1802D01*
G01X256277D01*
G02X256119Y479603I-47J194D01*
G01X255875Y479766D01*
G02X255788Y479900I110J167D01*
G01Y479903D01*
G03X254305Y481168I-1483J-237D01*
G03Y478164I0J-1502D01*
G01X254306D01*
G03X254560Y478186I-2J1502D01*
G01X254565Y478187D01*
X254573Y478188D01*
X254625Y478195D01*
X254667Y478182D01*
G02X254739Y478143I-57J-192D01*
G01X254740Y478142D01*
X254835Y478060D01*
G02X254886Y477992I-131J-151D01*
G01X254906Y477948D01*
X254904Y477899D01*
Y477886D01*
G03X254902Y477824I1800J-89D01*
G01Y474424D01*
G03X254904Y474346I1803J7D01*
G01Y474343D01*
G02X254834Y474182I-200J-9D01*
G01X254738Y474101D01*
G02X254574Y474057I-129J153D01*
G01X254573D01*
G03X254306Y474081I-267J-1478D01*
G01X254305D01*
G03Y471077I0J-1502D01*
G03X255789Y472346I0J1502D01*
G01X255796Y472389D01*
X255840Y472458D01*
X256157Y472669D01*
X256238Y472683D01*
X256279Y472673D01*
G03X256705Y472622I426J1751D01*
G03X257131Y472673I0J1802D01*
G01X257172Y472683D01*
X257253Y472669D01*
X257570Y472458D01*
X257614Y472389D01*
X257621Y472346D01*
G03X259105Y471077I1484J233D01*
G03X260091Y471446I0J1502D01*
G01X260093Y471448D01*
G02X260223Y471496I130J-152D01*
G01X260487D01*
G02X260617Y471448I0J-200D01*
G01X260618Y471447D01*
G03X261605Y471077I987J1131D01*
G01X261606D01*
G03X261860Y471099I-2J1502D01*
G01X261865Y471100D01*
X261873Y471101D01*
X261925Y471108D01*
X261967Y471095D01*
G02X262039Y471056I-57J-192D01*
G01X262040Y471055D01*
X262135Y470973D01*
G02X262186Y470905I-131J-151D01*
G01X262206Y470861D01*
X262204Y470812D01*
Y470799D01*
G03X262202Y470737I1800J-89D01*
G01Y467337D01*
G03X262206Y467245I1802J32D01*
G01Y467208D01*
G02X262006Y467008I-200J0D01*
G01X259555D01*
G03X259413Y466949I0J-200D01*
G01X256684Y464220D01*
G03X256625Y464078I141J-142D01*
G01Y455279D01*
G02X256566Y455137I-200J0D01*
G01X255321Y453891D01*
G03X255262Y453755I141J-142D01*
G02X255239Y453667I-200J5D01*
G03X254976Y452618I1973J-1052D01*
G01Y451771D01*
G02X254921Y451634I-200J1D01*
G01X254706Y451407D01*
X254637Y451375D01*
X254598Y451373D01*
G03Y448373I80J-1500D01*
G01X254637Y448371D01*
X254706Y448339D01*
X254921Y448112D01*
Y448111D01*
X254976D01*
Y445825D01*
G02X254917Y445683I-200J0D01*
G01X254485Y445251D01*
X254457Y445222D01*
X254383Y445192D01*
X253043D01*
X253029Y445194D01*
G03X252696Y445219I-335J-2238D01*
G01X252695D01*
G03X251010Y444467I0J-2263D01*
G01X250982Y444435D01*
X250909Y444402D01*
X250866Y444394D01*
X243474D01*
G03X243332Y444335I0J-200D01*
G01X237394Y438397D01*
G03X237335Y438255I141J-142D01*
G01Y422511D01*
G03X237394Y422369I200J0D01*
G01X240458Y419305D01*
G03X240600Y419246I142J141D01*
G01X263808D01*
G02X263892Y419228I1J-200D01*
G01X263966Y419193D01*
G02X264032Y419144I-84J-182D01*
G01X264035Y419141D01*
G03X266841Y417853I2806J2413D01*
G03X270543Y421555I0J3702D01*
G03X270518Y421983I-3702J-2D01*
G01X270513Y422026D01*
X270538Y422106D01*
X270766Y422362D01*
G02X270915Y422429I149J-133D01*
G01X271636D01*
G02X271785Y422362I0J-200D01*
G01X272013Y422106D01*
X272038Y422026D01*
X272033Y421983D01*
G03X272008Y421555I3677J-430D01*
G03X275708Y417854I3701J0D01*
G01X283010D01*
G03X286712Y421555I0J3702D01*
G03X286687Y421983I-3702J-2D01*
G01X286682Y422026D01*
X286707Y422106D01*
X286935Y422362D01*
G02X287084Y422429I149J-133D01*
G01X291782D01*
G02X291931Y422362I0J-200D01*
G01X292159Y422106D01*
X292184Y422026D01*
X292179Y421983D01*
G03X292154Y421555I3677J-430D01*
G03X299558I3702J0D01*
G03X299533Y421983I-3702J-2D01*
G01X299528Y422026D01*
X299553Y422106D01*
X299781Y422362D01*
G02X299930Y422429I149J-133D01*
G01X319669D01*
G02X319702Y422426I-2J-200D01*
G02X319809Y422372I-32J-197D01*
G01X335272Y406909D01*
G02X335274Y406907I-140J-142D01*
G02X335331Y406767I-143J-140D01*
G01Y306684D01*
X335301Y306610D01*
X335272Y306582D01*
X329119Y300429D01*
X329091Y300400D01*
X329017Y300370D01*
X223281D01*
X223207Y300400D01*
X223179Y300429D01*
X215785Y307823D01*
X215756Y307851D01*
X215726Y307925D01*
Y387540D01*
G02X215736Y387602I200J0D01*
G01X215751Y387649D01*
X215817Y387715D01*
X215862Y387730D01*
G03Y390576I-483J1423D01*
G01X215801Y390597D01*
X215726Y390701D01*
Y394627D01*
G02X215736Y394689I200J0D01*
G01X215751Y394736D01*
X215817Y394802D01*
X215862Y394817D01*
G03Y397663I-483J1423D01*
G01X215801Y397684D01*
X215726Y397788D01*
Y401713D01*
G02X215736Y401775I200J0D01*
G01X215751Y401822D01*
X215817Y401888D01*
X215862Y401903D01*
G03Y404749I-483J1423D01*
G01X215801Y404770D01*
X215726Y404874D01*
Y408800D01*
G02X215736Y408862I200J0D01*
G01X215751Y408909D01*
X215817Y408975D01*
X215862Y408990D01*
G03Y411836I-483J1423D01*
G01X215801Y411857D01*
X215726Y411961D01*
Y415886D01*
G02X215736Y415948I200J0D01*
G01X215751Y415995D01*
X215817Y416061D01*
X215862Y416076D01*
G03Y418922I-483J1423D01*
G01X215801Y418943D01*
X215726Y419047D01*
Y422973D01*
G02X215736Y423035I200J0D01*
G01X215751Y423082D01*
X215817Y423148D01*
X215862Y423163D01*
G03Y426009I-483J1423D01*
G01X215801Y426030D01*
X215726Y426134D01*
Y430060D01*
G02X215736Y430122I200J0D01*
G01X215751Y430169D01*
X215817Y430235D01*
X215862Y430250D01*
G03Y433096I-483J1423D01*
G01X215801Y433117D01*
X215726Y433221D01*
Y437147D01*
G02X215736Y437209I200J0D01*
G01X215751Y437256D01*
X215817Y437322D01*
X215862Y437337D01*
G03Y440183I-483J1423D01*
G01X215801Y440204D01*
X215726Y440308D01*
Y465926D01*
G02X215736Y465988I200J0D01*
G01X215751Y466035D01*
X215817Y466101D01*
X215862Y466116D01*
G03Y468962I-483J1423D01*
G01X215801Y468983D01*
X215726Y469087D01*
Y473013D01*
G02X215736Y473075I200J0D01*
G01X215751Y473122D01*
X215817Y473188D01*
X215862Y473203D01*
G03Y476049I-483J1423D01*
G01X215801Y476070D01*
X215726Y476174D01*
Y480099D01*
G02X215736Y480161I200J0D01*
G01X215751Y480208D01*
X215817Y480274D01*
X215862Y480289D01*
G03Y483135I-483J1423D01*
G01X215801Y483156D01*
X215726Y483260D01*
Y487186D01*
G02X215736Y487248I200J0D01*
G01X215751Y487295D01*
X215817Y487361D01*
X215862Y487376D01*
G03X216882Y488799I-483J1423D01*
G03X216467Y489835I-1501J0D01*
G01X216442Y489862D01*
X216410Y489937D01*
G02X216440Y490143I184J78D01*
G01X216447Y490151D01*
X241155Y514859D01*
G02X241157Y514861I142J-140D01*
G02X241297Y514918I140J-143D01*
G01X262002D01*
G02X262202Y514718I0J-200D01*
G01Y511471D01*
G03X262204Y511393I1803J7D01*
G01Y511390D01*
G02X262134Y511229I-200J-9D01*
G01X262038Y511148D01*
G02X261874Y511104I-129J153D01*
G01X261873D01*
G03X261606Y511128I-267J-1478D01*
G01X261605D01*
G03Y508124I0J-1502D01*
G03X263089Y509393I0J1502D01*
G01X263096Y509436D01*
X263140Y509505D01*
X263413Y509687D01*
G02X263524Y509720I110J-167D01*
G01X263580D01*
X263603Y509715D01*
G03X264004Y509668I409J1755D01*
G01X264006D01*
G03X264419Y509717I-4J1803D01*
G01X264430Y509720D01*
X264456Y509723D01*
G02X264590Y509691I23J-198D01*
G01X264870Y509505D01*
X264914Y509436D01*
X264921Y509393D01*
G03X266405Y508124I1484J233D01*
G03Y511128I0J1502D01*
G01X266403D01*
G03X266153Y511107I0J-1502D01*
G01X266136Y511104D01*
X266094Y511096D01*
X266012Y511117D01*
X265978Y511143D01*
X265974Y511146D01*
X265876Y511229D01*
G02X265806Y511390I130J152D01*
G01Y511393D01*
G03X265808Y511471I-1801J85D01*
G01Y514718D01*
G02X266008Y514918I200J0D01*
G01X273038D01*
X273108Y514890D01*
X273137Y514862D01*
X273337Y514670D01*
X273398Y514536D01*
G03X276398I1500J72D01*
G01X276459Y514670D01*
X276659Y514862D01*
G02X276798Y514918I139J-144D01*
G01X317051D01*
G02X317210Y514839I0J-200D01*
G01X317228Y514816D01*
X317233Y514809D01*
G03X318497Y514115I1264J804D01*
G03X318729Y514133I0J1502D01*
G01X318772Y514140D01*
X318856Y514116D01*
X319120Y513891D01*
G02X319190Y513739I-130J-152D01*
G01Y512539D01*
G02X319120Y512387I-200J0D01*
G01X318856Y512162D01*
X318772Y512138D01*
X318729Y512145D01*
G03X318497Y512163I-232J-1484D01*
G03Y509159I0J-1502D01*
G01X318498D01*
G03X319700Y509761I-1J1502D01*
G01X319721Y509789D01*
X319838Y509867D01*
X319875Y509875D01*
X319942Y509891D01*
G02X320038Y509889I44J-195D01*
G01X320100Y509873D01*
X320122Y509861D01*
G03X320993Y509636I872J1578D01*
G03X321885Y509873I-1J1803D01*
G01X321919Y509892D01*
X321994Y509903D01*
X322117Y509873D01*
X322153Y509865D01*
X322265Y509789D01*
X322286Y509761D01*
G03X323488Y509159I1203J900D01*
G01X323489D01*
G03Y512163I0J1502D01*
G03X323257Y512145I0J-1502D01*
G01X323214Y512138D01*
X323130Y512162D01*
X322866Y512387D01*
G02X322796Y512539I130J152D01*
G01Y513739D01*
G02X322866Y513891I200J0D01*
G01X323130Y514116D01*
X323214Y514140D01*
X323257Y514133D01*
G03X323489Y514115I232J1484D01*
G03X324753Y514809I0J1498D01*
G01X324758Y514816D01*
X324776Y514839D01*
G02X324935Y514918I159J-121D01*
G01X333450D01*
G02X333847Y514560I-1J-400D01*
G02X333843Y514492I-199J-22D01*
G02X333790Y514398I-194J48D01*
G01X297697Y478305D01*
G03X297638Y478164I141J-142D01*
G01Y465665D01*
G02X297580Y465524I-200J0D01*
G01X297087Y465030D01*
G02X297081Y465024I-144J138D01*
G02X296804Y465030I-135J147D01*
G01X296739Y465094D01*
G02X296737Y465096I140J142D01*
G01X296613Y465220D01*
G03X295011Y465884I-1603J-1602D01*
G03X294155Y465716I0J-2265D01*
G01X294134Y465717D01*
X293804Y465878D01*
X293752Y465938D01*
X293739Y465976D01*
G03X292316Y466995I-1423J-484D01*
G03X290813Y465492I0J-1503D01*
G03X292315Y463989I1503J0D01*
G01X292317D01*
G03X292357Y463990I-18J1503D01*
G01X292398Y463991D01*
X292436Y463976D01*
G02X292502Y463934I-72J-186D01*
G01X292713Y463732D01*
X292745Y463657D01*
Y463616D01*
G03X293170Y462296I2266J1D01*
G01X293189Y462270D01*
X293208Y462211D01*
Y461626D01*
X293189Y461566D01*
X293170Y461541D01*
G03X292832Y460839I1842J-1319D01*
G03X292746Y460273I2179J-621D01*
G01X292745Y460232D01*
X292728Y460195D01*
G02X292683Y460132I-182J82D01*
G01X292504Y459963D01*
G02X292438Y459921I-138J145D01*
G01X292398Y459906D01*
G03X292317Y459909I-96J-1500D01*
G01X292315D01*
G03X290813Y458406I1J-1503D01*
G03X292316Y456903I1503J0D01*
G03X293724Y457880I0J1503D01*
G01X293738Y457917D01*
X293765Y457947D01*
G02X293796Y457974I146J-137D01*
G02X293829Y457993I116J-163D01*
G01X294051Y458095D01*
G02X294129Y458113I83J-182D01*
G01X294168Y458114D01*
X294206Y458100D01*
X294207D01*
G03X295011Y457952I805J2118D01*
G03X296613Y458616I-1J2266D01*
G01X296815Y458818D01*
X296816D01*
X297076Y459078D01*
G02X297218Y459137I142J-141D01*
G01X299048D01*
G03X299189Y459196I-1J200D01*
G01X303191Y463198D01*
G03X303250Y463339I-141J142D01*
G01Y475838D01*
G02X303307Y475978I200J0D01*
G01X342188Y514859D01*
G02X342190Y514861I142J-140D01*
G02X342330Y514918I140J-143D01*
G37*
G36*
G01X225244Y1446675D02*
G03I-491J0D01*
G37*
G36*
G01X230236D02*
G03I-491J0D01*
G37*
G36*
G01X216956D02*
G03I-491J0D01*
G37*
G36*
G01X227740Y1445013D02*
G03I-491J0D01*
G37*
G36*
G01X216956Y1451631D02*
G03I-491J0D01*
G37*
G36*
G01Y1462631D02*
G03I-491J0D01*
G37*
G36*
G01Y1457675D02*
G03I-491J0D01*
G37*
G36*
G01X230236Y1462631D02*
G03I-491J0D01*
G37*
G36*
G01X225244Y1457675D02*
G03I-491J0D01*
G37*
G36*
G01Y1451631D02*
G03I-491J0D01*
G37*
G36*
G01X230236D02*
G03I-491J0D01*
G37*
G36*
G01Y1457675D02*
G03I-491J0D01*
G37*
G36*
G01X225244Y1462631D02*
G03I-491J0D01*
G37*
G36*
G01X227740Y1464293D02*
G03I-491J0D01*
G37*
G36*
G01Y1456013D02*
G03I-491J0D01*
G37*
G36*
G01Y1453293D02*
G03I-491J0D01*
G37*
G36*
G01X287304Y174205D02*
X290856D01*
G02X290996Y174148I0J-200D01*
G01X290997Y174147D01*
X293199Y171945D01*
G02X293201Y171943I-140J-142D01*
G02X293258Y171803I-143J-140D01*
G01Y147990D01*
G02X293148Y147811I-200J0D01*
G01X292830Y147650D01*
G02X292620Y147668I-90J178D01*
G03X291726Y147963I-894J-1207D01*
G03Y144959I0J-1502D01*
G03X292620Y145254I0J1502D01*
G02X292830Y145272I120J-161D01*
G01X293148Y145111D01*
G02X293258Y144932I-90J-179D01*
G01Y138227D01*
X293185Y138124D01*
X293125Y138103D01*
G03X292424Y137587I502J-1416D01*
G01X292403Y137559D01*
X292316Y137501D01*
G02X292249Y137473I-109J168D01*
G01X292130Y137446D01*
X292056Y137457D01*
X292023Y137475D01*
G03X291722Y137612I-894J-1565D01*
G03X291131Y137712I-592J-1703D01*
G03X290540Y137612I1J-1803D01*
G03X290239Y137475I593J-1702D01*
G01X290206Y137457D01*
X290132Y137446D01*
X290013Y137473D01*
G02X289946Y137501I42J196D01*
G01X289858Y137560D01*
X289838Y137588D01*
G03X288635Y138189I-1202J-901D01*
G01X288592D01*
X288591Y138188D01*
G03X287133Y136687I44J-1501D01*
G03X288635Y135185I1502J0D01*
G03X288867Y135203I0J1502D01*
G01X288910Y135210D01*
X288994Y135186D01*
X289292Y134932D01*
X289328Y134853D01*
Y133610D01*
Y133565D01*
X289292Y133486D01*
X288994Y133232D01*
X288910Y133208D01*
X288867Y133215D01*
G03X288632Y133233I-232J-1484D01*
G01X288631D01*
G03X287133Y131731I4J-1502D01*
G03X288635Y130229I1502J0D01*
G01X288636D01*
G03X289838Y130830I0J1502D01*
G01X289858Y130858D01*
X289946Y130917D01*
G02X290013Y130945I109J-168D01*
G01X290132Y130972D01*
X290206Y130961D01*
X290239Y130943D01*
G03X290540Y130806I894J1565D01*
G03X291131Y130706I592J1703D01*
G03X291722Y130806I-1J1803D01*
G03X292023Y130943I-593J1702D01*
G01X292056Y130961D01*
X292130Y130972D01*
X292249Y130945D01*
G02X292316Y130917I-42J-196D01*
G01X292403Y130859D01*
X292424Y130831D01*
G03X293125Y130315I1203J900D01*
G01X293185Y130294D01*
X293258Y130191D01*
Y124053D01*
X293185Y123950D01*
X293125Y123929D01*
G03X292424Y123413I502J-1416D01*
G01X292403Y123385D01*
X292316Y123327D01*
G02X292249Y123299I-109J168D01*
G01X292130Y123272D01*
X292056Y123283D01*
X292023Y123301D01*
G03X291722Y123438I-894J-1565D01*
G03X291131Y123538I-592J-1703D01*
G03X290540Y123438I1J-1803D01*
G03X290239Y123301I593J-1702D01*
G01X290206Y123283D01*
X290132Y123272D01*
X290013Y123299D01*
G02X289946Y123327I42J196D01*
G01X289858Y123386D01*
X289838Y123414D01*
G03X288635Y124015I-1202J-901D01*
G01X288592D01*
X288591Y124014D01*
G03X287133Y122513I44J-1501D01*
G03X288635Y121011I1502J0D01*
G03X288867Y121029I0J1502D01*
G01X288910Y121036D01*
X288994Y121012D01*
X289292Y120758D01*
X289328Y120679D01*
Y119436D01*
Y119391D01*
X289292Y119312D01*
X288994Y119058D01*
X288910Y119034D01*
X288867Y119041D01*
G03X288632Y119059I-232J-1484D01*
G01X288631D01*
G03X287133Y117557I4J-1502D01*
G03X288635Y116055I1502J0D01*
G01X288636D01*
G03X289838Y116656I0J1502D01*
G01X289858Y116684D01*
X289946Y116743D01*
G02X290013Y116771I109J-168D01*
G01X290132Y116798D01*
X290206Y116787D01*
X290239Y116769D01*
G03X290540Y116632I894J1565D01*
G03X291131Y116532I592J1703D01*
G03X291722Y116632I-1J1803D01*
G03X292023Y116769I-593J1702D01*
G01X292056Y116787D01*
X292130Y116798D01*
X292249Y116771D01*
G02X292316Y116743I-42J-196D01*
G01X292403Y116685D01*
X292424Y116657D01*
G03X293125Y116141I1203J900D01*
G01X293185Y116120D01*
X293258Y116017D01*
Y78102D01*
G02X293232Y78003I-200J0D01*
G01X293172Y77899D01*
X293140Y77865D01*
X293119Y77851D01*
G03X292681Y77421I811J-1264D01*
G01X292680Y77420D01*
Y77419D01*
G02X292546Y77334I-165J113D01*
G01X292257Y77288D01*
G02X292103Y77327I-32J197D01*
G03X291182Y77642I-920J-1187D01*
G01X291152D01*
G03X289680Y76140I30J-1502D01*
G03X291182Y74638I1502J0D01*
G01X291198D01*
X291258Y74639D01*
X291361Y74572D01*
X291528Y74174D01*
G02X291485Y73955I-184J-78D01*
G01X290031Y72501D01*
X290003Y72472D01*
X289929Y72442D01*
X243816D01*
G02X243674Y72501I0J200D01*
G01X242358Y73817D01*
X242329Y73845D01*
X242299Y73919D01*
Y100401D01*
G02X242303Y100441I200J0D01*
G01X242314Y100498D01*
X242330Y100535D01*
X242560Y100763D01*
G02X242701Y100821I141J-142D01*
G01X242712D01*
G03Y103825I0J1502D01*
G01X242701D01*
G02X242560Y103883I0J200D01*
G01X242358Y104083D01*
G02X242299Y104225I141J142D01*
G01Y107488D01*
G02X242303Y107528I200J0D01*
G01X242314Y107585D01*
X242330Y107622D01*
X242560Y107850D01*
G02X242701Y107908I141J-142D01*
G01X242712D01*
G03Y110912I0J1502D01*
G01X242701D01*
G02X242560Y110970I0J200D01*
G01X242358Y111170D01*
G02X242299Y111312I141J142D01*
G01Y114574D01*
G02X242303Y114614I200J0D01*
G01X242314Y114671D01*
X242330Y114708D01*
X242560Y114936D01*
G02X242701Y114994I141J-142D01*
G01X242712D01*
G03Y117998I0J1502D01*
G01X242701D01*
G02X242560Y118056I0J200D01*
G01X242358Y118256D01*
G02X242299Y118398I141J142D01*
G01Y121661D01*
G02X242303Y121701I200J0D01*
G01X242314Y121758D01*
X242330Y121795D01*
X242560Y122023D01*
G02X242701Y122081I141J-142D01*
G01X242712D01*
G03Y125085I0J1502D01*
G01X242701D01*
G02X242560Y125143I0J200D01*
G01X242358Y125343D01*
G02X242299Y125485I141J142D01*
G01Y128748D01*
G02X242303Y128788I200J0D01*
G01X242314Y128845D01*
X242330Y128882D01*
X242560Y129110D01*
G02X242701Y129168I141J-142D01*
G01X242712D01*
G03Y132172I0J1502D01*
G01X242701D01*
G02X242560Y132230I0J200D01*
G01X242358Y132430D01*
G02X242299Y132572I141J142D01*
G01Y135834D01*
G02X242303Y135874I200J0D01*
G01X242314Y135931D01*
X242330Y135968D01*
X242560Y136196D01*
G02X242701Y136254I141J-142D01*
G01X242712D01*
G03Y139258I0J1502D01*
G01X242701D01*
G02X242560Y139316I0J200D01*
G01X242358Y139516D01*
G02X242299Y139658I141J142D01*
G01Y172123D01*
G02X242356Y172263I200J0D01*
G01X242357Y172264D01*
X244239Y174146D01*
G02X244241Y174148I142J-140D01*
G02X244381Y174205I140J-143D01*
G01X284310D01*
G02X284496Y174078I0J-200D01*
G01X284655Y173673D01*
X284628Y173554D01*
X284582Y173512D01*
G03X284005Y172190I1226J-1322D01*
G03X287609I1802J0D01*
G03X287032Y173512I-1803J0D01*
G01X286986Y173554D01*
X286959Y173673D01*
X287118Y174078D01*
G02X287304Y174205I186J-73D01*
G37*
G36*
G01X239874Y1348187D02*
G03I-491J0D01*
G37*
G36*
G01Y1360099D02*
G03I-491J0D01*
G37*
G36*
G01Y1372385D02*
G03I-491J0D01*
G37*
G36*
G01Y1384297D02*
G03I-491J0D01*
G37*
G36*
G01X259994Y1348187D02*
G03I-491J0D01*
G37*
G36*
G01X252114D02*
G03I-491J0D01*
G37*
G36*
G01X247754D02*
G03I-491J0D01*
G37*
G36*
G01X259994Y1360099D02*
G03I-491J0D01*
G37*
G36*
G01X252114D02*
G03I-491J0D01*
G37*
G36*
G01X247754D02*
G03I-491J0D01*
G37*
G36*
G01X259994Y1372385D02*
G03I-491J0D01*
G37*
G36*
G01X252114D02*
G03I-491J0D01*
G37*
G36*
G01X247754D02*
G03I-491J0D01*
G37*
G36*
G01Y1384297D02*
G03I-491J0D01*
G37*
G36*
G01X259994D02*
G03I-491J0D01*
G37*
G36*
G01X252114D02*
G03I-491J0D01*
G37*
G36*
G01X259994Y1396583D02*
G03I-491J0D01*
G37*
G36*
G01X252114D02*
G03I-491J0D01*
G37*
G36*
G01X259994Y1408495D02*
G03I-491J0D01*
G37*
G36*
G01X252114D02*
G03I-491J0D01*
G37*
G36*
G01X342382Y54588D02*
X371080D01*
X371204Y54464D01*
Y52932D01*
X370863Y52591D01*
X342382D01*
G03X336445Y46654I0J-5937D01*
G01Y7874D01*
G02X330571Y2000I-5874J0D01*
G01X283327D01*
G02X277453Y7874I0J5874D01*
G01Y46126D01*
X279450D01*
Y7874D01*
G03X283325Y3998I3876J0D01*
G01X330571D01*
G03X334448Y7874I0J3877D01*
G01Y46654D01*
G02X342382Y54588I7934J0D01*
G37*
G36*
G01X272208Y1135600D02*
X281472D01*
G02X281614Y1135541I0J-200D01*
G01X282868Y1134287D01*
G03X282911Y1134254I142J141D01*
G01X282927Y1134239D01*
G03X283960Y1133810I1034J1032D01*
G01X287217D01*
G02X287417Y1133610I0J-200D01*
G01Y1126997D01*
G02X287217Y1126797I-200J0D01*
G01X279515D01*
G02X279373Y1126856I0J200D01*
G01X278902Y1127327D01*
X278900D01*
X278504Y1127723D01*
G02X278447Y1127885I142J141D01*
G01X278483Y1128238D01*
X278530Y1128315D01*
X278568Y1128340D01*
G03X279156Y1129429I-714J1089D01*
G03X276552I-1302J0D01*
G03X276748Y1128742I1302J0D01*
G01X276749Y1128741D01*
G02X276753Y1128539I-171J-104D01*
G01X276583Y1128233D01*
G02X276448Y1128134I-175J97D01*
G02X276408Y1128130I-40J196D01*
G01X272053D01*
G02X271911Y1128189I0J200D01*
G01X271821Y1128279D01*
G02X271762Y1128421I141J142D01*
G01Y1135155D01*
G02X271821Y1135297I200J0D01*
G01X272066Y1135542D01*
G02X272208Y1135600I141J-142D01*
G37*
G36*
G01X278623Y1176978D02*
X278972D01*
G02X279114Y1176919I0J-200D01*
G01X279270Y1176763D01*
Y1153028D01*
X279081Y1152839D01*
G02X278939Y1152780I-142J141D01*
G01X278828D01*
X278759Y1152807D01*
X278731Y1152832D01*
G03X276977I-877J-961D01*
G02X276842Y1152780I-135J148D01*
G01X276271D01*
G02X276129Y1152839I0J200D01*
G01X275617Y1153351D01*
G02X275558Y1153493I141J142D01*
G01Y1176443D01*
G02X275617Y1176585I200J0D01*
G01X275951Y1176919D01*
G02X276093Y1176978I142J-141D01*
G01X277057D01*
G02X277163Y1176948I1J-200D01*
G03X277854Y1176749I692J1103D01*
G03X278545Y1176948I-1J1302D01*
G01X278569Y1176963D01*
X278623Y1176978D01*
G37*
G36*
G01X276594Y1348187D02*
G03I-491J0D01*
G37*
G36*
G01X272234D02*
G03I-491J0D01*
G37*
G36*
G01X264354D02*
G03I-491J0D01*
G37*
G36*
G01X276594Y1360099D02*
G03I-491J0D01*
G37*
G36*
G01X272234D02*
G03I-491J0D01*
G37*
G36*
G01X264354D02*
G03I-491J0D01*
G37*
G36*
G01X276594Y1372385D02*
G03I-491J0D01*
G37*
G36*
G01X272234D02*
G03I-491J0D01*
G37*
G36*
G01X264354D02*
G03I-491J0D01*
G37*
G36*
G01X276594Y1396583D02*
G03I-491J0D01*
G37*
G36*
G01Y1384297D02*
G03I-491J0D01*
G37*
G36*
G01X272234D02*
G03I-491J0D01*
G37*
G36*
G01X264354D02*
G03I-491J0D01*
G37*
G36*
G01X272234Y1396583D02*
G03I-491J0D01*
G37*
G36*
G01X264354D02*
G03I-491J0D01*
G37*
G36*
G01X276594Y1408495D02*
G03I-491J0D01*
G37*
G36*
G01X272234D02*
G03I-491J0D01*
G37*
G36*
G01X264354D02*
G03I-491J0D01*
G37*
G36*
G01X288638Y429263D02*
X284843D01*
X283402D01*
X282163D01*
X281304Y430122D01*
Y446625D01*
X281916Y447237D01*
Y449811D01*
X281304Y450423D01*
Y456169D01*
X281813Y456678D01*
X287237D01*
X287664Y456251D01*
Y445974D01*
X288638Y445000D01*
Y429263D01*
G37*
G36*
G01X323044Y444701D02*
X353201D01*
G02X353343Y444642I0J-200D01*
G01X355292Y442693D01*
G02X355351Y442551I-141J-142D01*
G01Y411754D01*
G02X355292Y411612I-200J0D01*
G01X354644Y410964D01*
G02X354502Y410905I-142J141D01*
G01X335436D01*
G02X335294Y410964I0J200D01*
G01X321574Y424684D01*
G03X321432Y424743I-142J-141D01*
G01X304810D01*
G02X304668Y424802I0J200D01*
G01X300225Y429245D01*
G03X300083Y429304I-142J-141D01*
G01X289840D01*
G02X289640Y429504I0J200D01*
G01Y444223D01*
G02X289698Y444364I200J0D01*
G01X289976Y444642D01*
G02X290118Y444701I142J-141D01*
G01X296946D01*
G02X297095Y444635I0J-200D01*
G03X298507Y444006I1413J1273D01*
G03X299919Y444635I-1J1902D01*
G02X300068Y444701I149J-134D01*
G01X300795D01*
G02X300953Y444623I0J-200D01*
G03X302457Y443886I1503J1164D01*
G03X303961Y444623I1J1901D01*
G02X304119Y444701I158J-122D01*
G01X320054D01*
G02X320230Y444597I0J-200D01*
G03X322868I1319J718D01*
G02X323044Y444701I176J-96D01*
G37*
G36*
G01X280923Y1124859D02*
X287087D01*
G02X287229Y1124800I0J-200D01*
G01X287718Y1124311D01*
G02X287777Y1124169I-141J-142D01*
G01Y1122074D01*
G02X287776Y1122058I-200J4D01*
G03X287772Y1121949I1298J-102D01*
G01Y1121947D01*
G03X287776Y1121838I1302J-7D01*
G02X287777Y1121822I-199J-20D01*
G01Y1118334D01*
G02X287776Y1118318I-200J4D01*
G03X287772Y1118209I1298J-102D01*
G01Y1118207D01*
G03X287776Y1118098I1302J-7D01*
G02X287777Y1118082I-199J-20D01*
G01Y1117749D01*
Y1116519D01*
X287355Y1116097D01*
X282483D01*
X280912D01*
G02X280712Y1116297I0J200D01*
G01Y1122420D01*
Y1124648D01*
X280923Y1124859D01*
G37*
G36*
G01X290037Y1172000D02*
Y1151404D01*
G02X289978Y1151262I-200J0D01*
G01X289824Y1151108D01*
G02X289682Y1151049I-142J141D01*
G01X288785D01*
G02X288643Y1151108I0J200D01*
G01X288501Y1151250D01*
G02X288499Y1151252I140J142D01*
G03X288456Y1151295I-1296J-1253D01*
G02X288454Y1151297I140J142D01*
G01X287674Y1152077D01*
Y1178141D01*
X288240Y1178707D01*
G02X288382Y1178766I142J-141D01*
G01X289834D01*
X290900Y1177700D01*
X292600D01*
X293800Y1176500D01*
Y1173700D01*
X293300Y1173200D01*
X291237D01*
X290037Y1172000D01*
G37*
G36*
G01X281056Y1178697D02*
X282123D01*
X282347Y1178473D01*
X282375Y1178445D01*
Y1177028D01*
Y1151527D01*
X282288Y1151440D01*
X281847Y1150999D01*
X280749D01*
X280168Y1151580D01*
Y1152509D01*
Y1176397D01*
X280170Y1176400D01*
Y1177811D01*
X281056Y1178697D01*
G37*
G36*
G01X286766Y1175413D02*
Y1154266D01*
X286534Y1154034D01*
X283671D01*
X283474Y1154231D01*
Y1175304D01*
X283759Y1175589D01*
X286590D01*
X286766Y1175413D01*
G37*
G36*
G01X291932Y1167578D02*
X292127Y1167773D01*
G02X292269Y1167832I142J-141D01*
G01X297169D01*
G02X297311Y1167773I0J-200D01*
G01X297537Y1167547D01*
G02X297596Y1167405I-141J-142D01*
G01Y1158972D01*
G02X297537Y1158830I-200J0D01*
G01X297154Y1158447D01*
G02X297012Y1158388I-142J141D01*
G01X292362D01*
G02X292220Y1158447I0J200D01*
G01X291932Y1158735D01*
G02X291873Y1158877I141J142D01*
G01Y1167436D01*
G02X291932Y1167578I200J0D01*
G37*
G36*
G01X288834Y1348187D02*
G03I-491J0D01*
G37*
G36*
G01X284474D02*
G03I-491J0D01*
G37*
G36*
G01X288834Y1360099D02*
G03I-491J0D01*
G37*
G36*
G01X284474D02*
G03I-491J0D01*
G37*
G36*
G01X288834Y1372385D02*
G03I-491J0D01*
G37*
G36*
G01X284474D02*
G03I-491J0D01*
G37*
G36*
G01X288834Y1384297D02*
G03I-491J0D01*
G37*
G36*
G01Y1396583D02*
G03I-491J0D01*
G37*
G36*
G01X284474D02*
G03I-491J0D01*
G37*
G36*
G01Y1384297D02*
G03I-491J0D01*
G37*
G36*
G01X288834Y1408495D02*
G03I-491J0D01*
G37*
G36*
G01X284474D02*
G03I-491J0D01*
G37*
G36*
G01X281388Y1461182D02*
G03I-491J0D01*
G37*
G36*
G01X290049Y1460782D02*
G03I-491J0D01*
G37*
G36*
G01X281388Y1456451D02*
G03I-491J0D01*
G37*
G36*
G01Y1465913D02*
G03I-491J0D01*
G37*
G36*
G01X290049Y1465513D02*
G03I-491J0D01*
G37*
G36*
G01Y1480867D02*
G03I-491J0D01*
G37*
G36*
G01X281388Y1476536D02*
G03I-491J0D01*
G37*
G36*
G01X290049Y1476136D02*
G03I-491J0D01*
G37*
G36*
G01Y1470244D02*
G03I-491J0D01*
G37*
G36*
G01X281388Y1471805D02*
G03I-491J0D01*
G37*
G36*
G01Y1481267D02*
G03I-491J0D01*
G37*
G36*
G01X290049Y1485598D02*
G03I-491J0D01*
G37*
G36*
G01X281388Y1487160D02*
G03I-491J0D01*
G37*
G36*
G01Y1496622D02*
G03I-491J0D01*
G37*
G36*
G01X290049Y1496222D02*
G03I-491J0D01*
G37*
G36*
G01X281388Y1491891D02*
G03I-491J0D01*
G37*
G36*
G01X290049Y1491491D02*
G03I-491J0D01*
G37*
G36*
G01X281388Y1511976D02*
G03I-491J0D01*
G37*
G36*
G01Y1507245D02*
G03I-491J0D01*
G37*
G36*
G01X290049Y1506845D02*
G03I-491J0D01*
G37*
G36*
G01Y1500953D02*
G03I-491J0D01*
G37*
G36*
G01X281388Y1502514D02*
G03I-491J0D01*
G37*
G36*
G01X290049Y1511576D02*
G03I-491J0D01*
G37*
G36*
G01Y1516307D02*
G03I-491J0D01*
G37*
G36*
G01X281388Y1558813D02*
G03I-491J0D01*
G37*
G36*
G01X290049Y1578498D02*
G03I-491J0D01*
G37*
G36*
G01Y1572606D02*
G03I-491J0D01*
G37*
G36*
G01X281388Y1574167D02*
G03I-491J0D01*
G37*
G36*
G01Y1568275D02*
G03I-491J0D01*
G37*
G36*
G01Y1578898D02*
G03I-491J0D01*
G37*
G36*
G01Y1563544D02*
G03I-491J0D01*
G37*
G36*
G01X290049Y1563144D02*
G03I-491J0D01*
G37*
G36*
G01Y1567875D02*
G03I-491J0D01*
G37*
G36*
G01Y1583229D02*
G03I-491J0D01*
G37*
G36*
G01X281388Y1594253D02*
G03I-491J0D01*
G37*
G36*
G01X290049Y1593853D02*
G03I-491J0D01*
G37*
G36*
G01Y1587960D02*
G03I-491J0D01*
G37*
G36*
G01X281388Y1589522D02*
G03I-491J0D01*
G37*
G36*
G01Y1583629D02*
G03I-491J0D01*
G37*
G36*
G01Y1609607D02*
G03I-491J0D01*
G37*
G36*
G01X290049Y1609207D02*
G03I-491J0D01*
G37*
G36*
G01X281388Y1598984D02*
G03I-491J0D01*
G37*
G36*
G01X290049Y1598584D02*
G03I-491J0D01*
G37*
G36*
G01Y1603315D02*
G03I-491J0D01*
G37*
G36*
G01X281388Y1604876D02*
G03I-491J0D01*
G37*
G36*
G01Y1614338D02*
G03I-491J0D01*
G37*
G36*
G01X290049Y1613938D02*
G03I-491J0D01*
G37*
G36*
G01Y1618669D02*
G03I-491J0D01*
G37*
G36*
G01X310382Y1167234D02*
X310827Y1167679D01*
G02X310969Y1167738I142J-141D01*
G01X315931D01*
G02X316073Y1167679I0J-200D01*
G01X316268Y1167484D01*
G02X316327Y1167342I-141J-142D01*
G01Y1158940D01*
G02X316268Y1158798I-200J0D01*
G01X316011Y1158541D01*
G02X315869Y1158482I-142J141D01*
G01X311063D01*
G02X310921Y1158541I0J200D01*
G01X310382Y1159080D01*
G02X310323Y1159222I141J142D01*
G01Y1167092D01*
G02X310382Y1167234I200J0D01*
G37*
G36*
G01X301857Y1167906D02*
X308764D01*
G02X308904Y1167849I0J-200D01*
G01X308905Y1167848D01*
X309257Y1167496D01*
G02X309259Y1167494I-140J-142D01*
G02X309316Y1167354I-143J-140D01*
G01Y1160613D01*
G02X309197Y1160430I-200J0D01*
G01X308808Y1160257D01*
X308692Y1160276D01*
X308648Y1160316D01*
G03X307775Y1160652I-873J-966D01*
G03X306473Y1159350I0J-1302D01*
G03X306530Y1158967I1302J-2D01*
G01X306545Y1158922D01*
X306529Y1158828D01*
X306309Y1158531D01*
G02X306148Y1158450I-161J119D01*
G01X301922D01*
G02X301761Y1158531I0J200D01*
G01X301542Y1158827D01*
X301526Y1158920D01*
X301540Y1158966D01*
G03X301597Y1159350I-1245J381D01*
G03X300295Y1160652I-1302J0D01*
G01X300294D01*
G03X299303Y1160193I1J-1302D01*
G01X299302D01*
G02X299080Y1160134I-153J129D01*
G01X298729Y1160264D01*
G02X298598Y1160452I69J188D01*
G01Y1165728D01*
G02X298729Y1165916I200J0D01*
G01X299080Y1166046D01*
G02X299302Y1165987I69J-188D01*
G01X299303D01*
G03X300295Y1165528I992J842D01*
G01X300334D01*
Y1165529D01*
G03X301597Y1166830I-39J1301D01*
G01X301598D01*
G03X301491Y1167347I-1303J0D01*
G01X301490D01*
G02X301507Y1167537I184J79D01*
G01X301690Y1167816D01*
G02X301857Y1167906I167J-110D01*
G37*
G36*
G01X308954Y1348187D02*
G03I-491J0D01*
G37*
G36*
G01X301074D02*
G03I-491J0D01*
G37*
G36*
G01X296714D02*
G03I-491J0D01*
G37*
G36*
G01X308954Y1360099D02*
G03I-491J0D01*
G37*
G36*
G01X301074D02*
G03I-491J0D01*
G37*
G36*
G01X296714D02*
G03I-491J0D01*
G37*
G36*
G01X308954Y1372385D02*
G03I-491J0D01*
G37*
G36*
G01X301074D02*
G03I-491J0D01*
G37*
G36*
G01X296714D02*
G03I-491J0D01*
G37*
G36*
G01X308954Y1396583D02*
G03I-491J0D01*
G37*
G36*
G01X301074D02*
G03I-491J0D01*
G37*
G36*
G01Y1384297D02*
G03I-491J0D01*
G37*
G36*
G01X296714D02*
G03I-491J0D01*
G37*
G36*
G01Y1396583D02*
G03I-491J0D01*
G37*
G36*
G01X308954Y1384297D02*
G03I-491J0D01*
G37*
G36*
G01Y1408495D02*
G03I-491J0D01*
G37*
G36*
G01X301074D02*
G03I-491J0D01*
G37*
G36*
G01X296714D02*
G03I-491J0D01*
G37*
G36*
G01X298711Y1461182D02*
G03I-491J0D01*
G37*
G36*
G01X307372Y1460782D02*
G03I-491J0D01*
G37*
G36*
G01X298711Y1456451D02*
G03I-491J0D01*
G37*
G36*
G01X307372Y1470244D02*
G03I-491J0D01*
G37*
G36*
G01Y1480867D02*
G03I-491J0D01*
G37*
G36*
G01X298711Y1465913D02*
G03I-491J0D01*
G37*
G36*
G01X307372Y1465513D02*
G03I-491J0D01*
G37*
G36*
G01X298711Y1471805D02*
G03I-491J0D01*
G37*
G36*
G01Y1476536D02*
G03I-491J0D01*
G37*
G36*
G01Y1481267D02*
G03I-491J0D01*
G37*
G36*
G01X307372Y1476136D02*
G03I-491J0D01*
G37*
G36*
G01X298711Y1487160D02*
G03I-491J0D01*
G37*
G36*
G01Y1491891D02*
G03I-491J0D01*
G37*
G36*
G01Y1496622D02*
G03I-491J0D01*
G37*
G36*
G01X307372Y1491491D02*
G03I-491J0D01*
G37*
G36*
G01Y1485598D02*
G03I-491J0D01*
G37*
G36*
G01Y1496222D02*
G03I-491J0D01*
G37*
G36*
G01Y1511576D02*
G03I-491J0D01*
G37*
G36*
G01X298711Y1511976D02*
G03I-491J0D01*
G37*
G36*
G01Y1507245D02*
G03I-491J0D01*
G37*
G36*
G01Y1502514D02*
G03I-491J0D01*
G37*
G36*
G01X307372Y1506845D02*
G03I-491J0D01*
G37*
G36*
G01Y1500953D02*
G03I-491J0D01*
G37*
G36*
G01Y1516307D02*
G03I-491J0D01*
G37*
G36*
G01X298711Y1558813D02*
G03I-491J0D01*
G37*
G36*
G01X307372Y1567875D02*
G03I-491J0D01*
G37*
G36*
G01X298711Y1574167D02*
G03I-491J0D01*
G37*
G36*
G01X307372Y1578498D02*
G03I-491J0D01*
G37*
G36*
G01Y1572606D02*
G03I-491J0D01*
G37*
G36*
G01X298711Y1578898D02*
G03I-491J0D01*
G37*
G36*
G01Y1563544D02*
G03I-491J0D01*
G37*
G36*
G01X307372Y1563144D02*
G03I-491J0D01*
G37*
G36*
G01X298711Y1568275D02*
G03I-491J0D01*
G37*
G36*
G01Y1583629D02*
G03I-491J0D01*
G37*
G36*
G01X307372Y1583229D02*
G03I-491J0D01*
G37*
G36*
G01X298711Y1589522D02*
G03I-491J0D01*
G37*
G36*
G01Y1594253D02*
G03I-491J0D01*
G37*
G36*
G01X307372Y1593853D02*
G03I-491J0D01*
G37*
G36*
G01Y1587960D02*
G03I-491J0D01*
G37*
G36*
G01X298711Y1604876D02*
G03I-491J0D01*
G37*
G36*
G01Y1598984D02*
G03I-491J0D01*
G37*
G36*
G01X307372Y1609207D02*
G03I-491J0D01*
G37*
G36*
G01Y1598584D02*
G03I-491J0D01*
G37*
G36*
G01Y1603315D02*
G03I-491J0D01*
G37*
G36*
G01X298711Y1609607D02*
G03I-491J0D01*
G37*
G36*
G01X307372Y1618669D02*
G03I-491J0D01*
G37*
G36*
G01X298711Y1614338D02*
G03I-491J0D01*
G37*
G36*
G01X307372Y1613938D02*
G03I-491J0D01*
G37*
G36*
G01X325554Y1348187D02*
G03I-491J0D01*
G37*
G36*
G01X321194D02*
G03I-491J0D01*
G37*
G36*
G01X313314D02*
G03I-491J0D01*
G37*
G36*
G01X325554Y1360099D02*
G03I-491J0D01*
G37*
G36*
G01X321194D02*
G03I-491J0D01*
G37*
G36*
G01X313314D02*
G03I-491J0D01*
G37*
G36*
G01X325554Y1372385D02*
G03I-491J0D01*
G37*
G36*
G01X321194D02*
G03I-491J0D01*
G37*
G36*
G01X313314D02*
G03I-491J0D01*
G37*
G36*
G01X325554Y1396583D02*
G03I-491J0D01*
G37*
G36*
G01Y1384297D02*
G03I-491J0D01*
G37*
G36*
G01X321194D02*
G03I-491J0D01*
G37*
G36*
G01X313314D02*
G03I-491J0D01*
G37*
G36*
G01X321194Y1396583D02*
G03I-491J0D01*
G37*
G36*
G01X313314D02*
G03I-491J0D01*
G37*
G36*
G01X325554Y1408495D02*
G03I-491J0D01*
G37*
G36*
G01X321194D02*
G03I-491J0D01*
G37*
G36*
G01X313314D02*
G03I-491J0D01*
G37*
G36*
G01X316034Y1456451D02*
G03I-491J0D01*
G37*
G36*
G01Y1461182D02*
G03I-491J0D01*
G37*
G36*
G01X324695Y1460782D02*
G03I-491J0D01*
G37*
G36*
G01Y1470244D02*
G03I-491J0D01*
G37*
G36*
G01Y1480867D02*
G03I-491J0D01*
G37*
G36*
G01X316034Y1465913D02*
G03I-491J0D01*
G37*
G36*
G01X324695Y1465513D02*
G03I-491J0D01*
G37*
G36*
G01X316034Y1471805D02*
G03I-491J0D01*
G37*
G36*
G01Y1476536D02*
G03I-491J0D01*
G37*
G36*
G01Y1481267D02*
G03I-491J0D01*
G37*
G36*
G01X324695Y1476136D02*
G03I-491J0D01*
G37*
G36*
G01X316034Y1487160D02*
G03I-491J0D01*
G37*
G36*
G01Y1491891D02*
G03I-491J0D01*
G37*
G36*
G01Y1496622D02*
G03I-491J0D01*
G37*
G36*
G01X324695Y1491491D02*
G03I-491J0D01*
G37*
G36*
G01Y1485598D02*
G03I-491J0D01*
G37*
G36*
G01Y1496222D02*
G03I-491J0D01*
G37*
G36*
G01Y1500953D02*
G03I-491J0D01*
G37*
G36*
G01Y1511576D02*
G03I-491J0D01*
G37*
G36*
G01X316034Y1507245D02*
G03I-491J0D01*
G37*
G36*
G01Y1502514D02*
G03I-491J0D01*
G37*
G36*
G01Y1511976D02*
G03I-491J0D01*
G37*
G36*
G01X324695Y1506845D02*
G03I-491J0D01*
G37*
G36*
G01Y1516307D02*
G03I-491J0D01*
G37*
G36*
G01X316034Y1558813D02*
G03I-491J0D01*
G37*
G36*
G01Y1568275D02*
G03I-491J0D01*
G37*
G36*
G01Y1574167D02*
G03I-491J0D01*
G37*
G36*
G01X324695Y1567875D02*
G03I-491J0D01*
G37*
G36*
G01Y1578498D02*
G03I-491J0D01*
G37*
G36*
G01Y1572606D02*
G03I-491J0D01*
G37*
G36*
G01X316034Y1578898D02*
G03I-491J0D01*
G37*
G36*
G01Y1563544D02*
G03I-491J0D01*
G37*
G36*
G01X324695Y1563144D02*
G03I-491J0D01*
G37*
G36*
G01X316034Y1583629D02*
G03I-491J0D01*
G37*
G36*
G01Y1589522D02*
G03I-491J0D01*
G37*
G36*
G01Y1594253D02*
G03I-491J0D01*
G37*
G36*
G01X324695Y1583229D02*
G03I-491J0D01*
G37*
G36*
G01Y1593853D02*
G03I-491J0D01*
G37*
G36*
G01Y1587960D02*
G03I-491J0D01*
G37*
G36*
G01X316034Y1604876D02*
G03I-491J0D01*
G37*
G36*
G01Y1598984D02*
G03I-491J0D01*
G37*
G36*
G01X324695Y1609207D02*
G03I-491J0D01*
G37*
G36*
G01Y1598584D02*
G03I-491J0D01*
G37*
G36*
G01Y1603315D02*
G03I-491J0D01*
G37*
G36*
G01X316034Y1609607D02*
G03I-491J0D01*
G37*
G36*
G01Y1614338D02*
G03I-491J0D01*
G37*
G36*
G01X324695Y1613938D02*
G03I-491J0D01*
G37*
G36*
G01Y1618669D02*
G03I-491J0D01*
G37*
G36*
G01X396233Y448689D02*
X413028D01*
X413137Y448602D01*
X413152Y448533D01*
G03X414910Y447129I1758J399D01*
G03X416369Y447873I0J1803D01*
G01X416407Y447926D01*
X416530Y447966D01*
X416954Y447828D01*
G02X417092Y447638I-62J-190D01*
G01Y431715D01*
G02X417034Y431574I-200J0D01*
G01X416895Y431435D01*
G02X416753Y431376I-142J141D01*
G01X407715D01*
G03X407573Y431317I0J-200D01*
G01X406906Y430650D01*
G03X406847Y430508I141J-142D01*
G01Y426996D01*
G02X406788Y426854I-200J0D01*
G01X406363Y426429D01*
G02X406221Y426370I-142J141D01*
G01X388520D01*
G03X388378Y426311I0J-200D01*
G01X387896Y425829D01*
G03X387837Y425687I141J-142D01*
G01Y415233D01*
X387833Y415229D01*
Y400761D01*
G03X387892Y400619I200J0D01*
G01X389899Y398612D01*
G02X389958Y398470I-141J-142D01*
G01Y397832D01*
G02X389758Y397632I-200J0D01*
G01X387794D01*
G03X387653Y397574I0J-200D01*
G01X382016Y391937D01*
G03X381958Y391796I142J-141D01*
G01Y390227D01*
G02X381758Y390027I-200J0D01*
G01X372043D01*
G02X371868Y390129I-1J200D01*
G01X371670Y390480D01*
X371672Y390587D01*
X371701Y390634D01*
G03X371962Y391569I-1541J934D01*
G03X368358I-1802J0D01*
G03X368619Y390634I1802J-1D01*
G01X368648Y390587D01*
X368650Y390480D01*
X368452Y390129D01*
G02X368277Y390027I-174J98D01*
G01X343471D01*
G02X343329Y390086I0J200D01*
G01X341832Y391583D01*
G02X341773Y391725I141J142D01*
G01Y404332D01*
G02X341832Y404474I200J0D01*
G01X345678Y408320D01*
G02X345820Y408379I142J-141D01*
G01X355243D01*
G03X355385Y408438I0J200D01*
G01X356294Y409347D01*
G03X356353Y409489I-141J142D01*
G01Y438319D01*
G02X356473Y438503I200J1D01*
G01X356863Y438674D01*
X356980Y438654D01*
X357024Y438614D01*
G03X358042Y438216I1018J1103D01*
G03X359544Y439718I0J1502D01*
G03X359059Y440824I-1502J1D01*
G02X358994Y440971I135J148D01*
G01Y441265D01*
G02X359059Y441412I200J-1D01*
G03X359544Y442518I-1017J1105D01*
G03X358042Y444020I-1502J0D01*
G03X356728Y443246I0J-1502D01*
G01X356701Y443198D01*
X356608Y443142D01*
X356553D01*
G02X356353Y443342I0J200D01*
G01Y443764D01*
G02X356412Y443906I200J0D01*
G01X358252Y445746D01*
X358389Y445762D01*
X358449Y445725D01*
G03X359241Y445499I792J1275D01*
G03X360743Y447001I0J1502D01*
G03X360517Y447793I-1501J0D01*
G01X360480Y447853D01*
X360496Y447990D01*
X361152Y448646D01*
X361258Y448672D01*
X361312Y448655D01*
G03X361754Y448589I440J1436D01*
G03X362261Y448677I0J1502D01*
G01X362294Y448689D01*
X364414D01*
X364447Y448677D01*
G03X364954Y448589I507J1414D01*
G03X365461Y448677I0J1502D01*
G01X365494Y448689D01*
X366399D01*
X366501Y448620D01*
X366523Y448563D01*
G03X366902Y448012I1396J555D01*
G02X366967Y447865I-135J-148D01*
G01Y447571D01*
G02X366902Y447424I-200J1D01*
G03X366417Y446318I1017J-1105D01*
G03X369421I1502J0D01*
G03X368936Y447424I-1502J1D01*
G02X368871Y447571I135J148D01*
G01Y447865D01*
G02X368936Y448012I200J-1D01*
G03X369315Y448563I-1017J1106D01*
G01X369337Y448620D01*
X369439Y448689D01*
X374399D01*
X374501Y448620D01*
X374523Y448563D01*
G03X374902Y448012I1396J555D01*
G02X374967Y447865I-135J-148D01*
G01Y447571D01*
G02X374902Y447424I-200J1D01*
G03X374417Y446318I1017J-1105D01*
G03X377421I1502J0D01*
G03X376936Y447424I-1502J1D01*
G02X376871Y447571I135J148D01*
G01Y447865D01*
G02X376936Y448012I200J-1D01*
G03X377315Y448563I-1017J1106D01*
G01X377337Y448620D01*
X377439Y448689D01*
X384928D01*
X384967Y448671D01*
G03X385584Y448539I616J1370D01*
G03X386201Y448671I1J1502D01*
G01X386240Y448689D01*
X394921D01*
X394960Y448671D01*
G03X395577Y448539I616J1370D01*
G03X396194Y448671I1J1502D01*
G01X396233Y448689D01*
G37*
G36*
G01X370652Y1066535D02*
G02I-17700J0D01*
G37*
G36*
G01Y1263386D02*
G02I-17700J0D01*
G37*
G36*
G01X337794Y1348187D02*
G03I-491J0D01*
G37*
G36*
G01X333434D02*
G03I-491J0D01*
G37*
G36*
G01X337794Y1360099D02*
G03I-491J0D01*
G37*
G36*
G01X333434D02*
G03I-491J0D01*
G37*
G36*
G01X337794Y1372385D02*
G03I-491J0D01*
G37*
G36*
G01X333434D02*
G03I-491J0D01*
G37*
G36*
G01X337794Y1384297D02*
G03I-491J0D01*
G37*
G36*
G01Y1396583D02*
G03I-491J0D01*
G37*
G36*
G01X333434D02*
G03I-491J0D01*
G37*
G36*
G01Y1384297D02*
G03I-491J0D01*
G37*
G36*
G01X337794Y1408495D02*
G03I-491J0D01*
G37*
G36*
G01X333434D02*
G03I-491J0D01*
G37*
G36*
G01X333356Y1456451D02*
G03I-491J0D01*
G37*
G36*
G01Y1461182D02*
G03I-491J0D01*
G37*
G36*
G01X342018Y1460782D02*
G03I-491J0D01*
G37*
G36*
G01X333356Y1465913D02*
G03I-491J0D01*
G37*
G36*
G01X342018Y1476136D02*
G03I-491J0D01*
G37*
G36*
G01Y1470244D02*
G03I-491J0D01*
G37*
G36*
G01Y1480867D02*
G03I-491J0D01*
G37*
G36*
G01X333356Y1471805D02*
G03I-491J0D01*
G37*
G36*
G01Y1476536D02*
G03I-491J0D01*
G37*
G36*
G01Y1481267D02*
G03I-491J0D01*
G37*
G36*
G01X342018Y1465513D02*
G03I-491J0D01*
G37*
G36*
G01X333356Y1487160D02*
G03I-491J0D01*
G37*
G36*
G01Y1491891D02*
G03I-491J0D01*
G37*
G36*
G01Y1496622D02*
G03I-491J0D01*
G37*
G36*
G01X342018Y1491491D02*
G03I-491J0D01*
G37*
G36*
G01Y1485598D02*
G03I-491J0D01*
G37*
G36*
G01Y1496222D02*
G03I-491J0D01*
G37*
G36*
G01X333356Y1507245D02*
G03I-491J0D01*
G37*
G36*
G01Y1502514D02*
G03I-491J0D01*
G37*
G36*
G01Y1511976D02*
G03I-491J0D01*
G37*
G36*
G01X342018Y1506845D02*
G03I-491J0D01*
G37*
G36*
G01Y1500953D02*
G03I-491J0D01*
G37*
G36*
G01Y1511576D02*
G03I-491J0D01*
G37*
G36*
G01Y1516307D02*
G03I-491J0D01*
G37*
G36*
G01X333356Y1558813D02*
G03I-491J0D01*
G37*
G36*
G01Y1578898D02*
G03I-491J0D01*
G37*
G36*
G01Y1563544D02*
G03I-491J0D01*
G37*
G36*
G01X342018Y1563144D02*
G03I-491J0D01*
G37*
G36*
G01X333356Y1568275D02*
G03I-491J0D01*
G37*
G36*
G01Y1574167D02*
G03I-491J0D01*
G37*
G36*
G01X342018Y1567875D02*
G03I-491J0D01*
G37*
G36*
G01Y1578498D02*
G03I-491J0D01*
G37*
G36*
G01Y1572606D02*
G03I-491J0D01*
G37*
G36*
G01Y1583229D02*
G03I-491J0D01*
G37*
G36*
G01Y1593853D02*
G03I-491J0D01*
G37*
G36*
G01Y1587960D02*
G03I-491J0D01*
G37*
G36*
G01X333356Y1583629D02*
G03I-491J0D01*
G37*
G36*
G01Y1589522D02*
G03I-491J0D01*
G37*
G36*
G01Y1594253D02*
G03I-491J0D01*
G37*
G36*
G01X342018Y1603315D02*
G03I-491J0D01*
G37*
G36*
G01X333356Y1609607D02*
G03I-491J0D01*
G37*
G36*
G01Y1604876D02*
G03I-491J0D01*
G37*
G36*
G01Y1598984D02*
G03I-491J0D01*
G37*
G36*
G01X342018Y1609207D02*
G03I-491J0D01*
G37*
G36*
G01Y1598584D02*
G03I-491J0D01*
G37*
G36*
G01X333356Y1614338D02*
G03I-491J0D01*
G37*
G36*
G01X342018Y1613938D02*
G03I-491J0D01*
G37*
G36*
G01Y1618669D02*
G03I-491J0D01*
G37*
G36*
G01X389666Y174205D02*
X393218D01*
G02X393358Y174148I0J-200D01*
G01X393359Y174147D01*
X395561Y171945D01*
G02X395563Y171943I-140J-142D01*
G02X395620Y171803I-143J-140D01*
G01Y138227D01*
X395547Y138124D01*
X395487Y138103D01*
G03X394786Y137587I502J-1416D01*
G01X394765Y137559D01*
X394678Y137501D01*
G02X394611Y137473I-109J168D01*
G01X394492Y137446D01*
X394418Y137457D01*
X394385Y137475D01*
G03X394084Y137612I-894J-1565D01*
G03X393493Y137712I-592J-1703D01*
G03X392902Y137612I1J-1803D01*
G03X392601Y137475I593J-1702D01*
G01X392568Y137457D01*
X392494Y137446D01*
X392375Y137473D01*
G02X392308Y137501I42J196D01*
G01X392220Y137560D01*
X392200Y137588D01*
G03X390997Y138189I-1202J-901D01*
G01X390954D01*
X390953Y138188D01*
G03X389495Y136687I44J-1501D01*
G03X390997Y135185I1502J0D01*
G03X391229Y135203I0J1502D01*
G01X391272Y135210D01*
X391356Y135186D01*
X391654Y134932D01*
X391690Y134853D01*
Y133610D01*
Y133565D01*
X391654Y133486D01*
X391356Y133232D01*
X391272Y133208D01*
X391229Y133215D01*
G03X390994Y133233I-232J-1484D01*
G01X390993D01*
G03X389495Y131731I4J-1502D01*
G03X390997Y130229I1502J0D01*
G01X390998D01*
G03X392200Y130830I0J1502D01*
G01X392220Y130858D01*
X392308Y130917D01*
G02X392375Y130945I109J-168D01*
G01X392494Y130972D01*
X392568Y130961D01*
X392601Y130943D01*
G03X392902Y130806I894J1565D01*
G03X393493Y130706I592J1703D01*
G03X394084Y130806I-1J1803D01*
G03X394385Y130943I-593J1702D01*
G01X394418Y130961D01*
X394492Y130972D01*
X394611Y130945D01*
G02X394678Y130917I-42J-196D01*
G01X394765Y130859D01*
X394786Y130831D01*
G03X395487Y130315I1203J900D01*
G01X395547Y130294D01*
X395620Y130191D01*
Y124053D01*
X395547Y123950D01*
X395487Y123929D01*
G03X394786Y123413I502J-1416D01*
G01X394765Y123385D01*
X394678Y123327D01*
G02X394611Y123299I-109J168D01*
G01X394492Y123272D01*
X394418Y123283D01*
X394385Y123301D01*
G03X394084Y123438I-894J-1565D01*
G03X393493Y123538I-592J-1703D01*
G03X392902Y123438I1J-1803D01*
G03X392601Y123301I593J-1702D01*
G01X392568Y123283D01*
X392494Y123272D01*
X392375Y123299D01*
G02X392308Y123327I42J196D01*
G01X392220Y123386D01*
X392200Y123414D01*
G03X390997Y124015I-1202J-901D01*
G01X390954D01*
X390953Y124014D01*
G03X389495Y122513I44J-1501D01*
G03X390997Y121011I1502J0D01*
G03X391229Y121029I0J1502D01*
G01X391272Y121036D01*
X391356Y121012D01*
X391654Y120758D01*
X391690Y120679D01*
Y119436D01*
Y119391D01*
X391654Y119312D01*
X391356Y119058D01*
X391272Y119034D01*
X391229Y119041D01*
G03X390994Y119059I-232J-1484D01*
G01X390993D01*
G03X389495Y117557I4J-1502D01*
G03X390997Y116055I1502J0D01*
G01X390998D01*
G03X392200Y116656I0J1502D01*
G01X392220Y116684D01*
X392308Y116743D01*
G02X392375Y116771I109J-168D01*
G01X392494Y116798D01*
X392568Y116787D01*
X392601Y116769D01*
G03X392902Y116632I894J1565D01*
G03X393493Y116532I592J1703D01*
G03X394084Y116632I-1J1803D01*
G03X394385Y116769I-593J1702D01*
G01X394418Y116787D01*
X394492Y116798D01*
X394611Y116771D01*
G02X394678Y116743I-42J-196D01*
G01X394765Y116685D01*
X394786Y116657D01*
G03X395487Y116141I1203J900D01*
G01X395547Y116120D01*
X395620Y116017D01*
Y75811D01*
G02X395561Y75669I-200J0D01*
G01X395270Y75378D01*
G02X395020Y75352I-141J142D01*
G01X394960Y75392D01*
X394917Y75526D01*
X394943Y75593D01*
G03X395046Y76143I-1399J547D01*
G01Y76157D01*
G03X393544Y77642I-1502J-17D01*
G03Y74638I0J-1502D01*
G01X393560D01*
X393620Y74639D01*
X393723Y74572D01*
X393890Y74174D01*
G02X393847Y73955I-184J-78D01*
G01X392393Y72501D01*
X392365Y72472D01*
X392291Y72442D01*
X346178D01*
G02X346036Y72501I0J200D01*
G01X344720Y73817D01*
X344691Y73845D01*
X344661Y73919D01*
Y100421D01*
G02X344720Y100563I200J0D01*
G01X344922Y100763D01*
G02X345063Y100821I141J-142D01*
G01X345074D01*
G03Y103825I0J1502D01*
G01X345063D01*
G02X344922Y103883I0J200D01*
G01X344720Y104083D01*
G02X344661Y104225I141J142D01*
G01Y107508D01*
G02X344720Y107650I200J0D01*
G01X344922Y107850D01*
G02X345063Y107908I141J-142D01*
G01X345074D01*
G03Y110912I0J1502D01*
G01X345063D01*
G02X344922Y110970I0J200D01*
G01X344720Y111170D01*
G02X344661Y111312I141J142D01*
G01Y114594D01*
G02X344720Y114736I200J0D01*
G01X344922Y114936D01*
G02X345063Y114994I141J-142D01*
G01X345074D01*
G03Y117998I0J1502D01*
G01X345063D01*
G02X344922Y118056I0J200D01*
G01X344720Y118256D01*
G02X344661Y118398I141J142D01*
G01Y121681D01*
G02X344720Y121823I200J0D01*
G01X344922Y122023D01*
G02X345063Y122081I141J-142D01*
G01X345074D01*
G03Y125085I0J1502D01*
G01X345063D01*
G02X344922Y125143I0J200D01*
G01X344720Y125343D01*
G02X344661Y125485I141J142D01*
G01Y128768D01*
G02X344720Y128910I200J0D01*
G01X344922Y129110D01*
G02X345063Y129168I141J-142D01*
G01X345074D01*
G03Y132172I0J1502D01*
G01X345063D01*
G02X344922Y132230I0J200D01*
G01X344720Y132430D01*
G02X344661Y132572I141J142D01*
G01Y135854D01*
G02X344720Y135996I200J0D01*
G01X344922Y136196D01*
G02X345063Y136254I141J-142D01*
G01X345074D01*
G03Y139258I0J1502D01*
G01X345063D01*
G02X344922Y139316I0J200D01*
G01X344720Y139516D01*
G02X344661Y139658I141J142D01*
G01Y172123D01*
G02X344718Y172263I200J0D01*
G01X344719Y172264D01*
X346601Y174146D01*
G02X346603Y174148I142J-140D01*
G02X346743Y174205I140J-143D01*
G01X386672D01*
G02X386858Y174078I0J-200D01*
G01X387017Y173673D01*
X386990Y173554D01*
X386944Y173512D01*
G03X386367Y172190I1226J-1322D01*
G03X389971I1802J0D01*
G03X389394Y173512I-1803J0D01*
G01X389348Y173554D01*
X389321Y173673D01*
X389480Y174078D01*
G02X389666Y174205I186J-73D01*
G37*
G36*
G01X358557Y1159455D02*
G03I-610J0D01*
G37*
G36*
G01X357914Y1348187D02*
G03I-491J0D01*
G37*
G36*
G01X350034D02*
G03I-491J0D01*
G37*
G36*
G01X345674D02*
G03I-491J0D01*
G37*
G36*
G01X357914Y1360099D02*
G03I-491J0D01*
G37*
G36*
G01X350034D02*
G03I-491J0D01*
G37*
G36*
G01X345674D02*
G03I-491J0D01*
G37*
G36*
G01X357914Y1372385D02*
G03I-491J0D01*
G37*
G36*
G01X350034D02*
G03I-491J0D01*
G37*
G36*
G01X345674D02*
G03I-491J0D01*
G37*
G36*
G01X357914Y1396583D02*
G03I-491J0D01*
G37*
G36*
G01X350034D02*
G03I-491J0D01*
G37*
G36*
G01X357914Y1384297D02*
G03I-491J0D01*
G37*
G36*
G01X350034D02*
G03I-491J0D01*
G37*
G36*
G01X345674D02*
G03I-491J0D01*
G37*
G36*
G01Y1396583D02*
G03I-491J0D01*
G37*
G36*
G01X357914Y1408495D02*
G03I-491J0D01*
G37*
G36*
G01X350034D02*
G03I-491J0D01*
G37*
G36*
G01X345674D02*
G03I-491J0D01*
G37*
G36*
G01X350679Y1491891D02*
G03I-491J0D01*
G37*
G36*
G01Y1487160D02*
G03I-491J0D01*
G37*
G36*
G01Y1496622D02*
G03I-491J0D01*
G37*
G36*
G01Y1507246D02*
G03I-491J0D01*
G37*
G36*
G01Y1502515D02*
G03I-491J0D01*
G37*
G36*
G01Y1511977D02*
G03I-491J0D01*
G37*
G36*
G01Y1558813D02*
G03I-491J0D01*
G37*
G36*
G01Y1578898D02*
G03I-491J0D01*
G37*
G36*
G01Y1563544D02*
G03I-491J0D01*
G37*
G36*
G01Y1568275D02*
G03I-491J0D01*
G37*
G36*
G01Y1574167D02*
G03I-491J0D01*
G37*
G36*
G01Y1583629D02*
G03I-491J0D01*
G37*
G36*
G01Y1594253D02*
G03I-491J0D01*
G37*
G36*
G01Y1589522D02*
G03I-491J0D01*
G37*
G36*
G01Y1604876D02*
G03I-491J0D01*
G37*
G36*
G01Y1609607D02*
G03I-491J0D01*
G37*
G36*
G01Y1598984D02*
G03I-491J0D01*
G37*
G36*
G01Y1614338D02*
G03I-491J0D01*
G37*
G36*
G01X370154Y1348187D02*
G03I-491J0D01*
G37*
G36*
G01X362274D02*
G03I-491J0D01*
G37*
G36*
G01X370154Y1360099D02*
G03I-491J0D01*
G37*
G36*
G01X362274D02*
G03I-491J0D01*
G37*
G36*
G01X370154Y1372385D02*
G03I-491J0D01*
G37*
G36*
G01X362274D02*
G03I-491J0D01*
G37*
G36*
G01X370154Y1384297D02*
G03I-491J0D01*
G37*
G36*
G01X362274D02*
G03I-491J0D01*
G37*
G36*
G01X370154Y1396583D02*
G03I-491J0D01*
G37*
G36*
G01X362274D02*
G03I-491J0D01*
G37*
G36*
G01X370154Y1408495D02*
G03I-491J0D01*
G37*
G36*
G01X362274D02*
G03I-491J0D01*
G37*
G36*
G01X492382Y54588D02*
X520615D01*
X520833Y54370D01*
Y52809D01*
X520615Y52591D01*
X492382D01*
G03X486445Y46654I0J-5937D01*
G01Y7874D01*
G02X480571Y2000I-5874J0D01*
G01X385689D01*
G02X379815Y7874I0J5874D01*
G01Y46160D01*
X381812D01*
Y7874D01*
G03X385687Y3998I3876J0D01*
G01X480571D01*
G03X484448Y7874I0J3877D01*
G01Y46654D01*
G02X492382Y54588I7934J0D01*
G37*
G36*
G01X392995Y342555D02*
G03I-608J0D01*
G37*
G36*
G01Y337599D02*
G03I-608J0D01*
G37*
G36*
G01X421094Y446867D02*
X421120Y446893D01*
G02X421262Y446952I142J-141D01*
G01X426126D01*
X426199Y446922D01*
X426220Y446901D01*
X432147D01*
G02X432289Y446842I0J-200D01*
G01X436356Y442775D01*
X436383Y442670D01*
X436368Y442617D01*
G03X436296Y442114I1730J-504D01*
G03X437654Y440367I1803J0D01*
G01X437722Y440350D01*
X437805Y440243D01*
Y437014D01*
X437704Y436900D01*
X437628Y436891D01*
G03Y433311I207J-1790D01*
G01X437704Y433302D01*
X437805Y433188D01*
Y378675D01*
G02X437746Y378533I-200J0D01*
G01X433856Y374643D01*
G02X433714Y374584I-142J141D01*
G01X387324D01*
G02X387182Y374643I0J200D01*
G01X386018Y375807D01*
G02X385959Y375949I141J142D01*
G01Y378788D01*
X385961Y378801D01*
G03X385975Y379028I-1788J224D01*
G03X385961Y379255I-1802J3D01*
G01X385959Y379268D01*
Y390138D01*
G02X386018Y390280I200J0D01*
G01X389310Y393572D01*
G02X389452Y393631I142J-141D01*
G01X390611D01*
G02X390752Y393572I-1J-200D01*
G01X391265Y393059D01*
G03X391407Y393000I142J141D01*
G01X419910D01*
G03X420052Y393059I0J200D01*
G01X421933Y394940D01*
G03X421992Y395082I-141J142D01*
G01Y406278D01*
G03X421933Y406420I-200J0D01*
G01X418570Y409782D01*
G02X418512Y409924I142J141D01*
G01Y427310D01*
G02X418570Y427451I200J0D01*
G01X420968Y429849D01*
X421035Y429915D01*
G03X421094Y430057I-141J142D01*
G01Y446867D01*
G37*
G36*
G01X391628Y395610D02*
Y398285D01*
G03X391569Y398427I-200J0D01*
G01X388914Y401082D01*
G02X388855Y401224I141J142D01*
G01Y424378D01*
G02X388914Y424520I200J0D01*
G01X389662Y425268D01*
G02X389804Y425327I142J-141D01*
G01X407132D01*
G03X407274Y425386I0J200D01*
G01X407972Y426084D01*
G03X408031Y426226I-141J142D01*
G01Y429273D01*
G02X408090Y429415I200J0D01*
G01X408577Y429902D01*
G02X408719Y429961I142J-141D01*
G01X415542D01*
G02X415684Y429902I0J-200D01*
G01X416451Y429135D01*
G02X416510Y428993I-141J-142D01*
G01Y409095D01*
G03X416569Y408953I200J0D01*
G01X419931Y405591D01*
G02X419990Y405449I-141J-142D01*
G01Y395911D01*
G02X419931Y395769I-200J0D01*
G01X419223Y395061D01*
G02X419081Y395002I-142J141D01*
G01X392236D01*
G02X392094Y395061I0J200D01*
G01X391687Y395468D01*
G02X391628Y395610I141J142D01*
G37*
G36*
G01X386963Y915493D02*
X433390D01*
G02X433532Y915434I0J-200D01*
G01X434097Y914869D01*
G02X434156Y914727I-141J-142D01*
G01Y881193D01*
X434183Y881166D01*
Y839663D01*
G02X434124Y839521I-200J0D01*
G01X433548Y838945D01*
X433520Y838916D01*
X433446Y838886D01*
X388540D01*
G02X388398Y838945I0J200D01*
G01X385867Y841476D01*
X385838Y841504D01*
X385808Y841578D01*
Y862545D01*
G02X385882Y862700I200J0D01*
G01X386157Y862924D01*
X386243Y862945D01*
X386288Y862936D01*
G03X386589Y862906I299J1472D01*
G03Y865910I0J1502D01*
G03X386288Y865880I-2J-1502D01*
G01X386243Y865871D01*
X386157Y865892D01*
X385882Y866116D01*
X385847Y866145D01*
X385808Y866226D01*
Y914338D01*
G02X385867Y914480I200J0D01*
G01X386821Y915434D01*
G02X386963Y915493I142J-141D01*
G37*
G36*
G01X406055Y975776D02*
X434634D01*
G02X434776Y975717I0J-200D01*
G01X437457Y973037D01*
G03X437946Y972736I875J874D01*
G01X438008Y972716D01*
X438084Y972611D01*
Y918862D01*
G02X438025Y918720I-200J0D01*
G01X436015Y916710D01*
G02X435873Y916651I-142J141D01*
G01X378126D01*
G02X377984Y916710I0J200D01*
G01X377362Y917332D01*
G02X377303Y917474I141J142D01*
G01Y951840D01*
G02X377378Y951996I200J0D01*
G01X377658Y952220D01*
X377746Y952240D01*
X377790Y952230D01*
G03X378119Y952194I327J1466D01*
G03X379621Y953696I0J1502D01*
G03X379472Y954347I-1502J-1D01*
G01X379453Y954388D01*
X379452Y954476D01*
X379616Y954837D01*
X379683Y954895D01*
X379726Y954906D01*
G03X381047Y956643I-482J1737D01*
G03X379245Y958445I-1802J0D01*
G03X377983Y957929I0J-1801D01*
G01X377940Y957887D01*
X377822Y957864D01*
X377426Y958030D01*
G02X377303Y958215I77J185D01*
G01Y959998D01*
G02X377406Y960173I200J0D01*
G01X377761Y960369D01*
X377869Y960366D01*
X377916Y960336D01*
G03X378875Y960060I958J1526D01*
G03Y963664I0J1802D01*
G03X377916Y963388I-1J-1802D01*
G01X377869Y963358D01*
X377761Y963355D01*
X377406Y963551D01*
G02X377303Y963726I97J175D01*
G01Y965982D01*
G02X377409Y966159I200J0D01*
G01X377769Y966351D01*
X377879Y966346D01*
X377925Y966315D01*
G03X378928Y966010I1003J1497D01*
G03Y969614I0J1802D01*
G03X377925Y969309I0J-1802D01*
G01X377879Y969278D01*
X377769Y969273D01*
X377409Y969465D01*
G02X377303Y969642I94J177D01*
G01Y973423D01*
G02X377362Y973565I200J0D01*
G01X379514Y975717D01*
G02X379656Y975776I142J-141D01*
G01X402297D01*
G02X402448Y975706I-1J-200D01*
G01X402675Y975442D01*
X402699Y975358D01*
X402692Y975315D01*
G03X402674Y975084I1484J-232D01*
G03X403080Y974057I1502J0D01*
G01X403106Y974029D01*
X403134Y973960D01*
Y973608D01*
X403106Y973539D01*
X403080Y973511D01*
G03X402674Y972484I1096J-1027D01*
G03X403044Y971497I1501J0D01*
G01X403068Y971469D01*
X403093Y971402D01*
Y971066D01*
X403068Y970999D01*
X403044Y970971D01*
G03X402674Y969984I1131J-987D01*
G03X405678I1502J0D01*
G03X405308Y970971I-1501J0D01*
G01X405284Y970999D01*
X405259Y971066D01*
Y971402D01*
X405284Y971469D01*
X405308Y971497D01*
G03X405678Y972484I-1131J987D01*
G03X405272Y973511I-1502J0D01*
G01X405246Y973539D01*
X405218Y973608D01*
Y973960D01*
X405246Y974029D01*
X405272Y974057D01*
G03X405678Y975084I-1096J1027D01*
G03X405660Y975315I-1502J-1D01*
G01X405653Y975358D01*
X405677Y975442D01*
X405904Y975706D01*
G02X406055Y975776I152J-130D01*
G37*
G36*
G01X389066Y1254968D02*
X444903D01*
G02X445045Y1254909I0J-200D01*
G01X446053Y1253901D01*
G02X446112Y1253759I-141J-142D01*
G01Y1215829D01*
G02X446053Y1215687I-200J0D01*
G01X445599Y1215233D01*
X445571Y1215204D01*
X445497Y1215174D01*
X409516D01*
X408933Y1215757D01*
X404454D01*
X403871Y1215174D01*
X398003D01*
X395333D01*
X394917Y1214758D01*
X394076Y1213917D01*
Y1196747D01*
X396329Y1194494D01*
X397176D01*
X455945D01*
G02X456087Y1194435I0J-200D01*
G01X457130Y1193392D01*
G02X457188Y1193251I-142J-141D01*
G01Y1192422D01*
G03X457388Y1192222I200J0D01*
G01X457438D01*
G03X457873Y1191970I435J249D01*
G01X458533D01*
G02X458595Y1191927I-81J-183D01*
G01X464486Y1186036D01*
G02X464545Y1185894I-141J-142D01*
G01Y1157818D01*
G02X464486Y1157676I-200J0D01*
G01X464125Y1157315D01*
X464097Y1157286D01*
X464023Y1157256D01*
X378656D01*
X378582Y1157286D01*
X378554Y1157315D01*
X376901Y1158968D01*
G02X376842Y1159110I141J142D01*
G01Y1237884D01*
G02X376864Y1237975I200J0D01*
G01X376913Y1238072D01*
X376942Y1238106D01*
X376961Y1238120D01*
G03X388295Y1254247I-18810J25266D01*
G01X388303Y1254271D01*
X388327Y1254312D01*
X388924Y1254909D01*
G02X389066Y1254968I142J-141D01*
G37*
G36*
G01X462673Y1264194D02*
Y1258311D01*
X459346Y1254984D01*
Y1242973D01*
X462673Y1239646D01*
Y1215608D01*
G02X462614Y1215466I-200J0D01*
G01X462536Y1215388D01*
G02X462394Y1215329I-142J141D01*
G01X448536D01*
G02X448394Y1215388I0J200D01*
G01X448283Y1215499D01*
G02X448224Y1215641I141J142D01*
G01Y1254815D01*
G03X448165Y1254957I-200J0D01*
G01X446839Y1256283D01*
G03X446697Y1256342I-142J-141D01*
G01X393274D01*
G02X393132Y1256401I0J200D01*
G01X392624Y1256909D01*
G02X392565Y1257051I141J142D01*
G01Y1268751D01*
X393340Y1269526D01*
X405484D01*
X421338D01*
X423669Y1267195D01*
X423699D01*
X423969Y1266925D01*
X424368Y1266526D01*
X432278D01*
X434067Y1264738D01*
X462129D01*
X462673Y1264194D01*
G37*
G36*
G01X396287Y1404355D02*
X391929D01*
G03X391787Y1404296I0J-200D01*
G01X389638Y1402147D01*
Y1391706D01*
G02X389579Y1391564I-200J0D01*
G01X389526Y1391511D01*
G02X389384Y1391452I-142J141D01*
G01X385001D01*
G02X384859Y1391511I0J200D01*
G01X384261Y1392109D01*
G02X384202Y1392251I141J142D01*
G01Y1394301D01*
G02X384217Y1394378I200J1D01*
G01X390191Y1408796D01*
G02X390234Y1408861I185J-76D01*
G01X390965Y1409592D01*
G02X391107Y1409651I142J-141D01*
G01X396840D01*
G02X396982Y1409592I0J-200D01*
G01X397099Y1409475D01*
G02X397158Y1409333I-141J-142D01*
G01Y1405497D01*
G02X397068Y1405330I-200J0D01*
G03X396340Y1404432I1043J-1590D01*
G02X396296Y1404364I-186J72D01*
G01X396287Y1404355D01*
G37*
G36*
G01X391739Y1394590D02*
G02X391527Y1394789I-12J200D01*
G01Y1402127D01*
G02X391586Y1402269I200J0D01*
G01X391870Y1402553D01*
G02X392012Y1402612I142J-141D01*
G01X395935D01*
G02X396077Y1402553I0J-200D01*
G01X396831Y1401799D01*
G02X396890Y1401657I-141J-142D01*
G01Y1400170D01*
X396884Y1400146D01*
G03X396838Y1399779I1456J-369D01*
G03X396884Y1399412I1502J2D01*
G01X396890Y1399388D01*
Y1395823D01*
G02X396831Y1395681I-200J0D01*
G01X395801Y1394652D01*
G02X395659Y1394593I-142J141D01*
G01X391852D01*
G03X391740Y1394590I-2J-2002D01*
G01X391739D01*
G37*
G36*
G01X408431Y320854D02*
X414113D01*
X414469Y320498D01*
Y313380D01*
X414083Y312994D01*
X408756D01*
X408282Y313468D01*
Y320704D01*
X408431Y320854D01*
G37*
G36*
G01X402038Y320958D02*
X406392D01*
X407118Y320232D01*
Y313837D01*
X406941Y313660D01*
X401846D01*
X399764D01*
X398227Y315197D01*
Y320576D01*
X398609Y320958D01*
X402038D01*
G37*
G36*
G01X412521Y336490D02*
X418109D01*
G02X418251Y336431I0J-200D01*
G01X418556Y336126D01*
G02X418614Y335985I-142J-141D01*
G01Y330345D01*
G03X418673Y330204I200J1D01*
G01X419796Y329081D01*
G03X419937Y329022I142J141D01*
G01X436351D01*
G03X436492Y329081I-1J200D01*
G01X436605Y329193D01*
G02X436746Y329252I142J-141D01*
G01X437539D01*
G03X437681Y329311I0J200D01*
G01X438068Y329698D01*
G03X438127Y329840I-141J142D01*
G01Y335310D01*
G02X438186Y335452I200J0D01*
G01X438702Y335968D01*
G02X438844Y336027I142J-141D01*
G01X443899D01*
G02X444041Y335968I0J-200D01*
G01X444457Y335552D01*
G02X444516Y335410I-141J-142D01*
G01Y323212D01*
X444514Y323210D01*
Y320751D01*
Y317504D01*
X442555Y315545D01*
X421190D01*
X417768Y318967D01*
G02X417626Y319026I0J200D01*
G01X415071Y321581D01*
G03X414929Y321640I-142J-141D01*
G01X414826D01*
G02X414685Y321699I1J200D01*
G01X414586Y321797D01*
G03X414445Y321856I-142J-141D01*
G01X408099D01*
G03X407958Y321797I1J-200D01*
G01X407831Y321670D01*
X407758Y321640D01*
X407740D01*
X407479Y321901D01*
G03X407338Y321960I-142J-141D01*
G01X403630D01*
G02X403489Y322018I0J200D01*
G01X403204Y322303D01*
G02X403145Y322445I141J142D01*
G01Y328745D01*
G02X403204Y328887I200J0D01*
G01X403670Y329353D01*
G02X403812Y329412I142J-141D01*
G01X410854D01*
G03X410996Y329471I0J200D01*
G01X411133Y329608D01*
G02X411278Y329667I142J-141D01*
G01X411608Y329660D01*
X411682Y329627D01*
X411710Y329597D01*
G03X412812Y329115I1102J1019D01*
G03Y332119I0J1502D01*
G03X411860Y331779I0J-1503D01*
G02X411667Y331745I-127J155D01*
G01X411553Y331785D01*
G02X411423Y331935I66J189D01*
G03X411389Y332078I-1768J-345D01*
G01X411382Y332104D01*
Y334818D01*
G02X411476Y334988I200J0D01*
G03X412307Y336299I-958J1526D01*
G01X412311Y336333D01*
X412340Y336392D01*
X412379Y336431D01*
G02X412521Y336490I142J-141D01*
G37*
G36*
G01X418254Y356639D02*
X426483D01*
G02X426625Y356580I0J-200D01*
G01X427337Y355868D01*
G02X427396Y355726I-141J-142D01*
G01Y354854D01*
G02X427337Y354712I-200J0D01*
G01X425725Y353100D01*
G03X425666Y352958I141J-142D01*
G01Y350195D01*
G02X425607Y350053I-200J0D01*
G01X425443Y349889D01*
G02X425302Y349830I-142J141D01*
G01X420025D01*
G03X419884Y349772I0J-200D01*
G01X418673Y348561D01*
G03X418614Y348420I141J-142D01*
G01Y342197D01*
G02X418556Y342056I-200J0D01*
G01X417572Y341072D01*
G02X417430Y341013I-142J141D01*
G01X408717D01*
G02X408575Y341072I0J200D01*
G01X406871Y342776D01*
G02X406812Y342918I141J142D01*
G01Y351447D01*
G02X406871Y351589I200J0D01*
G01X408015Y352733D01*
X408053Y352748D01*
G03X408887Y353582I-560J1394D01*
G01X408902Y353620D01*
X410299Y355017D01*
X410407Y355043D01*
X410461Y355026D01*
G03X411007Y354941I547J1717D01*
G03X412788Y356469I0J1802D01*
G01X412799Y356543D01*
X412911Y356639D01*
X414894D01*
G02X415062Y356548I0J-200D01*
G03X418086I1512J980D01*
G02X418254Y356639I168J-109D01*
G37*
G36*
G01X410820Y725008D02*
X441793D01*
G02X441899Y724977I-1J-200D01*
G03X443103Y724632I1202J1922D01*
G01X473013D01*
G02X473154Y724573I-1J-200D01*
G01X475277Y722450D01*
G02X475336Y722308I-141J-142D01*
G01Y642592D01*
G02X475277Y642450I-200J0D01*
G01X470812Y637985D01*
G03X470753Y637843I141J-142D01*
G01Y609556D01*
G03X470768Y609479I200J-1D01*
G01X470797Y609411D01*
G02X470812Y609334I-185J-76D01*
G01Y581127D01*
G02X470753Y580985I-200J0D01*
G01X468971Y579203D01*
G02X468829Y579144I-142J141D01*
G01X410870D01*
X410797Y579174D01*
X410774Y579197D01*
X401345D01*
G02X401203Y579256I0J200D01*
G01X396480Y583979D01*
G02X396421Y584121I141J142D01*
G01Y710609D01*
G02X396480Y710751I200J0D01*
G01X410678Y724949D01*
G02X410820Y725008I142J-141D01*
G37*
G36*
G01X400223Y1096020D02*
Y1058207D01*
Y1056753D01*
X400887Y1056089D01*
X400925D01*
X401286Y1055728D01*
X402801D01*
X402808Y1055735D01*
X420495D01*
X420862Y1056102D01*
Y1058821D01*
Y1071074D01*
G02X420921Y1071216I200J0D01*
G01X421135Y1071430D01*
G02X421277Y1071489I142J-141D01*
G01X441969D01*
G03X442111Y1071548I0J200D01*
G01X443469Y1072906D01*
G03X443528Y1073048I-141J142D01*
G01Y1097275D01*
X440505Y1100298D01*
G02X440446Y1100440I141J142D01*
G01Y1104783D01*
G02X440505Y1104925I200J0D01*
G01X440547Y1104967D01*
G02X440689Y1105026I142J-141D01*
G01X445911D01*
G02X446053Y1104967I0J-200D01*
G01X447764Y1103256D01*
G03X447906Y1103197I142J141D01*
G01X451733D01*
G02X451875Y1103138I0J-200D01*
G01X455048Y1099965D01*
G03X455190Y1099906I142J141D01*
G01X464861D01*
G02X465003Y1099847I0J-200D01*
G01X465777Y1099073D01*
G02X465836Y1098931I-141J-142D01*
G01Y1072748D01*
G03X465895Y1072606I200J0D01*
G01X467437Y1071063D01*
G03X467579Y1071004I142J141D01*
G01X488084D01*
G02X488226Y1070945I0J-200D01*
G01X488497Y1070674D01*
G02X488556Y1070532I-141J-142D01*
G01Y1058768D01*
Y1057727D01*
X489492Y1056791D01*
X489910Y1056373D01*
X490762Y1055521D01*
X508010D01*
X508948Y1056459D01*
Y1056933D01*
Y1058999D01*
Y1088246D01*
G02X508963Y1088322I200J0D01*
G01X508979Y1088360D01*
Y1092827D01*
X508953Y1092853D01*
Y1097554D01*
G03X508894Y1097696I-200J0D01*
G01X506292Y1100298D01*
G02X506233Y1100440I141J142D01*
G01Y1104783D01*
G02X506292Y1104925I200J0D01*
G01X506334Y1104967D01*
G02X506476Y1105026I142J-141D01*
G01X511698D01*
G02X511840Y1104967I0J-200D01*
G01X513551Y1103256D01*
G03X513693Y1103197I142J141D01*
G01X517520D01*
G02X517662Y1103138I0J-200D01*
G01X520844Y1099956D01*
G03X520986Y1099897I142J141D01*
G01X523779D01*
G02X523921Y1099838I0J-200D01*
G01X524539Y1099220D01*
G02X524598Y1099078I-141J-142D01*
G01Y1097855D01*
G02X524539Y1097713I-200J0D01*
G01X519698Y1092873D01*
G03X519639Y1092731I141J-142D01*
G01Y1051222D01*
G02X519580Y1051080I-200J0D01*
G01X519373Y1050873D01*
X519345Y1050844D01*
X519271Y1050814D01*
X396153D01*
G02X396011Y1050873I0J200D01*
G01X394141Y1052743D01*
X394112Y1052771D01*
X394082Y1052845D01*
Y1095883D01*
Y1097699D01*
X394926Y1098543D01*
X399853D01*
X400223Y1098173D01*
Y1096020D01*
G37*
G36*
G01X401704Y1059146D02*
Y1069654D01*
X402767Y1070717D01*
X418682D01*
X419651Y1069748D01*
Y1059792D01*
Y1058249D01*
X418495Y1057093D01*
X402954D01*
X401704Y1058343D01*
Y1059146D01*
G37*
G36*
G01X434271Y1120863D02*
X447510D01*
G02X447652Y1120804I0J-200D01*
G01X447979Y1120477D01*
G02X448038Y1120335I-141J-142D01*
G01Y1107335D01*
G02X447979Y1107193I-200J0D01*
G01X446853Y1106067D01*
G02X446711Y1106008I-142J141D01*
G01X446428D01*
X446409Y1106028D01*
X440274D01*
G03X440133Y1105969I1J-200D01*
G01X439503Y1105339D01*
G03X439444Y1105198I141J-142D01*
G01Y1100025D01*
G03X439503Y1099884I200J1D01*
G01X442175Y1097211D01*
G02X442234Y1097070I-141J-142D01*
G01Y1097016D01*
X442248Y1097002D01*
X442278Y1096929D01*
Y1073275D01*
G02X442219Y1073133I-200J0D01*
G01X441782Y1072696D01*
G02X441640Y1072637I-142J141D01*
G01X402610D01*
G02X402468Y1072696I0J200D01*
G01X401754Y1073410D01*
G02X401695Y1073552I141J142D01*
G01Y1104857D01*
G03X401697Y1104889I-1497J110D01*
G03Y1104903I-200J7D01*
G03X401695Y1104935I-1499J-78D01*
G01Y1120414D01*
G02X401754Y1120556I200J0D01*
G01X402002Y1120804D01*
G02X402144Y1120863I142J-141D01*
G01X415605D01*
G02X415747Y1120804I0J-200D01*
G01X415851Y1120700D01*
G02X415910Y1120558I-141J-142D01*
G01Y1107335D01*
G02X415851Y1107193I-200J0D01*
G01X414725Y1106067D01*
G02X414583Y1106008I-142J141D01*
G01X414300D01*
X414281Y1106028D01*
X408146D01*
G03X408005Y1105969I1J-200D01*
G01X407375Y1105339D01*
G03X407316Y1105198I141J-142D01*
G01Y1100025D01*
G03X407375Y1099884I200J1D01*
G01X410828Y1096431D01*
G03X410969Y1096372I142J141D01*
G01X426237D01*
G03X426378Y1096431I-1J200D01*
G01X426402Y1096455D01*
X426475Y1096485D01*
X429307D01*
G03X429449Y1096544I0J200D01*
G01X433764Y1100859D01*
G03X433823Y1101001I-141J142D01*
G01Y1120415D01*
G02X433882Y1120557I200J0D01*
G01X434129Y1120804D01*
G02X434271Y1120863I142J-141D01*
G37*
G36*
G01X417619Y1097374D02*
X411301D01*
X408318Y1100357D01*
Y1104866D01*
X408478Y1105026D01*
X413866D01*
X415636Y1103256D01*
G03X415778Y1103197I142J141D01*
G01X417919D01*
X419688D01*
X420865Y1102020D01*
X423076Y1099809D01*
X424984D01*
X425524D01*
X426062Y1099271D01*
Y1097531D01*
X425905Y1097374D01*
X420440D01*
X417619D01*
G37*
G36*
G01X402408Y1156179D02*
X546946D01*
X547020Y1156149D01*
X547048Y1156120D01*
X548299Y1154869D01*
G02X548358Y1154727I-141J-142D01*
G01Y1124093D01*
X548328Y1124019D01*
X548299Y1123991D01*
X547677Y1123369D01*
X547649Y1123340D01*
X547575Y1123310D01*
X524806D01*
G03X524664Y1123251I0J-200D01*
G01X522069Y1120656D01*
G03X522010Y1120514I141J-142D01*
G01Y1113752D01*
G02X521956Y1113616I-200J1D01*
G03X521741Y1113226I649J-612D01*
G01Y1113225D01*
G02X521688Y1113133I-194J50D01*
G01X521545Y1112990D01*
G02X521403Y1112931I-142J141D01*
G01X521107D01*
G03X520967Y1112873I1J-200D01*
G01X520966Y1112872D01*
X520933Y1112840D01*
G02X520794Y1112784I-139J144D01*
G01X514955D01*
X514932Y1112807D01*
Y1121516D01*
G03X514873Y1121658I-200J0D01*
G01X514536Y1121995D01*
G03X514394Y1122054I-142J-141D01*
G01X502494D01*
G03X502352Y1121995I0J-200D01*
G01X502309Y1121952D01*
G02X502167Y1121893I-142J141D01*
G01X499960D01*
X499445Y1122408D01*
Y1126788D01*
X500569Y1127913D01*
G03X500628Y1128054I-141J142D01*
G01Y1129464D01*
G03X500569Y1129605I-200J-1D01*
G01X499573Y1130601D01*
X499238Y1130936D01*
X496082D01*
G03X495941Y1130995I-142J-141D01*
G01X494531D01*
G03X494390Y1130936I1J-200D01*
G01X491690Y1128236D01*
G03X491631Y1128095I141J-142D01*
G01Y1125282D01*
Y1122263D01*
X491261Y1121893D01*
G03X491119Y1121834I0J-200D01*
G01X489941Y1120656D01*
G03X489882Y1120514I141J-142D01*
G01Y1113743D01*
G02X489827Y1113606I-200J1D01*
G03X489612Y1113223I646J-615D01*
G01X489605Y1113197D01*
X489579Y1113152D01*
X489463Y1113036D01*
X489435Y1113007D01*
X489361Y1112977D01*
X488668D01*
G03X488527Y1112918I1J-200D01*
G01X488451Y1112843D01*
G02X488449Y1112841I-142J140D01*
G01X488448Y1112840D01*
G02X488309Y1112784I-139J144D01*
G01X482827D01*
X482804Y1112807D01*
Y1121516D01*
G03X482745Y1121658I-200J0D01*
G01X482408Y1121995D01*
G03X482266Y1122054I-142J-141D01*
G01X467826D01*
G02X467684Y1122113I0J200D01*
G01X467306Y1122491D01*
G03X467164Y1122550I-142J-141D01*
G01X458604D01*
G03X458462Y1122491I0J-200D01*
G01X456482Y1120511D01*
G03X456423Y1120369I141J-142D01*
G01Y1114080D01*
G02X456364Y1113938I-200J0D01*
G01X455269Y1112843D01*
X455241Y1112814D01*
X455167Y1112784D01*
X449368D01*
X449345Y1112807D01*
Y1121516D01*
G03X449286Y1121658I-200J0D01*
G01X448949Y1121995D01*
G03X448807Y1122054I-142J-141D01*
G01X436907D01*
G03X436765Y1121995I0J-200D01*
G01X436722Y1121952D01*
G02X436580Y1121893I-142J141D01*
G01X434749D01*
X434122Y1122520D01*
Y1127025D01*
X434812Y1127715D01*
Y1129453D01*
X434739Y1129526D01*
G03X434680Y1129667I-200J-1D01*
G01X433684Y1130663D01*
X433413Y1130934D01*
X430194D01*
G03X430053Y1130993I-142J-141D01*
G01X428643D01*
G03X428502Y1130934I1J-200D01*
G01X426155Y1128587D01*
G03X426096Y1128446I141J-142D01*
G01Y1125187D01*
Y1122191D01*
X425798Y1121893D01*
G03X425656Y1121834I0J-200D01*
G01X424354Y1120532D01*
G03X424295Y1120390I141J-142D01*
G01Y1113833D01*
G02X424236Y1113691I-200J0D01*
G01X423388Y1112843D01*
G02X423246Y1112784I-142J141D01*
G01X417240D01*
X417217Y1112807D01*
Y1121516D01*
G03X417158Y1121658I-200J0D01*
G01X416821Y1121995D01*
G03X416679Y1122054I-142J-141D01*
G01X404779D01*
G03X404637Y1121995I0J-200D01*
G01X404594Y1121952D01*
G02X404452Y1121893I-142J141D01*
G01X402400D01*
G02X402258Y1121952I0J200D01*
G01X401691Y1122519D01*
G02X401632Y1122661I141J142D01*
G01Y1133253D01*
G02X401666Y1133366I200J1D01*
G03X401667Y1148680I-11313J7658D01*
G01X401666Y1148681D01*
X401649Y1148707D01*
X401640Y1148736D01*
G02X401632Y1148793I192J56D01*
G01Y1155403D01*
G02X401691Y1155545I200J0D01*
G01X402266Y1156120D01*
G02X402408Y1156179I142J-141D01*
G37*
G36*
G01X398159Y1213821D02*
G02X398301Y1213880I142J-141D01*
G01X404817D01*
X405533Y1214596D01*
X407598D01*
X408314Y1213880D01*
X409516D01*
X504842D01*
X505636Y1214674D01*
X506951D01*
X507745Y1213880D01*
X518104D01*
X518956Y1214732D01*
X520466D01*
X521318Y1213880D01*
X526908D01*
X527730Y1214702D01*
X531826D01*
X531999Y1214529D01*
Y1196594D01*
X531571Y1196166D01*
X529328D01*
G02X529186Y1196107I-142J141D01*
G01X471130D01*
G02X470988Y1196166I0J200D01*
G01X470489Y1196665D01*
G02X470430Y1196807I141J142D01*
G01Y1200622D01*
G03X470371Y1200764I-200J0D01*
G01X469528Y1201607D01*
G03X469386Y1201666I-142J-141D01*
G01X457185D01*
G03X457043Y1201607I0J-200D01*
G01X456411Y1200975D01*
G03X456352Y1200833I141J-142D01*
G01Y1196307D01*
G02X456152Y1196107I-200J0D01*
G01X397928D01*
X396338D01*
X396201Y1196244D01*
X395593Y1196852D01*
Y1213245D01*
X396169Y1213821D01*
X398159D01*
G37*
G36*
G01X399102Y1293373D02*
Y1289015D01*
G03X399161Y1288873I200J0D01*
G01X401310Y1286724D01*
X411751D01*
G02X411893Y1286665I0J-200D01*
G01X411946Y1286612D01*
G02X412005Y1286470I-141J-142D01*
G01Y1282087D01*
G02X411946Y1281945I-200J0D01*
G01X411348Y1281347D01*
G02X411206Y1281288I-142J141D01*
G01X409156D01*
G02X409079Y1281303I-1J200D01*
G01X394661Y1287277D01*
G02X394596Y1287320I76J185D01*
G01X393865Y1288051D01*
G02X393806Y1288193I141J142D01*
G01Y1293926D01*
G02X393865Y1294068I200J0D01*
G01X393982Y1294185D01*
G02X394124Y1294244I142J-141D01*
G01X397960D01*
G02X398127Y1294154I0J-200D01*
G03X399025Y1293426I1590J1043D01*
G02X399093Y1293382I-72J-186D01*
G01X399102Y1293373D01*
G37*
G36*
G01X408867Y1288825D02*
G02X408668Y1288613I-200J-12D01*
G01X401330D01*
G02X401188Y1288672I0J200D01*
G01X400904Y1288956D01*
G02X400845Y1289098I141J142D01*
G01Y1293021D01*
G02X400904Y1293163I200J0D01*
G01X401658Y1293917D01*
G02X401800Y1293976I142J-141D01*
G01X403287D01*
X403311Y1293970D01*
G03X403678Y1293924I369J1456D01*
G03X404045Y1293970I-2J1502D01*
G01X404069Y1293976D01*
X407634D01*
G02X407776Y1293917I0J-200D01*
G01X408805Y1292887D01*
G02X408864Y1292745I-141J-142D01*
G01Y1288938D01*
G03X408867Y1288826I2002J-2D01*
G01Y1288825D01*
G37*
G36*
G01X397925Y1328028D02*
X410475D01*
G02X410617Y1327969I0J-200D01*
G01X411341Y1327245D01*
G02X411400Y1327103I-141J-142D01*
G01Y1323193D01*
G02X411341Y1323051I-200J0D01*
G01X410521Y1322231D01*
G03X410462Y1322089I141J-142D01*
G01Y1319664D01*
G03X410521Y1319522I200J0D01*
G01X411341Y1318702D01*
G02X411400Y1318560I-141J-142D01*
G01Y1317476D01*
X411379Y1317455D01*
Y1316880D01*
G03X411438Y1316738I200J0D01*
G01X411978Y1316198D01*
G02X412037Y1316056I-141J-142D01*
G01Y1313877D01*
G02X411978Y1313735I-200J0D01*
G01X411952Y1313709D01*
G02X411810Y1313650I-142J141D01*
G01X409627D01*
X409601Y1313657D01*
G03X409211Y1313708I-388J-1450D01*
G01X407803D01*
G02X407662Y1313767I1J200D01*
G01X407139Y1314290D01*
G02X407080Y1314432I141J142D01*
G01Y1315850D01*
G03X407021Y1315992I-200J0D01*
G01X404671Y1318342D01*
G03X404529Y1318401I-142J-141D01*
G01X397084D01*
G02X396942Y1318460I0J200D01*
G01X396566Y1318836D01*
G02X396507Y1318978I141J142D01*
G01Y1326610D01*
G02X396566Y1326752I200J0D01*
G01X397783Y1327969D01*
G02X397925Y1328028I142J-141D01*
G37*
G36*
G01X398774Y1557177D02*
X417177D01*
G02X417319Y1557118I0J-200D01*
G01X419901Y1554536D01*
Y1548398D01*
X420732Y1547567D01*
Y1546402D01*
G02X420624Y1546225I-200J0D01*
G03Y1543025I831J-1600D01*
G02X420732Y1542848I-92J-177D01*
G01Y1532979D01*
G02X420673Y1532837I-200J0D01*
G01X418092Y1530256D01*
G02X417950Y1530197I-142J141D01*
G01X396872D01*
G02X396730Y1530256I0J200D01*
G01X393341Y1533645D01*
G02X393282Y1533787I141J142D01*
G01Y1539542D01*
G02X393308Y1539641I200J0D01*
G03Y1541417I-1568J888D01*
G02X393282Y1541516I174J99D01*
G01Y1544642D01*
G02X393308Y1544741I200J0D01*
G03Y1546517I-1568J888D01*
G02X393282Y1546616I174J99D01*
G01Y1549742D01*
G02X393308Y1549841I200J0D01*
G03X393542Y1550729I-1568J888D01*
G03X393318Y1551599I-1802J0D01*
G01X393285Y1551658D01*
X393304Y1551790D01*
X398632Y1557118D01*
G02X398774Y1557177I142J-141D01*
G37*
G36*
G01X430437Y350936D02*
X433409D01*
X435383D01*
X436295Y350024D01*
Y348050D01*
X436998Y347347D01*
Y342986D01*
Y331003D01*
X436019Y330024D01*
X420269D01*
X419616Y330677D01*
Y348088D01*
X420357Y348829D01*
X425992D01*
X427001Y347820D01*
X429433D01*
X430117Y348504D01*
Y350616D01*
X430437Y350936D01*
G37*
G36*
G01X470004Y540990D02*
X411356D01*
X410638Y540272D01*
X410324Y539958D01*
Y527565D01*
X411927Y525962D01*
X470376D01*
X470804Y526390D01*
Y540390D01*
X470204Y540990D01*
X470004D01*
G37*
G36*
G01X470812Y557962D02*
Y545074D01*
Y542587D01*
X470237Y542012D01*
X432887D01*
X429782D01*
X411491D01*
X410413Y543090D01*
Y575323D01*
X411580Y576490D01*
X469904D01*
X470812Y575582D01*
Y573982D01*
Y563482D01*
Y559487D01*
Y557962D01*
G37*
G36*
G01X432831Y1287308D02*
X433016Y1287032D01*
G02X433035Y1286846I-166J-111D01*
G01Y1286845D01*
G03X432922Y1286274I1389J-572D01*
G03X435926I1502J0D01*
G03X435813Y1286844I-1502J-2D01*
G01Y1286846D01*
G02X435832Y1287032I185J75D01*
G01X436017Y1287308D01*
G02X436183Y1287397I166J-111D01*
G01X436511D01*
X436569Y1287378D01*
X436595Y1287360D01*
G03X437912Y1286936I1318J1838D01*
G01X440906D01*
G03X442151Y1287310I-1J2262D01*
G02X442261Y1287343I110J-167D01*
G01X443787D01*
G03X443929Y1287402I0J200D01*
G01X444081Y1287554D01*
G02X444223Y1287613I142J-141D01*
G01X463341D01*
G02X463483Y1287554I0J-200D01*
G01X463634Y1287403D01*
G03X463916I141J142D01*
G01X464662Y1288149D01*
G02X464804Y1288208I142J-141D01*
G01X520112D01*
G02X520254Y1288149I0J-200D01*
G01X522567Y1285836D01*
G03X522709Y1285777I142J141D01*
G01X529836D01*
G02X529978Y1285718I0J-200D01*
G01X530832Y1284864D01*
G02X530891Y1284722I-141J-142D01*
G01Y1282241D01*
G02X530832Y1282099I-200J0D01*
G01X530788Y1282055D01*
G02X530646Y1281996I-142J141D01*
G01X507854D01*
G02X507712Y1282055I0J200D01*
G01X507398Y1282369D01*
G03X507256Y1282428I-142J-141D01*
G01X493163D01*
G03X493021Y1282369I0J-200D01*
G01X491397Y1280745D01*
G02X491255Y1280686I-142J141D01*
G01X463211D01*
X463138Y1280656D01*
X463127Y1280645D01*
X425965D01*
G02X425823Y1280704I0J200D01*
G01X424375Y1282152D01*
G02X424316Y1282294I141J142D01*
G01Y1285046D01*
G02X424375Y1285188I200J0D01*
G01X425391Y1286204D01*
G02X425533Y1286263I142J-141D01*
G01X430661D01*
G03X430803Y1286322I0J200D01*
G01X431816Y1287335D01*
G02X431841Y1287356I141J-142D01*
G03X431845Y1287359I-1355J1811D01*
G02X431962Y1287397I117J-162D01*
G01X432665D01*
G02X432831Y1287308I0J-200D01*
G37*
G36*
G01X419727Y1324108D02*
Y1320178D01*
X420476Y1319429D01*
X423271D01*
X423717Y1319875D01*
X425478D01*
X425539Y1319814D01*
X425965D01*
X426410Y1320259D01*
Y1323541D01*
X427666Y1324797D01*
Y1326892D01*
Y1327147D01*
X429874Y1329355D01*
Y1333971D01*
X429449Y1334396D01*
X421994D01*
X421023Y1333425D01*
Y1325404D01*
X419727Y1324108D01*
G37*
G36*
G01X416647Y1380504D02*
X421365D01*
X421990Y1381129D01*
X429323D01*
X430630Y1379822D01*
Y1375616D01*
X432165Y1374081D01*
X435747D01*
X436372Y1373456D01*
Y1361234D01*
Y1356630D01*
X435320Y1355578D01*
X425941D01*
X425145Y1356374D01*
Y1361177D01*
X428243Y1364275D01*
Y1366605D01*
X430574Y1368936D01*
Y1371863D01*
X424576Y1377861D01*
X422502D01*
X420939Y1379424D01*
X416590D01*
X416419Y1379595D01*
Y1380276D01*
X416647Y1380504D01*
G37*
G36*
G01X430942Y1405532D02*
Y1392982D01*
G02X430883Y1392840I-200J0D01*
G01X430159Y1392116D01*
G02X430017Y1392057I-142J141D01*
G01X426107D01*
G02X425965Y1392116I0J200D01*
G01X425145Y1392936D01*
G03X425003Y1392995I-142J-141D01*
G01X422578D01*
G03X422436Y1392936I0J-200D01*
G01X421616Y1392116D01*
G02X421474Y1392057I-142J141D01*
G01X420390D01*
X420369Y1392078D01*
X419794D01*
G03X419652Y1392019I0J-200D01*
G01X419112Y1391479D01*
G02X418970Y1391420I-142J141D01*
G01X416791D01*
G02X416649Y1391479I0J200D01*
G01X416623Y1391505D01*
G02X416564Y1391647I141J142D01*
G01Y1393830D01*
X416571Y1393856D01*
G03X416622Y1394246I-1450J388D01*
G01Y1395654D01*
G02X416681Y1395795I200J-1D01*
G01X417204Y1396318D01*
G02X417346Y1396377I142J-141D01*
G01X418764D01*
G03X418906Y1396436I0J200D01*
G01X421256Y1398786D01*
G03X421315Y1398928I-141J142D01*
G01Y1406373D01*
G02X421374Y1406515I200J0D01*
G01X421750Y1406891D01*
G02X421892Y1406950I142J-141D01*
G01X429524D01*
G02X429666Y1406891I0J-200D01*
G01X430883Y1405674D01*
G02X430942Y1405532I-141J-142D01*
G37*
G36*
G01X420683Y1419000D02*
X424717D01*
G02X424859Y1418941I0J-200D01*
G01X427341Y1416459D01*
G02X427400Y1416317I-141J-142D01*
G01Y1410083D01*
G02X427341Y1409941I-200J0D01*
G01X427059Y1409659D01*
G02X426917Y1409600I-142J141D01*
G01X421983D01*
G02X421841Y1409659I0J200D01*
G01X420759Y1410741D01*
G02X420700Y1410883I141J142D01*
G01Y1414117D01*
G03X420641Y1414259I-200J0D01*
G01X420314Y1414586D01*
X420299Y1414628D01*
G03X420127Y1414997I-2096J-752D01*
G02X420100Y1415098I173J100D01*
G01Y1418417D01*
G02X420159Y1418559I200J0D01*
G01X420541Y1418941D01*
G02X420683Y1419000I142J-141D01*
G37*
G36*
G01X424764Y1564676D02*
X436724D01*
X437533Y1563867D01*
Y1553877D01*
X436548Y1552892D01*
X424905D01*
X423990Y1553807D01*
Y1563902D01*
X424764Y1564676D01*
G37*
G36*
G01X438657Y1037990D02*
X443744D01*
G02X443884Y1037933I0J-200D01*
G01X443885Y1037932D01*
X445870Y1035947D01*
G02X445872Y1035945I-140J-142D01*
G02X445929Y1035805I-143J-140D01*
G01Y1034162D01*
G02X445870Y1034020I-200J0D01*
G01X444587Y1032737D01*
X444559Y1032708D01*
X444485Y1032678D01*
X442509D01*
G03X442367Y1032619I0J-200D01*
G01X440909Y1031161D01*
G03X440850Y1031019I141J-142D01*
G01Y1009529D01*
G03X440909Y1009387I200J0D01*
G01X445694Y1004602D01*
G03X445836Y1004543I142J141D01*
G01X448756D01*
X448866Y1004455D01*
X448881Y1004386D01*
G03X452301I1710J380D01*
G01X452316Y1004455D01*
X452426Y1004543D01*
X453787D01*
G02X453927Y1004486I0J-200D01*
G01X453928Y1004485D01*
X453934Y1004479D01*
X454972Y1003442D01*
G03X455646Y1003022I1239J1238D01*
G03X456203Y1002928I566J1657D01*
G01X456228D01*
G03X456828Y1003041I-19J1752D01*
G01X456875Y1003058D01*
X456972Y1003047D01*
X457283Y1002831D01*
G02X457369Y1002667I-114J-164D01*
G01Y992777D01*
G03X457428Y992635I200J0D01*
G01X459237Y990826D01*
G03X459379Y990767I142J141D01*
G01X474961D01*
G03X475018Y990766I60J1801D01*
G03X475075Y990767I-3J1802D01*
G01X483660D01*
G03X483802Y990826I0J200D01*
G01X502081Y1009105D01*
G03X502140Y1009247I-141J142D01*
G01Y1028814D01*
G02X502340Y1029014I200J0D01*
G01X506566D01*
G03X508318Y1030766I0J1752D01*
G03X508086Y1031636I-1752J-1D01*
G01X508058Y1031685D01*
X508061Y1031795D01*
X508117Y1031884D01*
G02X508122Y1031891I165J-113D01*
G02X508285Y1031977I164J-114D01*
G01X513123D01*
X513124D01*
G02X513287Y1031891I-1J-200D01*
G02X513292Y1031884I-160J-120D01*
G01X513500Y1031554D01*
X513506Y1031453D01*
X513484Y1031406D01*
G03X513341Y1030761I1359J-640D01*
G01Y1030746D01*
G03X514843Y1029264I1502J20D01*
G03X516345Y1030740I0J1502D01*
G01Y1030763D01*
G03X516128Y1031545I-1502J4D01*
G01X516114Y1031567D01*
X516096Y1031628D01*
G02X516110Y1031775I192J56D01*
G01X516157Y1031868D01*
G02X516336Y1031977I178J-91D01*
G01X516358D01*
G02X516498Y1031920I0J-200D01*
G01X516499Y1031919D01*
X517199Y1031219D01*
G02X517201Y1031217I-140J-142D01*
G02X517258Y1031077I-143J-140D01*
G01Y980959D01*
G02X517199Y980817I-200J0D01*
G01X516030Y979648D01*
X516002Y979619D01*
X515928Y979589D01*
X508181D01*
G02X508007Y979690I0J200D01*
G03X505397I-1305J-742D01*
G01X505370Y979643D01*
X505277Y979589D01*
X505217D01*
G02X505031Y979717I0J200D01*
G01X504873Y980123D01*
X504901Y980242D01*
X504947Y980284D01*
G03X505435Y981392I-1014J1108D01*
G03X502431I-1502J0D01*
G03X502919Y980284I1502J0D01*
G01X502965Y980242D01*
X502993Y980123D01*
X502835Y979717D01*
G02X502649Y979589I-186J72D01*
G01X465307D01*
G02X465175Y979639I0J200D01*
G03X463917Y980114I-1257J-1426D01*
G01X449850D01*
G02X449709Y980173I1J200D01*
G01X435189Y994694D01*
G02X435130Y994835I141J142D01*
G01Y1034463D01*
G02X435187Y1034603I200J0D01*
G01X435188Y1034604D01*
X438515Y1037931D01*
G02X438517Y1037933I142J-140D01*
G02X438657Y1037990I140J-143D01*
G37*
G36*
G01X431334Y1333813D02*
X439187D01*
G02X439329Y1333754I0J-200D01*
G01X440631Y1332452D01*
G02X440690Y1332310I-141J-142D01*
G01Y1326058D01*
G02X440631Y1325916I-200J0D01*
G01X439472Y1324757D01*
G02X439330Y1324698I-142J141D01*
G01X431838D01*
G02X431696Y1324757I0J200D01*
G01X431560Y1324893D01*
X431530Y1324968D01*
X431531Y1325009D01*
G03X431532Y1325051I-2000J69D01*
G01Y1327276D01*
G03X430945Y1328691I-2002J-1D01*
G01X430938Y1328699D01*
G03X430881Y1329074I-1998J-112D01*
G01X430876Y1329098D01*
Y1333355D01*
G02X430934Y1333496I200J0D01*
G01X431192Y1333754D01*
G02X431334Y1333813I142J-141D01*
G37*
G36*
G01X438653Y1348187D02*
G03I-491J0D01*
G37*
G36*
G01Y1360099D02*
G03I-491J0D01*
G37*
G36*
G01Y1372385D02*
G03I-491J0D01*
G37*
G36*
G01Y1384297D02*
G03I-491J0D01*
G37*
G36*
G01X450893Y1348187D02*
G03I-491J0D01*
G37*
G36*
G01X446533D02*
G03I-491J0D01*
G37*
G36*
G01X450893Y1360099D02*
G03I-491J0D01*
G37*
G36*
G01X446533D02*
G03I-491J0D01*
G37*
G36*
G01X450893Y1372385D02*
G03I-491J0D01*
G37*
G36*
G01X446533D02*
G03I-491J0D01*
G37*
G36*
G01X450893Y1396583D02*
G03I-491J0D01*
G37*
G36*
G01Y1384297D02*
G03I-491J0D01*
G37*
G36*
G01X446533D02*
G03I-491J0D01*
G37*
G36*
G01X450893Y1408495D02*
G03I-491J0D01*
G37*
G36*
G01X454616Y1461182D02*
G03I-491J0D01*
G37*
G36*
G01Y1481267D02*
G03I-491J0D01*
G37*
G36*
G01Y1476536D02*
G03I-491J0D01*
G37*
G36*
G01Y1471805D02*
G03I-491J0D01*
G37*
G36*
G01Y1465913D02*
G03I-491J0D01*
G37*
G36*
G01Y1491891D02*
G03I-491J0D01*
G37*
G36*
G01Y1487160D02*
G03I-491J0D01*
G37*
G36*
G01Y1496622D02*
G03I-491J0D01*
G37*
G36*
G01Y1511976D02*
G03I-491J0D01*
G37*
G36*
G01Y1507245D02*
G03I-491J0D01*
G37*
G36*
G01Y1502514D02*
G03I-491J0D01*
G37*
G36*
G01Y1558813D02*
G03I-491J0D01*
G37*
G36*
G01Y1578898D02*
G03I-491J0D01*
G37*
G36*
G01Y1568275D02*
G03I-491J0D01*
G37*
G36*
G01Y1563544D02*
G03I-491J0D01*
G37*
G36*
G01Y1574167D02*
G03I-491J0D01*
G37*
G36*
G01Y1594253D02*
G03I-491J0D01*
G37*
G36*
G01Y1583629D02*
G03I-491J0D01*
G37*
G36*
G01Y1589522D02*
G03I-491J0D01*
G37*
G36*
G01Y1609607D02*
G03I-491J0D01*
G37*
G36*
G01Y1598984D02*
G03I-491J0D01*
G37*
G36*
G01Y1604876D02*
G03I-491J0D01*
G37*
G36*
G01Y1614338D02*
G03I-491J0D01*
G37*
G36*
G01X484785Y1005966D02*
X484499Y1005680D01*
X480462D01*
X479695Y1006447D01*
X476492D01*
X475725Y1005680D01*
X461791D01*
X461545Y1005926D01*
Y1011840D01*
X462149Y1012444D01*
X465853D01*
X466385Y1012976D01*
X466729Y1013320D01*
Y1022024D01*
X469885Y1025180D01*
X476885D01*
X482694D01*
X484818D01*
X485199Y1024799D01*
Y1006380D01*
X484785Y1005966D01*
G37*
G36*
G01X499858Y1120863D02*
X513097D01*
G02X513239Y1120804I0J-200D01*
G01X513566Y1120477D01*
G02X513625Y1120335I-141J-142D01*
G01Y1107335D01*
G02X513566Y1107193I-200J0D01*
G01X512440Y1106067D01*
G02X512298Y1106008I-142J141D01*
G01X512132D01*
X512113Y1106028D01*
X506061D01*
G03X505920Y1105969I1J-200D01*
G01X505290Y1105339D01*
G03X505232Y1105198I142J-141D01*
G01Y1100025D01*
G03X505290Y1099884I200J0D01*
G01X507893Y1097281D01*
G02X507952Y1097139I-141J-142D01*
G01Y1092438D01*
X507978Y1092412D01*
Y1088598D01*
G02X507962Y1088522I-200J2D01*
G01X507946Y1088483D01*
Y1072886D01*
G02X507888Y1072745I-200J0D01*
G01X507839Y1072696D01*
G02X507697Y1072637I-142J141D01*
G01X468197D01*
G02X468055Y1072696I0J200D01*
G01X467341Y1073410D01*
G02X467282Y1073552I141J142D01*
G01Y1104857D01*
G03X467284Y1104889I-1497J110D01*
G03Y1104903I-200J7D01*
G03X467282Y1104935I-1499J-78D01*
G01Y1120414D01*
G02X467341Y1120556I200J0D01*
G01X467589Y1120804D01*
G02X467731Y1120863I142J-141D01*
G01X481192D01*
G02X481334Y1120804I0J-200D01*
G01X481438Y1120700D01*
G02X481497Y1120558I-141J-142D01*
G01Y1107335D01*
G02X481438Y1107193I-200J0D01*
G01X480312Y1106067D01*
G02X480170Y1106008I-142J141D01*
G01X480004D01*
X479985Y1106028D01*
X473933D01*
G03X473792Y1105969I1J-200D01*
G01X473162Y1105339D01*
G03X473104Y1105198I142J-141D01*
G01Y1100025D01*
G03X473162Y1099884I200J0D01*
G01X476615Y1096431D01*
G03X476756Y1096372I142J141D01*
G01X492024D01*
G03X492165Y1096431I-1J200D01*
G01X492189Y1096455D01*
X492262Y1096485D01*
X494894D01*
G03X495036Y1096544I0J200D01*
G01X499351Y1100859D01*
G03X499410Y1101001I-141J142D01*
G01Y1120415D01*
G02X499469Y1120557I200J0D01*
G01X499716Y1120804D01*
G02X499858Y1120863I142J-141D01*
G37*
G36*
G01X486905Y1254968D02*
X538283D01*
G02X538425Y1254909I0J-200D01*
G01X539022Y1254312D01*
X539046Y1254271D01*
X539054Y1254247D01*
G03X550388Y1238120I30144J9139D01*
G01X550407Y1238106D01*
X550436Y1238072D01*
X550485Y1237975D01*
G02X550507Y1237884I-178J-91D01*
G01Y1159070D01*
X550477Y1158996D01*
X550448Y1158968D01*
X548795Y1157315D01*
G02X548653Y1157256I-142J141D01*
G01X467654D01*
G02X467512Y1157315I0J200D01*
G01X467318Y1157509D01*
X467289Y1157537D01*
X467259Y1157611D01*
Y1190766D01*
G02X467318Y1190908I200J0D01*
G01X468321Y1191911D01*
G02X468462Y1191970I142J-141D01*
G01X469197D01*
G03X469585Y1192153I1J501D01*
G02X469711Y1192224I154J-127D01*
G03X469882Y1192422I-29J198D01*
G01Y1193389D01*
G02X469941Y1193531I200J0D01*
G01X470338Y1193928D01*
G02X470480Y1193987I142J-141D01*
G01X530152D01*
X533442D01*
X534213Y1194758D01*
Y1215122D01*
X533619Y1215716D01*
X526463D01*
X525921Y1215174D01*
X521978D01*
X521462Y1215690D01*
X521456D01*
X521357Y1215789D01*
X518542D01*
X518443Y1215690D01*
X517927Y1215174D01*
X508691D01*
X508148Y1215717D01*
X504480D01*
X503937Y1215174D01*
X487155D01*
G02X487013Y1215233I0J200D01*
G01X486143Y1216103D01*
X486114Y1216131D01*
X486084Y1216205D01*
Y1254147D01*
G02X486143Y1254289I200J0D01*
G01X486763Y1254909D01*
G02X486905Y1254968I142J-141D01*
G37*
G36*
G01X530406Y1256342D02*
X485751D01*
X484953Y1255544D01*
Y1215751D01*
X484531Y1215329D01*
X480733D01*
X468004D01*
X465320D01*
X464803Y1215846D01*
Y1239781D01*
X466801Y1241779D01*
X466963Y1241941D01*
Y1256095D01*
X466801Y1256257D01*
X464803Y1258255D01*
Y1264602D01*
X465181Y1264980D01*
X491729D01*
X493350Y1266601D01*
X533592D01*
X534784Y1265409D01*
Y1256968D01*
X534158Y1256342D01*
X530406D01*
G37*
G36*
G01X471013Y1348187D02*
G03I-491J0D01*
G37*
G36*
G01X463133D02*
G03I-491J0D01*
G37*
G36*
G01X458773D02*
G03I-491J0D01*
G37*
G36*
G01X471013Y1360099D02*
G03I-491J0D01*
G37*
G36*
G01X463133D02*
G03I-491J0D01*
G37*
G36*
G01X458773D02*
G03I-491J0D01*
G37*
G36*
G01X471013Y1372385D02*
G03I-491J0D01*
G37*
G36*
G01X463133D02*
G03I-491J0D01*
G37*
G36*
G01X458773D02*
G03I-491J0D01*
G37*
G36*
G01X471013Y1396583D02*
G03I-491J0D01*
G37*
G36*
G01X463133D02*
G03I-491J0D01*
G37*
G36*
G01X458773D02*
G03I-491J0D01*
G37*
G36*
G01X471013Y1384297D02*
G03I-491J0D01*
G37*
G36*
G01X463133D02*
G03I-491J0D01*
G37*
G36*
G01X458773D02*
G03I-491J0D01*
G37*
G36*
G01X471013Y1408495D02*
G03I-491J0D01*
G37*
G36*
G01X463133D02*
G03I-491J0D01*
G37*
G36*
G01X458773D02*
G03I-491J0D01*
G37*
G36*
G01X471939Y1461182D02*
G03I-491J0D01*
G37*
G36*
G01X463277Y1460782D02*
G03I-491J0D01*
G37*
G36*
G01X471939Y1465913D02*
G03I-491J0D01*
G37*
G36*
G01X463277Y1465513D02*
G03I-491J0D01*
G37*
G36*
G01X471939Y1481267D02*
G03I-491J0D01*
G37*
G36*
G01X463277Y1480867D02*
G03I-491J0D01*
G37*
G36*
G01X471939Y1471805D02*
G03I-491J0D01*
G37*
G36*
G01Y1476536D02*
G03I-491J0D01*
G37*
G36*
G01X463277Y1476136D02*
G03I-491J0D01*
G37*
G36*
G01Y1470244D02*
G03I-491J0D01*
G37*
G36*
G01X471939Y1491891D02*
G03I-491J0D01*
G37*
G36*
G01X463277Y1491491D02*
G03I-491J0D01*
G37*
G36*
G01Y1485598D02*
G03I-491J0D01*
G37*
G36*
G01X471939Y1487160D02*
G03I-491J0D01*
G37*
G36*
G01Y1496622D02*
G03I-491J0D01*
G37*
G36*
G01X463277Y1496222D02*
G03I-491J0D01*
G37*
G36*
G01X471939Y1511976D02*
G03I-491J0D01*
G37*
G36*
G01Y1502514D02*
G03I-491J0D01*
G37*
G36*
G01Y1507245D02*
G03I-491J0D01*
G37*
G36*
G01X463277Y1511576D02*
G03I-491J0D01*
G37*
G36*
G01Y1506845D02*
G03I-491J0D01*
G37*
G36*
G01Y1500953D02*
G03I-491J0D01*
G37*
G36*
G01Y1516307D02*
G03I-491J0D01*
G37*
G36*
G01X471939Y1558813D02*
G03I-491J0D01*
G37*
G36*
G01Y1578898D02*
G03I-491J0D01*
G37*
G36*
G01X463277Y1563144D02*
G03I-491J0D01*
G37*
G36*
G01Y1578498D02*
G03I-491J0D01*
G37*
G36*
G01X471939Y1574167D02*
G03I-491J0D01*
G37*
G36*
G01Y1568275D02*
G03I-491J0D01*
G37*
G36*
G01Y1563544D02*
G03I-491J0D01*
G37*
G36*
G01X463277Y1567875D02*
G03I-491J0D01*
G37*
G36*
G01Y1572606D02*
G03I-491J0D01*
G37*
G36*
G01X471939Y1594253D02*
G03I-491J0D01*
G37*
G36*
G01X463277Y1593853D02*
G03I-491J0D01*
G37*
G36*
G01X471939Y1589522D02*
G03I-491J0D01*
G37*
G36*
G01Y1583629D02*
G03I-491J0D01*
G37*
G36*
G01X463277Y1583229D02*
G03I-491J0D01*
G37*
G36*
G01Y1587960D02*
G03I-491J0D01*
G37*
G36*
G01X471939Y1609607D02*
G03I-491J0D01*
G37*
G36*
G01Y1604876D02*
G03I-491J0D01*
G37*
G36*
G01Y1598984D02*
G03I-491J0D01*
G37*
G36*
G01X463277Y1609207D02*
G03I-491J0D01*
G37*
G36*
G01Y1598584D02*
G03I-491J0D01*
G37*
G36*
G01Y1603315D02*
G03I-491J0D01*
G37*
G36*
G01X471939Y1614338D02*
G03I-491J0D01*
G37*
G36*
G01X463277Y1613938D02*
G03I-491J0D01*
G37*
G36*
G01Y1618669D02*
G03I-491J0D01*
G37*
G36*
G01X482533Y924633D02*
G03I-590J0D01*
G37*
G36*
G01X488978Y938903D02*
G03I-590J0D01*
G37*
G36*
G01X490467Y1058603D02*
X489834Y1059236D01*
Y1069654D01*
X490897Y1070717D01*
X506812D01*
X507781Y1069748D01*
Y1059792D01*
Y1059085D01*
X507779Y1059083D01*
Y1057988D01*
X506819Y1057028D01*
X492042D01*
X491293Y1057777D01*
X490467Y1058603D01*
G37*
G36*
G01X483406Y1097374D02*
X477088D01*
X474105Y1100357D01*
Y1104866D01*
X474265Y1105026D01*
X479653D01*
X481423Y1103256D01*
G03X481565Y1103197I142J141D01*
G01X483706D01*
X485475D01*
X486652Y1102020D01*
X488863Y1099809D01*
X490771D01*
X491311D01*
X491849Y1099271D01*
Y1097531D01*
X491692Y1097374D01*
X486227D01*
X483406D01*
G37*
G36*
G01X487613Y1348187D02*
G03I-491J0D01*
G37*
G36*
G01X483253D02*
G03I-491J0D01*
G37*
G36*
G01X475373D02*
G03I-491J0D01*
G37*
G36*
G01X487613Y1360099D02*
G03I-491J0D01*
G37*
G36*
G01X483253D02*
G03I-491J0D01*
G37*
G36*
G01X475373D02*
G03I-491J0D01*
G37*
G36*
G01X487613Y1372385D02*
G03I-491J0D01*
G37*
G36*
G01X483253D02*
G03I-491J0D01*
G37*
G36*
G01X475373D02*
G03I-491J0D01*
G37*
G36*
G01X487613Y1384297D02*
G03I-491J0D01*
G37*
G36*
G01Y1396583D02*
G03I-491J0D01*
G37*
G36*
G01X483253D02*
G03I-491J0D01*
G37*
G36*
G01X475373D02*
G03I-491J0D01*
G37*
G36*
G01X483253Y1384297D02*
G03I-491J0D01*
G37*
G36*
G01X475373D02*
G03I-491J0D01*
G37*
G36*
G01X487613Y1408495D02*
G03I-491J0D01*
G37*
G36*
G01X483253D02*
G03I-491J0D01*
G37*
G36*
G01X475373D02*
G03I-491J0D01*
G37*
G36*
G01X489262Y1461182D02*
G03I-491J0D01*
G37*
G36*
G01X480600Y1460782D02*
G03I-491J0D01*
G37*
G36*
G01Y1465513D02*
G03I-491J0D01*
G37*
G36*
G01X489262Y1465913D02*
G03I-491J0D01*
G37*
G36*
G01X480600Y1470244D02*
G03I-491J0D01*
G37*
G36*
G01X489262Y1471805D02*
G03I-491J0D01*
G37*
G36*
G01Y1476536D02*
G03I-491J0D01*
G37*
G36*
G01Y1481267D02*
G03I-491J0D01*
G37*
G36*
G01X480600Y1480867D02*
G03I-491J0D01*
G37*
G36*
G01Y1476136D02*
G03I-491J0D01*
G37*
G36*
G01X489262Y1496622D02*
G03I-491J0D01*
G37*
G36*
G01X480600Y1496222D02*
G03I-491J0D01*
G37*
G36*
G01X489262Y1487160D02*
G03I-491J0D01*
G37*
G36*
G01Y1491891D02*
G03I-491J0D01*
G37*
G36*
G01X480600Y1491491D02*
G03I-491J0D01*
G37*
G36*
G01Y1485598D02*
G03I-491J0D01*
G37*
G36*
G01X489262Y1511976D02*
G03I-491J0D01*
G37*
G36*
G01X480600Y1511576D02*
G03I-491J0D01*
G37*
G36*
G01Y1506845D02*
G03I-491J0D01*
G37*
G36*
G01Y1500953D02*
G03I-491J0D01*
G37*
G36*
G01X489262Y1502514D02*
G03I-491J0D01*
G37*
G36*
G01Y1507245D02*
G03I-491J0D01*
G37*
G36*
G01X480600Y1516307D02*
G03I-491J0D01*
G37*
G36*
G01X489262Y1558813D02*
G03I-491J0D01*
G37*
G36*
G01Y1578898D02*
G03I-491J0D01*
G37*
G36*
G01X480600Y1563144D02*
G03I-491J0D01*
G37*
G36*
G01Y1578498D02*
G03I-491J0D01*
G37*
G36*
G01X489262Y1574167D02*
G03I-491J0D01*
G37*
G36*
G01Y1568275D02*
G03I-491J0D01*
G37*
G36*
G01Y1563544D02*
G03I-491J0D01*
G37*
G36*
G01X480600Y1567875D02*
G03I-491J0D01*
G37*
G36*
G01Y1572606D02*
G03I-491J0D01*
G37*
G36*
G01X489262Y1594253D02*
G03I-491J0D01*
G37*
G36*
G01X480600Y1593853D02*
G03I-491J0D01*
G37*
G36*
G01X489262Y1589522D02*
G03I-491J0D01*
G37*
G36*
G01Y1583629D02*
G03I-491J0D01*
G37*
G36*
G01X480600Y1583229D02*
G03I-491J0D01*
G37*
G36*
G01Y1587960D02*
G03I-491J0D01*
G37*
G36*
G01X489262Y1609607D02*
G03I-491J0D01*
G37*
G36*
G01Y1604876D02*
G03I-491J0D01*
G37*
G36*
G01Y1598984D02*
G03I-491J0D01*
G37*
G36*
G01X480600Y1609207D02*
G03I-491J0D01*
G37*
G36*
G01Y1598584D02*
G03I-491J0D01*
G37*
G36*
G01Y1603315D02*
G03I-491J0D01*
G37*
G36*
G01X489262Y1614338D02*
G03I-491J0D01*
G37*
G36*
G01X480600Y1613938D02*
G03I-491J0D01*
G37*
G36*
G01Y1618669D02*
G03I-491J0D01*
G37*
G36*
G01X499104Y174710D02*
X545579D01*
G02X545719Y174653I0J-200D01*
G01X545720Y174652D01*
X547922Y172450D01*
G02X547924Y172448I-140J-142D01*
G02X547981Y172308I-143J-140D01*
G01Y143109D01*
X547900Y143003D01*
X547834Y142985D01*
G03Y139509I477J-1738D01*
G01X547900Y139491D01*
X547981Y139385D01*
Y104934D01*
G02X547963Y104852I-200J1D01*
G01X547915Y104743D01*
X547885Y104716D01*
G03X547412Y103621I1031J-1095D01*
G03X547572Y102946I1502J0D01*
G01X547593Y102904D01*
X547595Y102814D01*
X547444Y102487D01*
G02X547310Y102377I-182J85D01*
G01X547309D01*
G03X545930Y100625I423J-1752D01*
G03X547609Y98827I1802J0D01*
G01X547647Y98824D01*
X547715Y98792D01*
X547927Y98565D01*
G02X547937Y98553I-148J-134D01*
G02X547981Y98428I-156J-125D01*
G01Y77986D01*
G02X547861Y77803I-200J0D01*
G01X547471Y77632D01*
X547354Y77652D01*
X547310Y77692D01*
G03X546293Y78089I-1017J-1104D01*
G03X545044Y77421I0J-1502D01*
G01X545020Y77386D01*
X544951Y77341D01*
X544620Y77288D01*
G02X544466Y77327I-32J197D01*
G03X543545Y77642I-920J-1187D01*
G01X543515D01*
G03X542043Y76140I30J-1502D01*
G03X543545Y74638I1502J0D01*
G03X544794Y75306I0J1502D01*
G01X544818Y75341D01*
X544887Y75386D01*
X545259Y75446D01*
X545339Y75426D01*
X545372Y75400D01*
G03X545988Y75116I921J1187D01*
G01X546042Y75105D01*
X546123Y75031D01*
X546240Y74640D01*
G02X546190Y74442I-192J-57D01*
G01X545773Y74025D01*
X545734Y74009D01*
G03X544899Y73174I559J-1394D01*
G01X544883Y73135D01*
X544754Y73006D01*
X544726Y72977D01*
X544652Y72947D01*
X498539D01*
G02X498397Y73006I0J200D01*
G01X497081Y74322D01*
X497052Y74350D01*
X497022Y74424D01*
Y172628D01*
G02X497079Y172768I200J0D01*
G01X497080Y172769D01*
X498962Y174651D01*
G02X498964Y174653I142J-140D01*
G02X499104Y174710I140J-143D01*
G37*
G36*
G01X626149Y559473D02*
X637672D01*
G02X637813Y559415I0J-200D01*
G01X637969Y559260D01*
X638054Y559175D01*
G02X638106Y559054I-148J-135D01*
G01Y549445D01*
G02X638047Y549304I-200J1D01*
G01X637893Y549150D01*
X637865Y549121D01*
X637791Y549091D01*
X631995D01*
G03X631853Y549032I0J-200D01*
G01X623908Y541087D01*
X623880Y541058D01*
X623806Y541028D01*
X593940D01*
G03X593798Y540969I0J-200D01*
G01X580234Y527405D01*
G03X580175Y527263I141J-142D01*
G01Y474821D01*
G02X580116Y474679I-200J0D01*
G01X559467Y454030D01*
X559439Y454001D01*
X559365Y453971D01*
X513655D01*
G02X513514Y454028I-1J200D01*
G01X513286Y454253D01*
X513255Y454324D01*
Y454364D01*
G03X512885Y455326I-1502J-25D01*
G01X512861Y455354D01*
X512836Y455421D01*
Y455757D01*
X512861Y455824D01*
X512885Y455852D01*
G03Y457826I-1131J987D01*
G01X512861Y457854D01*
X512836Y457921D01*
Y458257D01*
X512861Y458324D01*
X512885Y458352D01*
G03X513255Y459339I-1131J987D01*
G03X513206Y459719I-1502J-1D01*
G01X513195Y459761D01*
X513210Y459845D01*
X513426Y460166D01*
X513499Y460211D01*
X513542Y460217D01*
G03X515112Y462004I-232J1787D01*
G03X511508I-1802J0D01*
G03X511639Y461328I1802J-1D01*
G01X511656Y461288D01*
X511652Y461202D01*
X511479Y460857D01*
X511412Y460803D01*
X511371Y460791D01*
G03X510766Y460471I381J-1453D01*
G01X510738Y460447D01*
X510671Y460422D01*
X510335D01*
X510268Y460447D01*
X510240Y460471D01*
G03X509253Y460841I-987J-1131D01*
G03X507751Y459339I0J-1502D01*
G03X508121Y458352I1501J0D01*
G01X508145Y458324D01*
X508170Y458257D01*
Y457921D01*
X508145Y457854D01*
X508121Y457826D01*
G03Y455852I1131J-987D01*
G01X508145Y455824D01*
X508170Y455757D01*
Y455421D01*
X508145Y455354D01*
X508121Y455326D01*
G03X507751Y454364I1132J-987D01*
G01Y454324D01*
X507720Y454253D01*
X507492Y454028D01*
G02X507351Y453971I-140J143D01*
G01X505237D01*
G02X505060Y454079I1J200D01*
G01X504870Y454444D01*
X504878Y454555D01*
X504910Y454601D01*
G03X505184Y455466I-1228J865D01*
G03X502180I-1502J0D01*
G03X502454Y454601I1502J0D01*
G01X502486Y454555D01*
X502494Y454444D01*
X502304Y454079D01*
G02X502127Y453971I-178J92D01*
G01X495849D01*
G02X495707Y454030I0J200D01*
G01X491314Y458423D01*
X491285Y458451D01*
X491255Y458525D01*
Y477417D01*
G02X491362Y477594I200J0D01*
G01X491435Y477633D01*
X491553Y477621D01*
X491601Y477583D01*
G03X492736Y477180I1136J1399D01*
G03Y480784I0J1802D01*
G03X491601Y480381I1J-1802D01*
G01X491553Y480343D01*
X491435Y480331D01*
X491362Y480370D01*
G02X491255Y480547I93J177D01*
G01Y482417D01*
G02X491362Y482594I200J0D01*
G01X491675Y482759D01*
G02X491882Y482746I93J-177D01*
G01X491883D01*
G03X492736Y482480I853J1235D01*
G01X492764D01*
G03X494238Y483982I-28J1502D01*
G03X492736Y485484I-1502J0D01*
G01X492735D01*
G03X491883Y485218I1J-1502D01*
G01X491882D01*
G02X491675Y485205I-114J164D01*
G01X491362Y485370D01*
G02X491255Y485547I93J177D01*
G01Y486417D01*
G02X491362Y486594I200J0D01*
G01X491675Y486759D01*
G02X491882Y486746I93J-177D01*
G01X491883D01*
G03X492736Y486480I853J1235D01*
G01X492764D01*
G03X494238Y487982I-28J1502D01*
G03X492736Y489484I-1502J0D01*
G01X492735D01*
G03X491883Y489218I1J-1502D01*
G01X491882D01*
G02X491675Y489205I-114J164D01*
G01X491362Y489370D01*
G02X491255Y489547I93J177D01*
G01Y490063D01*
G02X491354Y490236I200J0D01*
G01X491698Y490438D01*
X491804Y490439D01*
X491851Y490412D01*
G03X492736Y490180I885J1570D01*
G01X492760D01*
G03X494538Y491982I-24J1802D01*
G03X492736Y493784I-1802J0D01*
G03X491851Y493552I0J-1802D01*
G01X491804Y493525D01*
X491698Y493526D01*
X491354Y493728D01*
G02X491255Y493901I101J173D01*
G01Y498417D01*
G02X491362Y498594I200J0D01*
G01X491675Y498759D01*
G02X491882Y498746I93J-177D01*
G01X491883D01*
G03X492736Y498480I853J1235D01*
G01X492764D01*
G03X494238Y499982I-28J1502D01*
G03X492736Y501484I-1502J0D01*
G01X492730D01*
G02X492546Y501607I1J200D01*
G01X492404Y501949D01*
G02X492447Y502167I185J77D01*
G01X492647Y502367D01*
G02X492789Y502426I142J-141D01*
G01X540106D01*
G03X540248Y502485I0J200D01*
G01X541433Y503670D01*
G03X541492Y503812I-141J142D01*
G01Y528321D01*
G02X541551Y528463I200J0D01*
G01X564196Y551108D01*
G02X564338Y551167I142J-141D01*
G01X598304D01*
G02X598399Y551143I0J-200D01*
G03X599821I711J1323D01*
G02X599916Y551167I95J-176D01*
G01X617677D01*
G03X617819Y551226I0J200D01*
G01X626007Y559414D01*
G02X626149Y559473I142J-141D01*
G37*
G36*
G01X499841Y537696D02*
Y554389D01*
X499823Y554407D01*
Y615308D01*
X499853Y615381D01*
X499878Y615406D01*
X514639D01*
G02X514781Y615347I0J-200D01*
G01X515192Y614936D01*
G02X515251Y614794I-141J-142D01*
G01Y573216D01*
G03X515310Y573074I200J0D01*
G01X518691Y569693D01*
G03X518833Y569634I142J141D01*
G01X524967D01*
G03X525109Y569693I0J200D01*
G01X525872Y570456D01*
X527822Y572407D01*
G03X527881Y572549I-141J142D01*
G01Y577148D01*
G02X527940Y577290I200J0D01*
G01X528259Y577609D01*
G02X528401Y577668I142J-141D01*
G01X532909D01*
G02X533051Y577609I0J-200D01*
G01X533669Y576991D01*
G02X533728Y576849I-141J-142D01*
G01Y570820D01*
G02X533669Y570678I-200J0D01*
G01X531587Y568596D01*
G03X531528Y568454I141J-142D01*
G01Y556856D01*
X531557Y556827D01*
Y551474D01*
G03X531616Y551332I200J0D01*
G01X533263Y549685D01*
G03X533405Y549626I142J141D01*
G01X536566D01*
G02X536708Y549567I0J-200D01*
G01X537593Y548682D01*
G02X537652Y548540I-141J-142D01*
G01Y536820D01*
G02X537593Y536678I-200J0D01*
G01X536963Y536048D01*
G02X536821Y535989I-142J141D01*
G01X501548D01*
G02X501406Y536048I0J200D01*
G01X499900Y537554D01*
G02X499841Y537696I141J142D01*
G37*
G36*
G01X506021Y684684D02*
X510333D01*
G02X510475Y684625I0J-200D01*
G01X511357Y683743D01*
G02X511416Y683601I-141J-142D01*
G01Y681950D01*
G02X511357Y681808I-200J0D01*
G01X511223Y681674D01*
G03X511164Y681532I141J-142D01*
G01Y677463D01*
G02X511105Y677321I-200J0D01*
G01X510368Y676584D01*
G02X510226Y676525I-142J141D01*
G01X505938D01*
X505929Y676535D01*
X503504D01*
G02X503362Y676594I0J200D01*
G01X503005Y676951D01*
G02X502946Y677093I141J142D01*
G01Y678306D01*
G02X503005Y678448I200J0D01*
G01X505102Y680545D01*
G03X505161Y680687I-141J142D01*
G01Y683824D01*
G02X505220Y683966I200J0D01*
G01X505879Y684625D01*
G02X506021Y684684I142J-141D01*
G37*
G36*
G01X495074Y690367D02*
X503161D01*
G02X503303Y690308I0J-200D01*
G01X503807Y689804D01*
G02X503866Y689662I-141J-142D01*
G01Y680808D01*
G02X503807Y680667I-200J1D01*
G01X502003Y678862D01*
G03X501944Y678721I141J-142D01*
G01Y678702D01*
X500468Y677225D01*
G02X500326Y677166I-142J141D01*
G01X496661D01*
G02X496519Y677225I0J200D01*
G01X494582Y679162D01*
G02X494523Y679304I141J142D01*
G01Y689816D01*
G02X494582Y689958I200J0D01*
G01X494932Y690308D01*
G02X495074Y690367I142J-141D01*
G37*
G36*
G01X505163Y700248D02*
Y696168D01*
X504318Y695323D01*
Y691768D01*
X503994Y691444D01*
X501198D01*
X499077D01*
X497700Y692821D01*
Y705712D01*
X498253Y706265D01*
X499935D01*
X504254D01*
X504537Y705982D01*
Y703582D01*
X505163Y702956D01*
Y700248D01*
G37*
G36*
G01X506812Y699234D02*
X510249D01*
X510520Y699505D01*
X515664D01*
X516179Y698990D01*
Y698749D01*
X516316Y698612D01*
Y698133D01*
Y695062D01*
X515767Y694514D01*
X515404D01*
X515074D01*
X513447Y692887D01*
X512959D01*
X511795Y691723D01*
Y691109D01*
X508938Y688252D01*
Y686641D01*
X508593Y686296D01*
X505588D01*
Y692414D01*
X506016Y692842D01*
Y692870D01*
X506247Y693101D01*
Y698669D01*
X506812Y699234D01*
G37*
G36*
G01X493628Y976078D02*
G03I-577J0D01*
G37*
G36*
G01X499853Y1348187D02*
G03I-491J0D01*
G37*
G36*
G01X495493D02*
G03I-491J0D01*
G37*
G36*
G01X499853Y1360099D02*
G03I-491J0D01*
G37*
G36*
G01X495493D02*
G03I-491J0D01*
G37*
G36*
G01X499853Y1372385D02*
G03I-491J0D01*
G37*
G36*
G01X495493D02*
G03I-491J0D01*
G37*
G36*
G01X499853Y1396583D02*
G03I-491J0D01*
G37*
G36*
G01Y1384297D02*
G03I-491J0D01*
G37*
G36*
G01X495493D02*
G03I-491J0D01*
G37*
G36*
G01Y1396583D02*
G03I-491J0D01*
G37*
G36*
G01X499853Y1408495D02*
G03I-491J0D01*
G37*
G36*
G01X495493D02*
G03I-491J0D01*
G37*
G36*
G01X506584Y1461182D02*
G03I-491J0D01*
G37*
G36*
G01X497923Y1460782D02*
G03I-491J0D01*
G37*
G36*
G01Y1465513D02*
G03I-491J0D01*
G37*
G36*
G01X506584Y1465913D02*
G03I-491J0D01*
G37*
G36*
G01X497923Y1480867D02*
G03I-491J0D01*
G37*
G36*
G01X506584Y1481267D02*
G03I-491J0D01*
G37*
G36*
G01X497923Y1476136D02*
G03I-491J0D01*
G37*
G36*
G01Y1470244D02*
G03I-491J0D01*
G37*
G36*
G01X506584Y1471805D02*
G03I-491J0D01*
G37*
G36*
G01Y1476536D02*
G03I-491J0D01*
G37*
G36*
G01X497923Y1496222D02*
G03I-491J0D01*
G37*
G36*
G01Y1491491D02*
G03I-491J0D01*
G37*
G36*
G01Y1485598D02*
G03I-491J0D01*
G37*
G36*
G01X506584Y1487160D02*
G03I-491J0D01*
G37*
G36*
G01Y1491891D02*
G03I-491J0D01*
G37*
G36*
G01Y1496622D02*
G03I-491J0D01*
G37*
G36*
G01Y1502514D02*
G03I-491J0D01*
G37*
G36*
G01Y1507245D02*
G03I-491J0D01*
G37*
G36*
G01X497923Y1511576D02*
G03I-491J0D01*
G37*
G36*
G01X506584Y1511976D02*
G03I-491J0D01*
G37*
G36*
G01X497923Y1506845D02*
G03I-491J0D01*
G37*
G36*
G01Y1500953D02*
G03I-491J0D01*
G37*
G36*
G01Y1516307D02*
G03I-491J0D01*
G37*
G36*
G01X506584Y1558813D02*
G03I-491J0D01*
G37*
G36*
G01Y1578898D02*
G03I-491J0D01*
G37*
G36*
G01X497923Y1563144D02*
G03I-491J0D01*
G37*
G36*
G01Y1578498D02*
G03I-491J0D01*
G37*
G36*
G01Y1567875D02*
G03I-491J0D01*
G37*
G36*
G01Y1572606D02*
G03I-491J0D01*
G37*
G36*
G01X506584Y1574167D02*
G03I-491J0D01*
G37*
G36*
G01Y1568275D02*
G03I-491J0D01*
G37*
G36*
G01Y1563544D02*
G03I-491J0D01*
G37*
G36*
G01X497923Y1583229D02*
G03I-491J0D01*
G37*
G36*
G01Y1587960D02*
G03I-491J0D01*
G37*
G36*
G01X506584Y1589522D02*
G03I-491J0D01*
G37*
G36*
G01Y1583629D02*
G03I-491J0D01*
G37*
G36*
G01X497923Y1593853D02*
G03I-491J0D01*
G37*
G36*
G01X506584Y1594253D02*
G03I-491J0D01*
G37*
G36*
G01X497923Y1603315D02*
G03I-491J0D01*
G37*
G36*
G01X506584Y1604876D02*
G03I-491J0D01*
G37*
G36*
G01Y1598984D02*
G03I-491J0D01*
G37*
G36*
G01X497923Y1609207D02*
G03I-491J0D01*
G37*
G36*
G01X506584Y1609607D02*
G03I-491J0D01*
G37*
G36*
G01X497923Y1598584D02*
G03I-491J0D01*
G37*
G36*
G01Y1613938D02*
G03I-491J0D01*
G37*
G36*
G01Y1618669D02*
G03I-491J0D01*
G37*
G36*
G01X506584Y1614338D02*
G03I-491J0D01*
G37*
G36*
G01X522750Y704864D02*
X527509D01*
G02X527649Y704807I0J-200D01*
G01X527650Y704806D01*
X527942Y704514D01*
G02X527944Y704512I-140J-142D01*
G02X528001Y704372I-143J-140D01*
G01Y694482D01*
G02X527942Y694340I-200J0D01*
G01X527574Y693972D01*
X527546Y693943D01*
X527472Y693913D01*
X523953D01*
X523436Y694430D01*
X517798D01*
X517318Y694910D01*
Y698465D01*
Y698694D01*
Y699088D01*
X517312Y699094D01*
Y699431D01*
X517008Y699735D01*
Y700799D01*
X517019Y700831D01*
G03X517106Y701351I-1515J521D01*
G03X517019Y701871I-1602J-1D01*
G01X517008Y701903D01*
Y703474D01*
G02X517065Y703614I200J0D01*
G01X517066Y703615D01*
X518256Y704805D01*
G02X518258Y704807I142J-140D01*
G02X518398Y704864I140J-143D01*
G01X519701D01*
G02X519842Y704805I-1J-200D01*
G01X520133Y704515D01*
G03X520274Y704456I142J141D01*
G01X522177D01*
G03X522318Y704515I-1J200D01*
G01X522609Y704805D01*
G02X522750Y704864I142J-141D01*
G37*
G36*
G01X518415Y724586D02*
X523804D01*
X523827Y724562D01*
Y723863D01*
X523797Y723790D01*
X523780Y723773D01*
Y712205D01*
Y712161D01*
X524813Y711128D01*
Y709605D01*
X522391Y707183D01*
Y706087D01*
G02X522332Y705945I-200J0D01*
G01X521904Y705517D01*
G02X521762Y705458I-142J141D01*
G01X520689D01*
G02X520547Y705517I0J200D01*
G01X520119Y705945D01*
G02X520060Y706087I141J142D01*
G01Y707252D01*
G03X520001Y707394I-200J0D01*
G01X519228Y708167D01*
G03X519086Y708226I-142J-141D01*
G01X518512D01*
G02X518370Y708285I0J200D01*
G01X517395Y709260D01*
G02X517336Y709402I141J142D01*
G01X515645Y711093D01*
Y713720D01*
X518156Y716231D01*
Y716668D01*
Y724326D01*
G02X518215Y724468I200J0D01*
G01X518274Y724527D01*
G02X518415Y724586I142J-141D01*
G37*
G36*
G01X515151D02*
X516539D01*
G02X516680Y724527I-1J-200D01*
G01X516839Y724368D01*
G02X516898Y724226I-141J-142D01*
G01Y716807D01*
G02X516839Y716665I-200J0D01*
G01X515617Y715443D01*
G02X515475Y715384I-142J141D01*
G01X513218D01*
G02X513076Y715443I0J200D01*
G01X511521Y716998D01*
G02X511462Y717140I141J142D01*
G01Y718723D01*
G02X511521Y718865I200J0D01*
G01X512359Y719703D01*
G03X512418Y719845I-141J142D01*
G01Y723896D01*
G02X512618Y724096I200J0D01*
G01X513684D01*
G03X515031Y724545I1J2241D01*
G02X515151Y724586I121J-159D01*
G37*
G36*
G01X521949Y799552D02*
X524902Y802505D01*
G02X525044Y802564I142J-141D01*
G01X527447D01*
G02X527589Y802505I0J-200D01*
G01X527958Y802136D01*
G02X528017Y801994I-141J-142D01*
G01Y796076D01*
G02X527958Y795934I-200J0D01*
G01X527766Y795742D01*
G02X527624Y795683I-142J141D01*
G01X522889D01*
G02X522747Y795742I0J200D01*
G01X521949Y796540D01*
G02X521890Y796682I141J142D01*
G01Y799410D01*
G02X521949Y799552I200J0D01*
G37*
G36*
G01X520382Y1031271D02*
G03I-590J0D01*
G37*
G36*
G01X519973Y1348187D02*
G03I-491J0D01*
G37*
G36*
G01X512093D02*
G03I-491J0D01*
G37*
G36*
G01X507733D02*
G03I-491J0D01*
G37*
G36*
G01X519973Y1360099D02*
G03I-491J0D01*
G37*
G36*
G01X512093D02*
G03I-491J0D01*
G37*
G36*
G01X507733D02*
G03I-491J0D01*
G37*
G36*
G01X519973Y1372385D02*
G03I-491J0D01*
G37*
G36*
G01X512093D02*
G03I-491J0D01*
G37*
G36*
G01X507733D02*
G03I-491J0D01*
G37*
G36*
G01X519973Y1384297D02*
G03I-491J0D01*
G37*
G36*
G01X512093D02*
G03I-491J0D01*
G37*
G36*
G01X519973Y1396583D02*
G03I-491J0D01*
G37*
G36*
G01X512093D02*
G03I-491J0D01*
G37*
G36*
G01X507733D02*
G03I-491J0D01*
G37*
G36*
G01Y1384297D02*
G03I-491J0D01*
G37*
G36*
G01X519973Y1408495D02*
G03I-491J0D01*
G37*
G36*
G01X512093D02*
G03I-491J0D01*
G37*
G36*
G01X507733D02*
G03I-491J0D01*
G37*
G36*
G01X515246Y1460782D02*
G03I-491J0D01*
G37*
G36*
G01Y1465513D02*
G03I-491J0D01*
G37*
G36*
G01Y1480867D02*
G03I-491J0D01*
G37*
G36*
G01Y1476136D02*
G03I-491J0D01*
G37*
G36*
G01Y1470244D02*
G03I-491J0D01*
G37*
G36*
G01Y1491491D02*
G03I-491J0D01*
G37*
G36*
G01Y1485598D02*
G03I-491J0D01*
G37*
G36*
G01Y1496222D02*
G03I-491J0D01*
G37*
G36*
G01Y1511576D02*
G03I-491J0D01*
G37*
G36*
G01Y1506845D02*
G03I-491J0D01*
G37*
G36*
G01Y1500953D02*
G03I-491J0D01*
G37*
G36*
G01Y1516307D02*
G03I-491J0D01*
G37*
G36*
G01Y1572606D02*
G03I-491J0D01*
G37*
G36*
G01Y1563144D02*
G03I-491J0D01*
G37*
G36*
G01Y1578498D02*
G03I-491J0D01*
G37*
G36*
G01Y1567875D02*
G03I-491J0D01*
G37*
G36*
G01Y1593853D02*
G03I-491J0D01*
G37*
G36*
G01Y1583229D02*
G03I-491J0D01*
G37*
G36*
G01Y1587960D02*
G03I-491J0D01*
G37*
G36*
G01Y1598584D02*
G03I-491J0D01*
G37*
G36*
G01Y1603315D02*
G03I-491J0D01*
G37*
G36*
G01Y1609207D02*
G03I-491J0D01*
G37*
G36*
G01Y1613938D02*
G03I-491J0D01*
G37*
G36*
G01Y1618669D02*
G03I-491J0D01*
G37*
G36*
G01X594744Y54588D02*
X623251D01*
X623486Y54353D01*
Y52826D01*
X623251Y52591D01*
X594744D01*
G03X588807Y46654I0J-5937D01*
G01Y7874D01*
G02X582933Y2000I-5874J0D01*
G01X535689D01*
G02X529815Y7874I0J5874D01*
G01Y46526D01*
X531812D01*
Y7874D01*
G03X535687Y3998I3876J0D01*
G01X582933D01*
G03X586810Y7874I0J3877D01*
G01Y46654D01*
G02X594744Y54588I7934J0D01*
G37*
G36*
G01X555306Y581389D02*
X617051D01*
X622297D01*
X625815Y577871D01*
X636266D01*
G02X636408Y577812I0J-200D01*
G01X637139Y577081D01*
G02X637198Y576939I-141J-142D01*
G01Y576791D01*
G02X637139Y576650I-200J1D01*
G01X637112Y576623D01*
Y561418D01*
G02X637054Y561277I-200J0D01*
G01X637020Y561243D01*
G02X636878Y561184I-142J141D01*
G01X625090D01*
G03X624948Y561125I0J-200D01*
G01X616229Y552406D01*
G02X616087Y552347I-142J141D01*
G01X600729D01*
X600614Y552457D01*
X600610Y552537D01*
G03X597610I-1500J-71D01*
G01X597606Y552457D01*
X597491Y552347D01*
X534817D01*
G02X534675Y552406I0J200D01*
G01X533489Y553592D01*
G02X533430Y553734I141J142D01*
G01Y567086D01*
G02X533489Y567228I200J0D01*
G01X539397Y573136D01*
G02X539539Y573195I142J-141D01*
G01X546946D01*
G03X547088Y573254I0J200D01*
G01X555164Y581330D01*
G02X555306Y581389I142J-141D01*
G37*
G36*
G01X529249Y693386D02*
X530667D01*
X531126Y693845D01*
X548718D01*
X549161Y693402D01*
Y692283D01*
Y685539D01*
X548791Y685169D01*
X546509D01*
X543915D01*
X542166D01*
X538978D01*
X537638Y686509D01*
X535911D01*
X530297D01*
X528607Y688199D01*
Y690355D01*
Y692744D01*
X529249Y693386D01*
G37*
G36*
G01X525389Y723883D02*
X534761D01*
G02X534903Y723824I0J-200D01*
G01X535504Y723223D01*
G02X535563Y723081I-141J-142D01*
G01Y719606D01*
G02X535521Y719483I-200J0D01*
G03X535122Y718317I1502J-1165D01*
G03X535142Y718041I1901J-1D01*
G01X535149Y717994D01*
X535119Y717904D01*
X534106Y716891D01*
G02X533964Y716832I-142J141D01*
G01X532207D01*
G03X532065Y716773I0J-200D01*
G01X532044Y716752D01*
X531974D01*
G03X531774Y716552I0J-200D01*
G01Y716524D01*
X531743Y716451D01*
X531037Y715745D01*
G03X530978Y715603I141J-142D01*
G01Y713205D01*
G02X530919Y713063I-200J0D01*
G01X530201Y712345D01*
G02X530059Y712286I-142J141D01*
G01X525155D01*
G02X525013Y712345I0J200D01*
G01X524840Y712518D01*
G02X524781Y712660I141J142D01*
G01Y723275D01*
G02X524840Y723417I200J0D01*
G01X525247Y723824D01*
G02X525389Y723883I142J-141D01*
G37*
G36*
G01X550275Y758128D02*
Y770128D01*
X549775Y770628D01*
X535275D01*
X534275Y769628D01*
Y758628D01*
X535275Y757628D01*
X549775D01*
X550275Y758128D01*
G37*
G36*
G01X541241Y806149D02*
X536741D01*
X536241Y805649D01*
Y787649D01*
X537241Y786649D01*
X541741D01*
X542241Y787149D01*
Y805149D01*
X541241Y806149D01*
G37*
G36*
G01X527936Y911458D02*
G03I-590J0D01*
G37*
G36*
G01X536573Y1348187D02*
G03I-491J0D01*
G37*
G36*
G01X532213D02*
G03I-491J0D01*
G37*
G36*
G01X524333D02*
G03I-491J0D01*
G37*
G36*
G01X536573Y1360099D02*
G03I-491J0D01*
G37*
G36*
G01X532213D02*
G03I-491J0D01*
G37*
G36*
G01X524333D02*
G03I-491J0D01*
G37*
G36*
G01X536573Y1372385D02*
G03I-491J0D01*
G37*
G36*
G01X532213D02*
G03I-491J0D01*
G37*
G36*
G01X524333D02*
G03I-491J0D01*
G37*
G36*
G01X536573Y1384297D02*
G03I-491J0D01*
G37*
G36*
G01Y1396583D02*
G03I-491J0D01*
G37*
G36*
G01X532213D02*
G03I-491J0D01*
G37*
G36*
G01X524333D02*
G03I-491J0D01*
G37*
G36*
G01X532213Y1384297D02*
G03I-491J0D01*
G37*
G36*
G01X524333D02*
G03I-491J0D01*
G37*
G36*
G01X536573Y1408495D02*
G03I-491J0D01*
G37*
G36*
G01X532213D02*
G03I-491J0D01*
G37*
G36*
G01X524333D02*
G03I-491J0D01*
G37*
G36*
G01X548979Y683209D02*
X545625D01*
X545492Y683076D01*
Y676877D01*
Y674065D01*
X545887Y673670D01*
X548763D01*
X549409Y674316D01*
Y677109D01*
Y682779D01*
X548979Y683209D01*
G37*
G36*
G01X553241Y808649D02*
X550241D01*
X548741Y807149D01*
Y791649D01*
Y788649D01*
X549741Y787649D01*
X552241D01*
X553741Y789149D01*
Y791649D01*
Y793269D01*
X553164Y793846D01*
Y798470D01*
X553195Y798501D01*
Y798947D01*
X553741Y799493D01*
Y808149D01*
X553241Y808649D01*
G37*
G36*
G01X559055Y794670D02*
X561890D01*
G02X562032Y794611I0J-200D01*
G01X563169Y793474D01*
G02X563228Y793332I-141J-142D01*
G01Y790945D01*
G02X563169Y790803I-200J0D01*
G01X562400Y790034D01*
G02X562258Y789975I-142J141D01*
G01X555471D01*
G02X555329Y790034I0J200D01*
G01X554974Y790389D01*
G02X554915Y790531I141J142D01*
G01Y793967D01*
G02X554974Y794109I200J0D01*
G01X555294Y794429D01*
G02X555435Y794488I142J-141D01*
G01X558241D01*
G03X559016Y794653I0J1901D01*
G01X559055Y794670D01*
G37*
G36*
G01X548650Y880804D02*
X553496D01*
X553690Y880610D01*
Y874249D01*
X553131Y873690D01*
X547581D01*
X546890Y874381D01*
Y879997D01*
X547697Y880804D01*
X548650D01*
G37*
G36*
G01X555467Y880998D02*
X560216D01*
X561185Y880029D01*
Y872469D01*
Y872217D01*
X559334Y870366D01*
X554984D01*
X554821Y870529D01*
Y872112D01*
Y880352D01*
X555467Y880998D01*
G37*
G36*
G01X548813Y1348187D02*
G03I-491J0D01*
G37*
G36*
G01X544453D02*
G03I-491J0D01*
G37*
G36*
G01X548813Y1360099D02*
G03I-491J0D01*
G37*
G36*
G01X544453D02*
G03I-491J0D01*
G37*
G36*
G01X548813Y1372385D02*
G03I-491J0D01*
G37*
G36*
G01X544453D02*
G03I-491J0D01*
G37*
G36*
G01X548813Y1396583D02*
G03I-491J0D01*
G37*
G36*
G01Y1384297D02*
G03I-491J0D01*
G37*
G36*
G01X544453D02*
G03I-491J0D01*
G37*
G36*
G01Y1396583D02*
G03I-491J0D01*
G37*
G36*
G01X548813Y1408495D02*
G03I-491J0D01*
G37*
G36*
G01X544453D02*
G03I-491J0D01*
G37*
G36*
G01X554883Y1524800D02*
X568932D01*
X568977Y1524789D01*
X568999Y1524778D01*
G03X569575Y1524638I578J1122D01*
G01X582779D01*
G02X582920Y1524580I0J-200D01*
G01X587141Y1520359D01*
G03X587283Y1520300I142J141D01*
G01X614659D01*
G02X614801Y1520241I0J-200D01*
G01X618783Y1516259D01*
G02X618842Y1516117I-141J-142D01*
G01Y1438425D01*
G02X618783Y1438283I-200J0D01*
G01X616709Y1436209D01*
G02X616567Y1436150I-142J141D01*
G01X554933D01*
G02X554791Y1436209I0J200D01*
G01X552864Y1438136D01*
G02X552805Y1438278I141J142D01*
G01Y1522722D01*
G02X552864Y1522864I200J0D01*
G01X554741Y1524741D01*
G02X554883Y1524800I142J-141D01*
G37*
G36*
G01X582903Y953407D02*
Y934507D01*
X582203Y933807D01*
X562503D01*
X562003Y934307D01*
Y942707D01*
X562203Y942907D01*
X569203D01*
X569803Y942307D01*
Y940407D01*
X570653Y939557D01*
X575353D01*
X576303Y940507D01*
Y953507D01*
Y956207D01*
X576503Y956407D01*
X576903Y956807D01*
X582503D01*
X582903Y956407D01*
Y953407D01*
G37*
G36*
G01X562603Y953707D02*
X569203D01*
X570203Y952707D01*
Y951207D01*
X571203Y950207D01*
X574903D01*
X575203Y949907D01*
Y945707D01*
X575003Y945507D01*
X562403D01*
X562103Y945807D01*
Y953207D01*
X562603Y953707D01*
G37*
G36*
G01X591518Y1066535D02*
G02I-17700J0D01*
G37*
G36*
G01Y1263386D02*
G02I-17700J0D01*
G37*
G36*
G01X568933Y1348187D02*
G03I-491J0D01*
G37*
G36*
G01X561053D02*
G03I-491J0D01*
G37*
G36*
G01X556693D02*
G03I-491J0D01*
G37*
G36*
G01X568933Y1360099D02*
G03I-491J0D01*
G37*
G36*
G01X561053D02*
G03I-491J0D01*
G37*
G36*
G01X556693D02*
G03I-491J0D01*
G37*
G36*
G01X568933Y1372385D02*
G03I-491J0D01*
G37*
G36*
G01X561053D02*
G03I-491J0D01*
G37*
G36*
G01X556693D02*
G03I-491J0D01*
G37*
G36*
G01X568933Y1384297D02*
G03I-491J0D01*
G37*
G36*
G01X561053D02*
G03I-491J0D01*
G37*
G36*
G01X568933Y1396583D02*
G03I-491J0D01*
G37*
G36*
G01X561053D02*
G03I-491J0D01*
G37*
G36*
G01X556693D02*
G03I-491J0D01*
G37*
G36*
G01Y1384297D02*
G03I-491J0D01*
G37*
G36*
G01X568933Y1408495D02*
G03I-491J0D01*
G37*
G36*
G01X561053D02*
G03I-491J0D01*
G37*
G36*
G01X556693D02*
G03I-491J0D01*
G37*
G36*
G01X583866Y203641D02*
X595074D01*
X596046Y202669D01*
Y195995D01*
X594492Y194441D01*
X583347D01*
X582635Y195153D01*
Y202410D01*
X583866Y203641D01*
G37*
G36*
G01X579841Y903364D02*
G03I-590J0D01*
G37*
G36*
G01X583296Y908959D02*
G03I-590J0D01*
G37*
G36*
G01X584303Y948307D02*
X589203D01*
X592303D01*
X594203D01*
X595003Y947507D01*
Y934507D01*
X594303Y933807D01*
X592703D01*
X584603D01*
X584003Y934407D01*
Y948007D01*
X584303Y948307D01*
G37*
G36*
G01X601466Y174710D02*
X647941D01*
G02X648081Y174653I0J-200D01*
G01X648082Y174652D01*
X650284Y172450D01*
G02X650286Y172448I-140J-142D01*
G02X650343Y172308I-143J-140D01*
G01Y143109D01*
X650262Y143003D01*
X650196Y142985D01*
G03Y139509I477J-1738D01*
G01X650262Y139491D01*
X650343Y139385D01*
Y104934D01*
G02X650325Y104852I-200J1D01*
G01X650277Y104743D01*
X650247Y104716D01*
G03X649774Y103621I1031J-1095D01*
G03X649934Y102946I1502J0D01*
G01X649955Y102904D01*
X649957Y102814D01*
X649806Y102487D01*
G02X649672Y102377I-182J85D01*
G01X649671D01*
G03X648292Y100625I423J-1752D01*
G03X649971Y98827I1802J0D01*
G01X650009Y98824D01*
X650077Y98792D01*
X650289Y98565D01*
G02X650299Y98553I-148J-134D01*
G02X650343Y98428I-156J-125D01*
G01Y77986D01*
G02X650223Y77803I-200J0D01*
G01X649833Y77632D01*
X649716Y77652D01*
X649672Y77692D01*
G03X648655Y78089I-1017J-1104D01*
G03X647406Y77421I0J-1502D01*
G01X647382Y77386D01*
X647313Y77341D01*
X646982Y77288D01*
G02X646828Y77327I-32J197D01*
G03X645907Y77642I-920J-1187D01*
G01X645877D01*
G03X644405Y76140I30J-1502D01*
G03X645907Y74638I1502J0D01*
G03X647156Y75306I0J1502D01*
G01X647180Y75341D01*
X647249Y75386D01*
X647621Y75446D01*
X647701Y75426D01*
X647734Y75400D01*
G03X648350Y75116I921J1187D01*
G01X648404Y75105D01*
X648485Y75031D01*
X648602Y74640D01*
G02X648552Y74442I-192J-57D01*
G01X648135Y74025D01*
X648096Y74009D01*
G03X647261Y73174I559J-1394D01*
G01X647245Y73135D01*
X647116Y73006D01*
X647088Y72977D01*
X647014Y72947D01*
X600901D01*
G02X600759Y73006I0J200D01*
G01X599443Y74322D01*
X599414Y74350D01*
X599384Y74424D01*
Y172628D01*
G02X599441Y172768I200J0D01*
G01X599442Y172769D01*
X601324Y174651D01*
G02X601326Y174653I142J-140D01*
G02X601466Y174710I140J-143D01*
G37*
G36*
G01X597719Y913386D02*
G03I-590J0D01*
G37*
G36*
G01X604995Y1034870D02*
G03I-590J0D01*
G37*
G36*
G01X592488Y1035011D02*
G03I-590J0D01*
G37*
G36*
G01X620741Y1040363D02*
G03I-590J0D01*
G37*
G36*
G01X619676Y1056453D02*
G03I-590J0D01*
G37*
G36*
G01X632820Y1167797D02*
X634733D01*
G02X634873Y1167740I0J-200D01*
G01X634874Y1167739D01*
X635383Y1167230D01*
G02X635385Y1167228I-140J-142D01*
G02X635442Y1167088I-143J-140D01*
G01Y1148690D01*
G03X635501Y1148548I200J0D01*
G01X636565Y1147484D01*
X636578Y1147463D01*
G03X637031Y1147010I1119J666D01*
G01X637052Y1146997D01*
X637699Y1146350D01*
G02X637748Y1146147I-141J-142D01*
G01X637622Y1145755D01*
X637538Y1145683D01*
X637482Y1145673D01*
G03X636395Y1144389I215J-1284D01*
G03X637279Y1143156I1302J0D01*
G01X637340Y1143135D01*
X637415Y1143031D01*
Y1142007D01*
X637340Y1141903D01*
X637279Y1141882D01*
G03X636395Y1140649I418J-1233D01*
G03X638999I1302J0D01*
G03X638977Y1140890I-1302J3D01*
G02X639003Y1141031I196J37D01*
G01X639142Y1141259D01*
G02X639193Y1141315I171J-104D01*
G01X639222Y1141337D01*
X639257Y1141348D01*
G03X639618Y1141829I-140J481D01*
G01Y1143330D01*
G03X639581Y1143518I-501J-1D01*
G02X639567Y1143607I186J75D01*
G03X639568Y1143639I-450J30D01*
G01Y1145139D01*
G03X639117Y1145590I-451J0D01*
G01X638874D01*
G02X638708Y1145679I0J200D01*
G01X638680Y1145720D01*
X638670Y1145818D01*
X638697Y1145885D01*
G02X638882Y1146010I185J-75D01*
G01X640955D01*
G02X641155Y1145810I0J-200D01*
G01Y1145690D01*
X641156Y1145689D01*
Y1145569D01*
G03X641657Y1145068I501J0D01*
G01X642426D01*
G02X642626Y1144868I0J-200D01*
G01Y1142043D01*
Y1142033D01*
G02X642540Y1141879I-200J11D01*
G02X642527Y1141870I-120J159D01*
G01X642231Y1141698D01*
X642123D01*
X642076Y1141726D01*
G03X641437Y1141901I-638J-1077D01*
G03Y1139397I0J-1252D01*
G03X642076Y1139572I1J1252D01*
G01X642123Y1139600D01*
X642231D01*
X642527Y1139428D01*
G02X642540Y1139419I-107J-168D01*
G02X642626Y1139265I-114J-165D01*
G01Y1138303D01*
Y1138293D01*
G02X642540Y1138139I-200J11D01*
G02X642527Y1138130I-120J159D01*
G01X642231Y1137958D01*
X642123D01*
X642076Y1137986D01*
G03X641437Y1138161I-638J-1077D01*
G03X640185Y1136909I0J-1252D01*
G03X640792Y1135836I1252J0D01*
G02X640889Y1135664I-103J-171D01*
G01Y1134414D01*
G02X640792Y1134242I-200J-1D01*
G03X640185Y1133169I645J-1073D01*
G03X641437Y1131917I1252J0D01*
G03X642076Y1132092I1J1252D01*
G01X642123Y1132120D01*
X642231D01*
X642527Y1131948D01*
G02X642540Y1131939I-107J-168D01*
G02X642626Y1131785I-114J-165D01*
G01Y1130823D01*
Y1130813D01*
G02X642540Y1130659I-200J11D01*
G02X642527Y1130650I-120J159D01*
G01X642231Y1130478D01*
X642123D01*
X642076Y1130506D01*
G03X641437Y1130681I-638J-1077D01*
G03Y1128177I0J-1252D01*
G03X642076Y1128352I1J1252D01*
G01X642123Y1128380D01*
X642231D01*
X642527Y1128208D01*
G02X642540Y1128199I-107J-168D01*
G02X642626Y1128045I-114J-165D01*
G01Y1127082D01*
Y1127072D01*
G02X642540Y1126918I-200J11D01*
G02X642527Y1126909I-120J159D01*
G01X642231Y1126737D01*
X642123D01*
X642076Y1126765D01*
G03X641437Y1126940I-638J-1077D01*
G03Y1124436I0J-1252D01*
G03X642076Y1124611I1J1252D01*
G01X642123Y1124639D01*
X642231D01*
X642527Y1124467D01*
G02X642540Y1124458I-107J-168D01*
G02X642626Y1124304I-114J-165D01*
G01Y1123537D01*
G03X642685Y1123395I200J0D01*
G01X642798Y1123282D01*
G02X642857Y1123140I-141J-142D01*
G01Y1122735D01*
G02X642657Y1122535I-200J0D01*
G01X642606D01*
X642517Y1122584D01*
X642489Y1122627D01*
G03X641437Y1123200I-1052J-679D01*
G03Y1120696I0J-1252D01*
G03X642210Y1120963I0J1252D01*
G01X642256Y1120999D01*
X642369Y1121011D01*
X642744Y1120828D01*
G02X642857Y1120649I-87J-180D01*
G01Y1119507D01*
G02X642744Y1119328I-200J1D01*
G01X642369Y1119145D01*
X642256Y1119157D01*
X642210Y1119193D01*
G03X641437Y1119460I-773J-985D01*
G03Y1116956I0J-1252D01*
G03X642489Y1117529I0J1252D01*
G01X642517Y1117572D01*
X642606Y1117621D01*
X642657D01*
G02X642857Y1117421I0J-200D01*
G01Y1117158D01*
G02X642798Y1117016I-200J0D01*
G01X641533Y1115751D01*
X641461Y1115720D01*
X641422D01*
G03X640223Y1114775I15J-1252D01*
G01X640206Y1114708D01*
X640098Y1114624D01*
X639036D01*
X638928Y1114708D01*
X638911Y1114775D01*
G03X636483I-1214J-307D01*
G01X636466Y1114708D01*
X636358Y1114624D01*
X635296D01*
X635188Y1114708D01*
X635171Y1114775D01*
G03X632743I-1214J-307D01*
G01X632726Y1114708D01*
X632618Y1114624D01*
X631555D01*
X631447Y1114708D01*
X631430Y1114775D01*
G03X629002I-1214J-307D01*
G01X628985Y1114708D01*
X628877Y1114624D01*
X627815D01*
X627707Y1114708D01*
X627690Y1114775D01*
G03X626476Y1115720I-1214J-307D01*
G03X625272Y1114810I0J-1251D01*
G01X625253Y1114746D01*
X625146Y1114665D01*
X624066D01*
X623959Y1114746D01*
X623940Y1114810D01*
G03X621532I-1204J-341D01*
G01X621513Y1114746D01*
X621406Y1114665D01*
X620326D01*
X620219Y1114746D01*
X620200Y1114810D01*
G03X618996Y1115720I-1204J-341D01*
G03X618071Y1115312I0J-1253D01*
G01X618068Y1115308D01*
X618065Y1115305D01*
G02X617782I-142J141D01*
G01X617646Y1115441D01*
G02X617587Y1115583I141J142D01*
G01Y1122350D01*
G02X617646Y1122492I200J0D01*
G01X618076Y1122922D01*
G02X618218Y1122981I142J-141D01*
G01X624950D01*
G02X625116Y1122892I0J-200D01*
G01X625329Y1122573D01*
X625339Y1122475D01*
X625320Y1122428D01*
G03X625224Y1121948I1156J-481D01*
G03X627728I1252J0D01*
G03X627378Y1122817I-1252J1D01*
G01X627350Y1122845D01*
X627321Y1122917D01*
X627324Y1123237D01*
G02X627383Y1123377I200J-2D01*
G01X627472Y1123466D01*
G03X627531Y1123608I-141J142D01*
G01Y1128725D01*
X627545Y1128775D01*
X627558Y1128798D01*
G03Y1130058I-1082J630D01*
G01X627545Y1130081D01*
X627531Y1130131D01*
Y1132100D01*
G03X627472Y1132242I-200J0D01*
G01X626920Y1132794D01*
G03X626778Y1132853I-142J-141D01*
G01X621438D01*
G02X621296Y1132912I0J200D01*
G01X619877Y1134331D01*
G02X619818Y1134473I141J142D01*
G01Y1136157D01*
G02X619877Y1136299I200J0D01*
G01X620469Y1136891D01*
G02X620610Y1136950I142J-141D01*
G01X622066D01*
X625110D01*
X625223Y1136849D01*
X625232Y1136772D01*
G03X626476Y1135657I1244J136D01*
G03X627728Y1136909I0J1252D01*
G03X627486Y1137649I-1252J0D01*
G01X627442Y1137709D01*
X627453Y1137856D01*
X627472Y1137875D01*
G03X627531Y1138017I-141J142D01*
G01Y1139824D01*
G02X627564Y1139934I200J0D01*
G03Y1141364I-1087J715D01*
G02X627531Y1141474I167J110D01*
G01Y1143564D01*
G02X627564Y1143674I200J0D01*
G03Y1145104I-1087J715D01*
G01X627547Y1145129D01*
X627531Y1145184D01*
Y1145307D01*
G02X627588Y1145447I200J0D01*
G01X627589Y1145448D01*
X628733Y1146592D01*
G02X628735Y1146594I142J-140D01*
G02X628875Y1146651I140J-143D01*
G01X628933D01*
G03X628935I1J1202D01*
G01X628939D01*
G03X628963Y1146650I62J1200D01*
G01X631111D01*
G03X631135Y1146651I-38J1201D01*
G01X631139D01*
G03X631141I1J1202D01*
G01X631715D01*
G03X631857Y1146710I0J200D01*
G01X632478Y1147331D01*
G03X632537Y1147473I-141J142D01*
G01Y1167514D01*
G02X632594Y1167654I200J0D01*
G01X632595Y1167655D01*
X632678Y1167738D01*
G02X632680Y1167740I142J-140D01*
G02X632820Y1167797I140J-143D01*
G37*
G36*
G01X697106Y54588D02*
X725589D01*
X725942Y54235D01*
Y52944D01*
X725589Y52591D01*
X697106D01*
G03X691169Y46654I0J-5937D01*
G01Y7874D01*
G02X685295Y2000I-5874J0D01*
G01X638051D01*
G02X632177Y7874I0J5874D01*
G01Y45760D01*
X634174D01*
Y7874D01*
G03X638049Y3998I3876J0D01*
G01X685295D01*
G03X689172Y7874I0J3877D01*
G01Y46654D01*
G02X697106Y54588I7934J0D01*
G37*
G36*
G01X621305Y1046785D02*
G03I-590J0D01*
G37*
G36*
G01X622238Y1131846D02*
X626159D01*
G02X626301Y1131787I0J-200D01*
G01X626471Y1131617D01*
G02X626529Y1131476I-142J-141D01*
G01Y1124752D01*
G02X626329Y1124552I-200J0D01*
G01X623039D01*
G02X622897Y1124611I0J200D01*
G01X621794Y1125714D01*
G02X621735Y1125856I141J142D01*
G01Y1131343D01*
G02X621794Y1131485I200J0D01*
G01X622096Y1131787D01*
G02X622238Y1131846I142J-141D01*
G37*
G36*
G01X628920Y1167697D02*
X631154D01*
G02X631296Y1167638I0J-200D01*
G01X631477Y1167457D01*
G02X631535Y1167316I-142J-141D01*
G01Y1148078D01*
G02X631477Y1147937I-200J0D01*
G01X631251Y1147711D01*
G02X631110Y1147652I-142J141D01*
G01X628964D01*
G02X628823Y1147711I1J200D01*
G01X628296Y1148238D01*
G02X628237Y1148380I141J142D01*
G01Y1155227D01*
X628241Y1155247D01*
G03X628278Y1155610I-1765J363D01*
G03X628241Y1155973I-1802J0D01*
G01X628237Y1155993D01*
Y1167014D01*
G02X628296Y1167156I200J0D01*
G01X628778Y1167638D01*
G02X628920Y1167697I142J-141D01*
G37*
G36*
G01X629295Y1182697D02*
X631194D01*
X631268Y1182667D01*
X631296Y1182638D01*
X631477Y1182457D01*
G02X631535Y1182316I-142J-141D01*
G01Y1171465D01*
G03X631586Y1171332I200J0D01*
G01X631611Y1171304D01*
X631637Y1171236D01*
Y1170440D01*
X631607Y1170366D01*
X631578Y1170338D01*
X630996Y1169756D01*
G02X630854Y1169697I-142J141D01*
G01X628980D01*
X628906Y1169727D01*
X628878Y1169756D01*
X628496Y1170138D01*
G02X628437Y1170280I141J142D01*
G01Y1173375D01*
G02X628462Y1173473I200J1D01*
G03X628748Y1174574I-1976J1101D01*
G01Y1182345D01*
X628814Y1182444D01*
X628868Y1182468D01*
G03X629169Y1182652I-522J1193D01*
G02X629295Y1182697I126J-155D01*
G37*
G36*
G01X635414Y1172164D02*
X634879Y1171629D01*
X634737Y1171615D01*
X634677Y1171654D01*
G03X633957Y1171872I-721J-1083D01*
G01X633956D01*
G03X633205Y1171634I0J-1302D01*
G01X633180Y1171615D01*
X633122Y1171597D01*
X632820D01*
G02X632678Y1171656I0J200D01*
G01X632596Y1171738D01*
X632567Y1171766D01*
X632537Y1171840D01*
Y1182814D01*
G02X632596Y1182956I200J0D01*
G01X632678Y1183038D01*
X632706Y1183067D01*
X632780Y1183097D01*
X635154D01*
G02X635296Y1183038I0J-200D01*
G01X635414Y1182920D01*
G02X635473Y1182778I-141J-142D01*
G01Y1172306D01*
G02X635414Y1172164I-200J0D01*
G37*
G36*
G01X636779Y1372385D02*
G03I-491J0D01*
G37*
G36*
G01Y1384297D02*
G03I-491J0D01*
G37*
G36*
G01Y1396583D02*
G03I-491J0D01*
G37*
G36*
G01X632419D02*
G03I-491J0D01*
G37*
G36*
G01X624539D02*
G03I-491J0D01*
G37*
G36*
G01X632419Y1408495D02*
G03I-491J0D01*
G37*
G36*
G01X624539D02*
G03I-491J0D01*
G37*
G36*
G01X636779D02*
G03I-491J0D01*
G37*
G36*
G01X636506Y1460782D02*
G03I-491J0D01*
G37*
G36*
G01X627845Y1461182D02*
G03I-491J0D01*
G37*
G36*
G01Y1456451D02*
G03I-491J0D01*
G37*
G36*
G01X636506Y1465513D02*
G03I-491J0D01*
G37*
G36*
G01X627845Y1465913D02*
G03I-491J0D01*
G37*
G36*
G01X636506Y1476136D02*
G03I-491J0D01*
G37*
G36*
G01X627845Y1476536D02*
G03I-491J0D01*
G37*
G36*
G01X636506Y1480867D02*
G03I-491J0D01*
G37*
G36*
G01X627845Y1481267D02*
G03I-491J0D01*
G37*
G36*
G01Y1471805D02*
G03I-491J0D01*
G37*
G36*
G01X636506Y1470244D02*
G03I-491J0D01*
G37*
G36*
G01X627845Y1496622D02*
G03I-491J0D01*
G37*
G36*
G01Y1487160D02*
G03I-491J0D01*
G37*
G36*
G01X636506Y1485598D02*
G03I-491J0D01*
G37*
G36*
G01Y1491491D02*
G03I-491J0D01*
G37*
G36*
G01X627845Y1491891D02*
G03I-491J0D01*
G37*
G36*
G01X636506Y1496222D02*
G03I-491J0D01*
G37*
G36*
G01X627845Y1511976D02*
G03I-491J0D01*
G37*
G36*
G01X636506Y1511576D02*
G03I-491J0D01*
G37*
G36*
G01X627845Y1502514D02*
G03I-491J0D01*
G37*
G36*
G01X636506Y1500953D02*
G03I-491J0D01*
G37*
G36*
G01Y1506845D02*
G03I-491J0D01*
G37*
G36*
G01X627845Y1507245D02*
G03I-491J0D01*
G37*
G36*
G01X636506Y1516307D02*
G03I-491J0D01*
G37*
G36*
G01X627845Y1558813D02*
G03I-491J0D01*
G37*
G36*
G01Y1578898D02*
G03I-491J0D01*
G37*
G36*
G01X636506Y1567875D02*
G03I-491J0D01*
G37*
G36*
G01X627845Y1568275D02*
G03I-491J0D01*
G37*
G36*
G01Y1574167D02*
G03I-491J0D01*
G37*
G36*
G01X636506Y1572606D02*
G03I-491J0D01*
G37*
G36*
G01Y1578498D02*
G03I-491J0D01*
G37*
G36*
G01Y1563144D02*
G03I-491J0D01*
G37*
G36*
G01X627845Y1563544D02*
G03I-491J0D01*
G37*
G36*
G01Y1583629D02*
G03I-491J0D01*
G37*
G36*
G01Y1589522D02*
G03I-491J0D01*
G37*
G36*
G01X636506Y1587960D02*
G03I-491J0D01*
G37*
G36*
G01Y1593853D02*
G03I-491J0D01*
G37*
G36*
G01X627845Y1594253D02*
G03I-491J0D01*
G37*
G36*
G01X636506Y1583229D02*
G03I-491J0D01*
G37*
G36*
G01Y1609207D02*
G03I-491J0D01*
G37*
G36*
G01X627845Y1609607D02*
G03I-491J0D01*
G37*
G36*
G01Y1604876D02*
G03I-491J0D01*
G37*
G36*
G01X636506Y1603315D02*
G03I-491J0D01*
G37*
G36*
G01Y1598584D02*
G03I-491J0D01*
G37*
G36*
G01X627845Y1598984D02*
G03I-491J0D01*
G37*
G36*
G01X636506Y1613938D02*
G03I-491J0D01*
G37*
G36*
G01X627845Y1614338D02*
G03I-491J0D01*
G37*
G36*
G01X636506Y1618669D02*
G03I-491J0D01*
G37*
G36*
G01X638155Y576249D02*
X641928D01*
X643369D01*
X644608D01*
X645467Y575390D01*
Y549500D01*
X644967Y549000D01*
X639607D01*
X639107Y549500D01*
Y559538D01*
X638114Y560531D01*
Y576208D01*
X638155Y576249D01*
G37*
G36*
G01X642357Y1192000D02*
X643304D01*
G02X643446Y1191941I0J-200D01*
G01X643928Y1191459D01*
G02X643987Y1191317I-141J-142D01*
G01Y1187283D01*
G02X643928Y1187141I-200J0D01*
G01X643846Y1187059D01*
X643818Y1187030D01*
X643744Y1187000D01*
X640370D01*
G03X640228Y1186941I0J-200D01*
G01X639765Y1186478D01*
X639749Y1186467D01*
G03X639625Y1186343I251J-375D01*
G01X639614Y1186327D01*
X639346Y1186059D01*
G03X639287Y1185917I141J-142D01*
G01Y1176483D01*
G03X639346Y1176341I200J0D01*
G01X640728Y1174959D01*
G02X640787Y1174817I-141J-142D01*
G01Y1173083D01*
G02X640728Y1172941I-200J0D01*
G01X639246Y1171459D01*
G03X639187Y1171317I141J-142D01*
G01Y1150583D01*
G03X639246Y1150441I200J0D01*
G01X640628Y1149059D01*
G02X640687Y1148917I-141J-142D01*
G01Y1147602D01*
G02X640487Y1147402I-200J0D01*
G01X638146D01*
G02X638005Y1147461I1J200D01*
G01X637683Y1147782D01*
G03X637641Y1147814I-141J-142D01*
G01X637542Y1147871D01*
G02X637531Y1147878I102J172D01*
G02X637446Y1147963I166J251D01*
G02X637439Y1147974I165J113D01*
G01X637382Y1148073D01*
G03X637350Y1148115I-174J-99D01*
G01X636502Y1148963D01*
G02X636444Y1149105I142J141D01*
G01Y1167089D01*
G03X636395Y1167426I-1202J-3D01*
G01X636387Y1167453D01*
Y1171854D01*
X636399Y1171888D01*
G03X636454Y1172087I-1126J418D01*
G03X636475Y1172305I-1180J224D01*
G01Y1182779D01*
G03X636454Y1182997I-1201J-6D01*
G03X636399Y1183196I-1181J-219D01*
G01X636387Y1183230D01*
Y1186052D01*
G02X636414Y1186152I200J0D01*
G01X636473Y1186255D01*
X636505Y1186289D01*
X636526Y1186303D01*
G03Y1188499I-698J1098D01*
G01X636505Y1188513D01*
X636473Y1188547D01*
X636414Y1188650D01*
G02X636387Y1188750I173J100D01*
G01Y1189517D01*
G02X636446Y1189659I200J0D01*
G01X638728Y1191941D01*
G02X638870Y1192000I142J-141D01*
G01X640517D01*
G02X640579Y1191990I0J-200D01*
G01X640666Y1191961D01*
X640690Y1191944D01*
G03X642184I747J1067D01*
G01X642208Y1191961D01*
X642295Y1191990D01*
G02X642357Y1192000I62J-190D01*
G37*
G36*
G01X646968Y1186298D02*
X650188D01*
G02X650332Y1186236I-1J-200D01*
G01X650561Y1185994D01*
X650589Y1185917D01*
X650586Y1185875D01*
G03X650585Y1185850I451J-31D01*
G01Y1184350D01*
G03X651037Y1183898I452J0D01*
G01X652237D01*
G03X652373Y1183919I0J452D01*
G01X652403Y1183929D01*
X652435D01*
G02X652635Y1183729I0J-200D01*
G01Y1182719D01*
G03X652764Y1182180I1202J3D01*
G01X652770Y1182168D01*
X652783Y1182130D01*
X652831Y1182063D01*
X652834Y1182059D01*
G03X652893Y1181977I1004J660D01*
G01X652900Y1181968D01*
G02X652958Y1181791I-243J-178D01*
G01X652957D01*
X652958Y1181790D01*
G02X652888Y1181599I-301J2D01*
G03X652884Y1181593I164J-114D01*
G03X652834Y1181523I952J-733D01*
G01X652831Y1181519D01*
X652783Y1181452D01*
X652770Y1181414D01*
X652764Y1181402D01*
G03X652635Y1180863I1073J-542D01*
G01Y1179651D01*
G02X652436Y1179452I-200J0D01*
G01X651237D01*
G03X650785Y1179000I0J-452D01*
G01Y1177500D01*
G03X651237Y1177048I452J0D01*
G01X651814D01*
G02X651873Y1177039I0J-200D01*
G01X651954Y1177014D01*
X651978Y1176999D01*
G03X652657Y1176799I679J1053D01*
G01X652684D01*
G03X653143Y1176897I-27J1252D01*
G01X653200Y1176921D01*
X653319Y1176898D01*
X653769Y1176448D01*
G03X653777Y1176440I854J846D01*
G01X653779Y1176438D01*
X653904Y1176309D01*
G03X653972Y1176263I144J139D01*
G01X654158Y1176187D01*
X654159D01*
G03X654178Y1176179I476J1104D01*
G01X654359Y1176106D01*
G02X654425Y1176062I-76J-185D01*
G01X654628Y1175859D01*
G03X654770Y1175800I142J141D01*
G01X655157D01*
G02X655339Y1175682I0J-200D01*
G01X655513Y1175297D01*
X655496Y1175180D01*
X655457Y1175136D01*
G03X655146Y1174310I941J-826D01*
G03X655190Y1173983I1252J2D01*
G01X655196Y1173957D01*
Y1173424D01*
Y1172890D01*
G03X655647Y1172438I452J0D01*
G01X656398D01*
X657148D01*
G03X657600Y1172890I0J452D01*
G01Y1173957D01*
X657606Y1173983D01*
G03X657650Y1174310I-1208J329D01*
G03X657339Y1175136I-1252J0D01*
G01X657300Y1175180D01*
X657283Y1175297D01*
X657457Y1175682D01*
G02X657639Y1175800I182J-82D01*
G01X662637D01*
G02X662819Y1175682I0J-200D01*
G01X662993Y1175297D01*
X662976Y1175180D01*
X662937Y1175136D01*
G03X662626Y1174310I941J-826D01*
G03X662670Y1173983I1252J2D01*
G01X662676Y1173957D01*
Y1173424D01*
Y1172890D01*
G03X663127Y1172438I452J0D01*
G01X663878D01*
X664628D01*
G03X665080Y1172890I0J452D01*
G01Y1173957D01*
X665086Y1173983D01*
G03X665130Y1174310I-1208J329D01*
G03X664819Y1175136I-1252J0D01*
G01X664780Y1175180D01*
X664763Y1175297D01*
X664937Y1175682D01*
G02X665119Y1175800I182J-82D01*
G01X670117D01*
G02X670299Y1175682I0J-200D01*
G01X670473Y1175297D01*
X670456Y1175180D01*
X670417Y1175136D01*
G03X670106Y1174310I941J-826D01*
G03X670150Y1173983I1252J2D01*
G01X670156Y1173957D01*
Y1173424D01*
Y1172890D01*
G03X670607Y1172438I452J0D01*
G01X671358D01*
X672108D01*
G03X672560Y1172890I0J452D01*
G01Y1173957D01*
X672566Y1173983D01*
G03X672610Y1174310I-1208J329D01*
G03X672299Y1175136I-1252J0D01*
G01X672260Y1175180D01*
X672243Y1175297D01*
X672417Y1175682D01*
G02X672599Y1175800I182J-82D01*
G01X677597D01*
G02X677779Y1175682I0J-200D01*
G01X677953Y1175297D01*
X677936Y1175180D01*
X677897Y1175136D01*
G03X677586Y1174322I941J-826D01*
G01Y1174309D01*
G03X677630Y1173982I1252J2D01*
G01X677636Y1173957D01*
Y1172890D01*
G03X677863Y1172499I452J1D01*
G03X678089Y1172438I227J391D01*
G01X679589D01*
G03X680041Y1172890I0J452D01*
G01Y1173962D01*
X680048Y1173987D01*
G03X680090Y1174310I-1210J322D01*
G03X679779Y1175136I-1252J0D01*
G01X679740Y1175180D01*
X679723Y1175297D01*
X679897Y1175682D01*
G02X680079Y1175800I182J-82D01*
G01X685078D01*
G02X685260Y1175682I0J-200D01*
G01X685434Y1175297D01*
X685417Y1175180D01*
X685378Y1175136D01*
G03X685067Y1174328I941J-826D01*
G01Y1174310D01*
G03X685111Y1173982I1252J1D01*
G01X685118Y1173957D01*
Y1172890D01*
G03X685569Y1172438I452J0D01*
G01X685611D01*
X687129D01*
G03X687581Y1172890I0J452D01*
G01Y1174090D01*
G03X687572Y1174178I-452J-2D01*
G02X687568Y1174230I196J41D01*
G03X687571Y1174310I-1249J87D01*
G03X687260Y1175136I-1252J0D01*
G01X687221Y1175180D01*
X687204Y1175297D01*
X687378Y1175682D01*
G02X687560Y1175800I182J-82D01*
G01X696298D01*
G02X696480Y1175682I0J-200D01*
G01X696654Y1175297D01*
X696637Y1175180D01*
X696598Y1175136D01*
G03X696287Y1174310I941J-826D01*
G03X696330Y1173984I1252J-1D01*
G01X696337Y1173959D01*
Y1172890D01*
G03X696789Y1172438I452J0D01*
G01X698289D01*
G03X698741Y1172890I0J452D01*
G01Y1173959D01*
X698748Y1173984D01*
G03X698791Y1174310I-1209J325D01*
G03X698480Y1175136I-1252J0D01*
G01X698441Y1175180D01*
X698424Y1175297D01*
X698598Y1175682D01*
G02X698780Y1175800I182J-82D01*
G01X703779D01*
G02X703961Y1175682I0J-200D01*
G01X704135Y1175297D01*
X704118Y1175180D01*
X704079Y1175136D01*
G03X703768Y1174310I941J-826D01*
G03X703812Y1173983I1252J2D01*
G01X703818Y1173957D01*
Y1173424D01*
Y1172890D01*
G03X704269Y1172438I452J0D01*
G01X705020D01*
X705770D01*
G03X706222Y1172890I0J452D01*
G01Y1173957D01*
X706228Y1173983D01*
G03X706272Y1174310I-1208J329D01*
G03X705961Y1175136I-1252J0D01*
G01X705922Y1175180D01*
X705905Y1175297D01*
X706079Y1175682D01*
G02X706261Y1175800I182J-82D01*
G01X711259D01*
G02X711441Y1175682I0J-200D01*
G01X711615Y1175297D01*
X711598Y1175180D01*
X711559Y1175136D01*
G03X711248Y1174310I941J-826D01*
G03X711292Y1173983I1252J2D01*
G01X711298Y1173957D01*
Y1173424D01*
Y1172890D01*
G03X711749Y1172438I452J0D01*
G01X712500D01*
X713250D01*
G03X713702Y1172890I0J452D01*
G01Y1173957D01*
X713708Y1173983D01*
G03X713752Y1174310I-1208J329D01*
G03X713441Y1175136I-1252J0D01*
G01X713402Y1175180D01*
X713385Y1175297D01*
X713559Y1175682D01*
G02X713741Y1175800I182J-82D01*
G01X716704D01*
G02X716844Y1175743I0J-200D01*
G01X716845Y1175742D01*
X717428Y1175159D01*
G02X717430Y1175157I-140J-142D01*
G02X717487Y1175017I-143J-140D01*
G01Y1172836D01*
G02X717420Y1172687I-200J0D01*
G01X717165Y1172459D01*
X717085Y1172434D01*
X717042Y1172439D01*
G03X716991Y1172442I-52J-449D01*
G01X716286D01*
X715490D01*
G03X715038Y1171990I0J-452D01*
G01Y1170923D01*
X715032Y1170897D01*
G03X714988Y1170570I1208J-329D01*
G03X716240Y1169318I1252J0D01*
G01Y1169317D01*
G03X716883Y1169495I-1J1253D01*
G01X716929Y1169522D01*
X717036Y1169524D01*
X717385Y1169326D01*
G02X717406Y1169313I-94J-176D01*
G02X717487Y1169157I-119J-161D01*
G01Y1160768D01*
Y1160763D01*
G02X717406Y1160607I-200J5D01*
G02X717385Y1160594I-115J163D01*
G01X717083Y1160423D01*
G02X716882Y1160425I-99J174D01*
G03X716240Y1160602I-642J-1076D01*
G03X714988Y1159350I0J-1252D01*
G03X715032Y1159023I1252J2D01*
G01X715038Y1158997D01*
Y1158464D01*
Y1157930D01*
G03X715489Y1157478I452J0D01*
G01X716991D01*
G03X717042Y1157481I-1J452D01*
G01X717085Y1157486D01*
X717165Y1157461D01*
X717420Y1157233D01*
G02X717487Y1157084I-133J-149D01*
G01Y1155683D01*
G02X717428Y1155541I-200J0D01*
G01X716648Y1154761D01*
G02X716506Y1154702I-142J141D01*
G01X714071D01*
G02X713910Y1154784I0J200D01*
G01X713691Y1155085D01*
X713676Y1155178D01*
X713691Y1155225D01*
G03X713752Y1155610I-1191J386D01*
G03X713708Y1155937I-1252J-2D01*
G01X713702Y1155963D01*
Y1156496D01*
Y1157030D01*
G03X713251Y1157482I-452J0D01*
G01X712500D01*
X711750D01*
G03X711298Y1157030I0J-452D01*
G01Y1155963D01*
X711292Y1155937D01*
G03X711248Y1155610I1208J-329D01*
G03X711309Y1155225I1252J1D01*
G01X711324Y1155178D01*
X711309Y1155085D01*
X711090Y1154784D01*
G02X710929Y1154702I-161J118D01*
G01X706591D01*
G02X706430Y1154784I0J200D01*
G01X706211Y1155085D01*
X706196Y1155178D01*
X706211Y1155225D01*
G03X706272Y1155612I-1191J386D01*
G01Y1155619D01*
G03X706228Y1155938I-1252J-10D01*
G01X706222Y1155963D01*
Y1157030D01*
G03X705995Y1157421I-452J-1D01*
G03X705769Y1157482I-227J-391D01*
G01X704269D01*
G03X703817Y1157030I0J-452D01*
G01Y1155958D01*
X703810Y1155933D01*
G03X703768Y1155610I1210J-322D01*
G03X703829Y1155225I1252J1D01*
G01X703844Y1155178D01*
X703829Y1155085D01*
X703610Y1154784D01*
G02X703449Y1154702I-161J118D01*
G01X699110D01*
G02X698949Y1154784I0J200D01*
G01X698730Y1155085D01*
X698715Y1155178D01*
X698730Y1155225D01*
G03X698791Y1155610I-1191J386D01*
G03X698748Y1155936I-1252J1D01*
G01X698741Y1155961D01*
Y1157030D01*
G03X698289Y1157482I-452J0D01*
G01X696789D01*
G03X696337Y1157030I0J-452D01*
G01Y1155961D01*
X696330Y1155936D01*
G03X696287Y1155610I1209J-325D01*
G03X696348Y1155225I1252J1D01*
G01X696363Y1155178D01*
X696348Y1155085D01*
X696129Y1154784D01*
G02X695968Y1154702I-161J118D01*
G01X687890D01*
G02X687729Y1154784I0J200D01*
G01X687510Y1155085D01*
X687495Y1155178D01*
X687510Y1155225D01*
G03X687571Y1155610I-1191J386D01*
G03X687528Y1155936I-1252J1D01*
G01X687521Y1155961D01*
Y1157030D01*
G03X687069Y1157482I-452J0D01*
G01X685569D01*
G03X685117Y1157030I0J-452D01*
G01Y1155961D01*
X685110Y1155936D01*
G03X685067Y1155610I1209J-325D01*
G03X685128Y1155225I1252J1D01*
G01X685143Y1155178D01*
X685128Y1155085D01*
X684909Y1154784D01*
G02X684748Y1154702I-161J118D01*
G01X680409D01*
G02X680248Y1154784I0J200D01*
G01X680029Y1155085D01*
X680014Y1155178D01*
X680029Y1155225D01*
G03X680090Y1155610I-1191J386D01*
G03X680048Y1155933I-1252J1D01*
G01X680041Y1155958D01*
Y1157030D01*
G03X679589Y1157482I-452J0D01*
G01X678089D01*
G03X677863Y1157421I1J-452D01*
G03X677636Y1157030I225J-392D01*
G01Y1155963D01*
X677630Y1155938D01*
G03X677586Y1155616I1208J-329D01*
G01Y1155598D01*
G03X677647Y1155225I1252J13D01*
G01X677662Y1155178D01*
X677647Y1155085D01*
X677428Y1154784D01*
G02X677267Y1154702I-161J118D01*
G01X672929D01*
G02X672768Y1154784I0J200D01*
G01X672549Y1155085D01*
X672534Y1155178D01*
X672549Y1155225D01*
G03X672610Y1155610I-1191J386D01*
G03X672566Y1155937I-1252J-2D01*
G01X672560Y1155963D01*
Y1156496D01*
Y1157030D01*
G03X672109Y1157482I-452J0D01*
G01X671358D01*
X670608D01*
G03X670156Y1157030I0J-452D01*
G01Y1155963D01*
X670150Y1155937D01*
G03X670106Y1155610I1208J-329D01*
G03X670167Y1155225I1252J1D01*
G01X670182Y1155178D01*
X670167Y1155085D01*
X669948Y1154784D01*
G02X669787Y1154702I-161J118D01*
G01X665449D01*
G02X665288Y1154784I0J200D01*
G01X665069Y1155085D01*
X665054Y1155178D01*
X665069Y1155225D01*
G03X665130Y1155610I-1191J386D01*
G03X665086Y1155937I-1252J-2D01*
G01X665080Y1155963D01*
Y1156496D01*
Y1157030D01*
G03X664629Y1157482I-452J0D01*
G01X663878D01*
X663128D01*
G03X662676Y1157030I0J-452D01*
G01Y1155963D01*
X662670Y1155937D01*
G03X662626Y1155610I1208J-329D01*
G03X662687Y1155225I1252J1D01*
G01X662702Y1155178D01*
X662687Y1155085D01*
X662468Y1154784D01*
G02X662307Y1154702I-161J118D01*
G01X657969D01*
G02X657808Y1154784I0J200D01*
G01X657589Y1155085D01*
X657574Y1155178D01*
X657589Y1155225D01*
G03X657650Y1155610I-1191J386D01*
G03X657606Y1155937I-1252J-2D01*
G01X657600Y1155963D01*
Y1156496D01*
Y1157030D01*
G03X657149Y1157482I-452J0D01*
G01X656398D01*
X655648D01*
G03X655196Y1157030I0J-452D01*
G01Y1155963D01*
X655190Y1155937D01*
G03X655146Y1155610I1208J-329D01*
G03X655324Y1154967I1252J0D01*
G02X655293Y1154723I-172J-102D01*
G01X653544Y1152974D01*
G02X653300Y1152943I-142J141D01*
G03X652657Y1153121I-643J-1074D01*
G03X652330Y1153077I2J-1252D01*
G01X652304Y1153070D01*
X651216D01*
G03X650785Y1152620I21J-451D01*
G01Y1151869D01*
X650786D01*
Y1151119D01*
G03X651237Y1150668I451J0D01*
G01X652304D01*
X652330Y1150661D01*
G03X652657Y1150617I329J1208D01*
G03X653057Y1150683I-1J1252D01*
G02X653151Y1150691I63J-190D01*
G01X653199Y1150684D01*
X653366Y1150564D01*
G02X653449Y1150402I-117J-162D01*
G01Y1145856D01*
G02X653366Y1145694I-200J0D01*
G01X653239Y1145602D01*
G02X653151Y1145567I-116J163D01*
G01X653101Y1145560D01*
G03X652657Y1145641I-443J-1171D01*
G03X652330Y1145597I2J-1252D01*
G01X652304Y1145590D01*
X651216D01*
G03X650785Y1145140I21J-451D01*
G01Y1144389D01*
X650786D01*
Y1143639D01*
G03X651237Y1143188I451J0D01*
G01X652304D01*
X652330Y1143181D01*
G03X652657Y1143137I329J1208D01*
G03X653285Y1143306I0J1251D01*
G01X653308Y1143319D01*
X653358Y1143333D01*
X653385D01*
G02X653585Y1143133I0J-200D01*
G01Y1142985D01*
X653587Y1142984D01*
Y1142683D01*
G02X653528Y1142541I-200J0D01*
G01X652916Y1141929D01*
X652831Y1141899D01*
X652786Y1141904D01*
G03X652657Y1141910I-123J-1255D01*
G03X652506Y1141901I-1J-1261D01*
G01X652494Y1141900D01*
X649080D01*
X649068Y1141901D01*
G03X648917Y1141910I-150J-1252D01*
G03X648766Y1141901I-1J-1261D01*
G01X648754Y1141900D01*
X646870D01*
G02X646728Y1141959I0J200D01*
G01X646546Y1142141D01*
X646517Y1142169D01*
X646487Y1142243D01*
Y1185817D01*
G02X646544Y1185957I200J0D01*
G01X646545Y1185958D01*
X646826Y1186239D01*
G02X646968Y1186298I142J-141D01*
G37*
G36*
G01X724510Y1188272D02*
X724166Y1187928D01*
X724138Y1187899D01*
X724064Y1187869D01*
X652150D01*
G02X652008Y1187928I0J200D01*
G01X651911Y1188025D01*
G02X651853Y1188166I142J141D01*
G01Y1189887D01*
G02X651912Y1190029I200J0D01*
G01X651914Y1190031D01*
G02X652056Y1190090I142J-141D01*
G01X653780D01*
X653785Y1190084D01*
X724078D01*
G02X724219Y1190026I0J-200D01*
G01X724510Y1189735D01*
G02X724569Y1189593I-141J-142D01*
G01Y1188414D01*
G02X724510Y1188272I-200J0D01*
G37*
G36*
G01X650806Y1187523D02*
G02X650793Y1187508I-157J123D01*
G01X650643Y1187358D01*
G02X650576Y1187314I-141J142D01*
G01X650542Y1187300D01*
X646144D01*
G02X646018Y1187345I0J200D01*
G02X646003Y1187358I123J157D01*
G01X645578Y1187783D01*
G02X645534Y1187850I142J141D01*
G01X645520Y1187884D01*
Y1191610D01*
G02X645555Y1191723I200J0D01*
G01Y1191724D01*
G02X645647Y1191796I164J-115D01*
G01X645648Y1191797D01*
G03X645680Y1191810I-474J1213D01*
G01X645777D01*
G03X646224Y1192198I0J451D01*
G02X646256Y1192282I198J-27D01*
G03X646479Y1193011I-1080J729D01*
G03X646256Y1193739I-1301J0D01*
G02X646224Y1193823I166J111D01*
G03X646217Y1193860I-447J-65D01*
G02X646256Y1194029I195J44D01*
G01X646452Y1194273D01*
G02X646608Y1194348I156J-125D01*
G01X651355D01*
G02X651555Y1194148I0J-200D01*
G01Y1193630D01*
X651545Y1193586D01*
X651534Y1193565D01*
G03X651405Y1193011I1123J-554D01*
G03X651534Y1192457I1252J0D01*
G01X651545Y1192436D01*
X651555Y1192392D01*
Y1192338D01*
G02X651496Y1192196I-200J0D01*
G01X650910Y1191610D01*
G03X650851Y1191468I141J-142D01*
G01Y1187649D01*
G02X650806Y1187523I-200J0D01*
G37*
G36*
G01X727858Y1202947D02*
G02X727667Y1202689I-191J-58D01*
G01X727484D01*
X727367Y1202806D01*
Y1202824D01*
X658157D01*
X651929D01*
X651843Y1202910D01*
Y1204954D01*
X652230Y1205341D01*
X658106D01*
X659159D01*
X686313D01*
G03X686455Y1205400I0J200D01*
G01X688563Y1207508D01*
G02X688705Y1207567I142J-141D01*
G01X691505D01*
G02X691647Y1207508I0J-200D01*
G01X693696Y1205459D01*
G03X693838Y1205400I142J141D01*
G01X727879D01*
G02X728021Y1205341I0J-200D01*
G01X728390Y1204972D01*
G02X728449Y1204830I-141J-142D01*
G01Y1204805D01*
G02X728376Y1204650I-200J0D01*
G03X727789Y1203412I1015J-1239D01*
G03X727858Y1202947I1602J0D01*
G37*
G36*
G01X652202Y1197625D02*
X652794D01*
G02X652936Y1197566I0J-200D01*
G01X653066Y1197435D01*
G03X653208Y1197376I142J141D01*
G01X724337D01*
G02X724537Y1197176I0J-200D01*
G01Y1196502D01*
G02X724478Y1196360I-200J0D01*
G01X723526Y1195408D01*
X723498Y1195379D01*
X723424Y1195349D01*
X646825D01*
G02X646683Y1195408I0J200D01*
G01X646547Y1195544D01*
Y1197370D01*
X646743Y1197566D01*
X652060D01*
G02X652202Y1197625I142J-141D01*
G37*
G36*
G01X649019Y1348187D02*
G03I-491J0D01*
G37*
G36*
G01Y1360099D02*
G03I-491J0D01*
G37*
G36*
G01Y1372385D02*
G03I-491J0D01*
G37*
G36*
G01X644659D02*
G03I-491J0D01*
G37*
G36*
G01Y1384297D02*
G03I-491J0D01*
G37*
G36*
G01X649019D02*
G03I-491J0D01*
G37*
G36*
G01Y1396583D02*
G03I-491J0D01*
G37*
G36*
G01X644659D02*
G03I-491J0D01*
G37*
G36*
G01Y1408495D02*
G03I-491J0D01*
G37*
G36*
G01X649019D02*
G03I-491J0D01*
G37*
G36*
G01X645168Y1461182D02*
G03I-491J0D01*
G37*
G36*
G01Y1456451D02*
G03I-491J0D01*
G37*
G36*
G01Y1471805D02*
G03I-491J0D01*
G37*
G36*
G01Y1481267D02*
G03I-491J0D01*
G37*
G36*
G01Y1465913D02*
G03I-491J0D01*
G37*
G36*
G01Y1476536D02*
G03I-491J0D01*
G37*
G36*
G01Y1491891D02*
G03I-491J0D01*
G37*
G36*
G01Y1487160D02*
G03I-491J0D01*
G37*
G36*
G01Y1496622D02*
G03I-491J0D01*
G37*
G36*
G01Y1502514D02*
G03I-491J0D01*
G37*
G36*
G01Y1507245D02*
G03I-491J0D01*
G37*
G36*
G01Y1511976D02*
G03I-491J0D01*
G37*
G36*
G01Y1558813D02*
G03I-491J0D01*
G37*
G36*
G01Y1578898D02*
G03I-491J0D01*
G37*
G36*
G01Y1574167D02*
G03I-491J0D01*
G37*
G36*
G01Y1568275D02*
G03I-491J0D01*
G37*
G36*
G01Y1563544D02*
G03I-491J0D01*
G37*
G36*
G01Y1594253D02*
G03I-491J0D01*
G37*
G36*
G01Y1589522D02*
G03I-491J0D01*
G37*
G36*
G01Y1583629D02*
G03I-491J0D01*
G37*
G36*
G01Y1604876D02*
G03I-491J0D01*
G37*
G36*
G01Y1609607D02*
G03I-491J0D01*
G37*
G36*
G01Y1598984D02*
G03I-491J0D01*
G37*
G36*
G01Y1614338D02*
G03I-491J0D01*
G37*
G36*
G01X655820Y1134697D02*
X724354D01*
G02X724496Y1134638I0J-200D01*
G01X724778Y1134356D01*
G02X724837Y1134214I-141J-142D01*
G01Y1132980D01*
G02X724778Y1132838I-200J0D01*
G01X724397Y1132457D01*
G02X724256Y1132398I-142J141D01*
G01X655918D01*
G02X655777Y1132457I1J200D01*
G01X655496Y1132738D01*
G02X655437Y1132880I141J142D01*
G01Y1134314D01*
G02X655496Y1134456I200J0D01*
G01X655678Y1134638D01*
G02X655820Y1134697I142J-141D01*
G37*
G36*
G01X655567Y1141927D02*
X655577Y1141937D01*
G02X655718Y1141996I142J-141D01*
G01X724656D01*
G02X724797Y1141937I-1J-200D01*
G01X724807Y1141927D01*
X724837Y1141854D01*
Y1139998D01*
G02X724637Y1139798I-200J0D01*
G01X656018D01*
G02X655877Y1139857I1J200D01*
G01X655596Y1140138D01*
G02X655537Y1140280I141J142D01*
G01Y1141854D01*
X655567Y1141927D01*
G37*
G36*
G01X726821Y1127129D02*
X734686D01*
G02X734828Y1127070I0J-200D01*
G01X735778Y1126120D01*
G02X735837Y1125978I-141J-142D01*
G01Y1125091D01*
G02X735778Y1124949I-200J0D01*
G01X735749Y1124920D01*
G02X735608Y1124862I-141J142D01*
G01X707546D01*
G03X706712Y1124547I0J-1262D01*
G02X706580Y1124497I-132J150D01*
G01X703100D01*
G02X702958Y1124556I0J200D01*
G01X702922Y1124592D01*
G03X702030Y1124962I-893J-892D01*
G01X693400D01*
G03X692508Y1124592I1J-1262D01*
G01X691308Y1123392D01*
G03X690938Y1122500I892J-893D01*
G01Y1122492D01*
G02X690738Y1122292I-200J0D01*
G01X688447D01*
G02X688305Y1122351I0J200D01*
G01X686218Y1124438D01*
G03X686076Y1124497I-142J-141D01*
G01X654054D01*
G02X653912Y1124556I0J200D01*
G01X653768Y1124700D01*
G02X653719Y1124900I142J141D01*
G01X653737Y1124960D01*
X653752Y1124983D01*
G03X653959Y1125690I-1095J704D01*
G01Y1125715D01*
G03X653567Y1126619I-1302J-27D01*
G01X653538Y1126648D01*
X653507Y1126721D01*
Y1126806D01*
G02X653707Y1127006I200J0D01*
G01X726531D01*
G03X726668Y1127061I-1J200D01*
G01X726673Y1127066D01*
X726693Y1127083D01*
G02X726821Y1127129I128J-154D01*
G37*
G36*
G01X726304Y1130030D02*
X726293Y1130007D01*
G03X726158Y1129429I1167J-577D01*
G03X726293Y1128851I1302J-1D01*
G01X726304Y1128828D01*
X726314Y1128786D01*
Y1128206D01*
G02X726274Y1128086I-200J0D01*
G02X726255Y1128064I-160J119D01*
G01X726229Y1128038D01*
X726193Y1128023D01*
G02X726117Y1128008I-76J185D01*
G01X653908D01*
G02X653788Y1128048I0J200D01*
G02X653766Y1128067I119J160D01*
G01X653750Y1128083D01*
Y1128665D01*
G02X653757Y1128718I200J1D01*
G01X653764Y1128742D01*
X653778Y1128766D01*
G03X653959Y1129428I-1121J662D01*
G01Y1129429D01*
G03X653914Y1129767I-1302J-1D01*
G02X653909Y1129793I194J51D01*
G01X653904Y1129832D01*
G02X653922Y1129916I200J1D01*
G01X653958Y1129995D01*
G02X653997Y1130052I182J-83D01*
G01X654068Y1130124D01*
X654083Y1130132D01*
G03X654413Y1130368I-544J1110D01*
G01X655057Y1131012D01*
G03X655268Y1131293I-873J875D01*
G01X655269Y1131294D01*
G02X655342Y1131370I176J-96D01*
G01X655365Y1131383D01*
X655415Y1131397D01*
X655887D01*
G03X655917Y1131396I55J1200D01*
G01X686180D01*
X686191Y1131395D01*
X686195Y1131394D01*
G03X686417Y1131375I222J1283D01*
G03X686639Y1131394I0J1302D01*
G01X686643Y1131395D01*
X686654Y1131396D01*
X724257D01*
G03X724287Y1131397I-25J1201D01*
G01X725625D01*
G02X725716Y1131375I0J-200D01*
G02X725766Y1131339I-90J-178D01*
G01X726256Y1130849D01*
G02X726292Y1130799I-142J-140D01*
G02X726314Y1130708I-178J-91D01*
G01Y1130072D01*
X726304Y1130030D01*
G37*
G36*
G01X655820Y1138797D02*
X724554D01*
G02X724696Y1138738I0J-200D01*
G01X724978Y1138456D01*
G02X725037Y1138314I-141J-142D01*
G01Y1135980D01*
G02X724978Y1135838I-200J0D01*
G01X724897Y1135757D01*
G02X724756Y1135698I-142J141D01*
G01X655537D01*
G02X655337Y1135898I0J200D01*
G01Y1138314D01*
G02X655396Y1138456I200J0D01*
G01X655678Y1138738D01*
G02X655820Y1138797I142J-141D01*
G37*
G36*
G01X719170Y1172100D02*
X728644D01*
X728718Y1172070D01*
X728746Y1172041D01*
X728928Y1171859D01*
G02X728987Y1171717I-141J-142D01*
G01Y1158483D01*
G03X729046Y1158341I200J0D01*
G01X729978Y1157409D01*
G02X730037Y1157267I-141J-142D01*
G01Y1156072D01*
X730025Y1156039D01*
G03X729949Y1155610I1176J-430D01*
G03X730025Y1155181I1252J1D01*
G01X730037Y1155148D01*
Y1152331D01*
X730025Y1152298D01*
G03X729949Y1151869I1176J-430D01*
G03X730025Y1151440I1252J1D01*
G01X730037Y1151407D01*
Y1148591D01*
X730025Y1148558D01*
G03X729949Y1148129I1176J-430D01*
G03X730025Y1147700I1252J1D01*
G01X730037Y1147667D01*
Y1144851D01*
X730025Y1144818D01*
G03X729949Y1144389I1176J-430D01*
G03X730025Y1143960I1252J1D01*
G01X730037Y1143927D01*
Y1142833D01*
G02X729978Y1142691I-200J0D01*
G01X729746Y1142459D01*
X729718Y1142430D01*
X729644Y1142400D01*
X725830D01*
G02X725717Y1142435I0J200D01*
G01X725667Y1142469D01*
X725657Y1142493D01*
X725607Y1142544D01*
X725606D01*
X725506Y1142645D01*
G03X725260Y1142834I-849J-850D01*
G03X725095Y1142914I-605J-1038D01*
G02X725036Y1142950I73J186D01*
G03X724904Y1143000I-132J-150D01*
G01X655030D01*
X654956Y1143030D01*
X654928Y1143059D01*
X654646Y1143341D01*
G02X654587Y1143483I141J142D01*
G01Y1152557D01*
X654617Y1152631D01*
X654646Y1152659D01*
X655628Y1153641D01*
G02X655770Y1153700I142J-141D01*
G01X718104D01*
G03X718246Y1153759I0J200D01*
G01X718829Y1154342D01*
G03X718870Y1154403I-143J140D01*
G01X718884Y1154433D01*
X718907Y1154460D01*
G02X718968Y1154505I147J-136D01*
G01X719150Y1154594D01*
X719255Y1154588D01*
X719299Y1154559D01*
G03X719980Y1154358I680J1051D01*
G01X720006D01*
G03X721232Y1155610I-26J1252D01*
G03X721195Y1155912I-1251J0D01*
G01X721189Y1155936D01*
Y1157030D01*
G03X720737Y1157482I-452J0D01*
G01X719237D01*
G03X719220Y1157481I18J-451D01*
G01X719216D01*
X719201D01*
X719163Y1157478D01*
X719094Y1157500D01*
X718963Y1157604D01*
G02X718887Y1157761I124J157D01*
G01Y1165330D01*
G02X718979Y1165499I200J1D01*
G01X719307Y1165708D01*
X719408Y1165715D01*
X719455Y1165693D01*
G03X719979Y1165578I524J1137D01*
G01X719980D01*
G03X720305Y1165621I0J1252D01*
G01X720331Y1165628D01*
X720866D01*
X721400D01*
G03X721852Y1166080I0J452D01*
G01Y1166830D01*
Y1167580D01*
G03X721401Y1168032I-452J0D01*
G01X720332D01*
X720306Y1168039D01*
G03X719781Y1168066I-325J-1209D01*
G03X719455Y1167967I197J-1236D01*
G01X719408Y1167945D01*
X719307Y1167952D01*
X718979Y1168161D01*
G02X718887Y1168330I108J168D01*
G01Y1171857D01*
X718917Y1171931D01*
X718946Y1171959D01*
X719028Y1172041D01*
G02X719170Y1172100I142J-141D01*
G37*
G36*
G01X724551Y1186897D02*
X725154D01*
G02X725294Y1186840I0J-200D01*
G01X725295Y1186839D01*
X726135Y1185999D01*
G02X726140Y1185994I-139J-144D01*
G01X726174Y1185958D01*
X726200Y1185862D01*
X726189Y1185814D01*
G03X726158Y1185532I1271J-282D01*
G01Y1185531D01*
G03X726833Y1184390I1302J0D01*
G01X726882Y1184363D01*
X726937Y1184270D01*
Y1183052D01*
X726882Y1182959D01*
X726833Y1182932D01*
G03Y1180650I627J-1141D01*
G01X726882Y1180623D01*
X726937Y1180530D01*
Y1179348D01*
G02X726819Y1179165I-200J-1D01*
G01X726715Y1179119D01*
G03X726158Y1178051I745J-1068D01*
G01Y1178049D01*
G03X726204Y1177707I1302J1D01*
G01Y1177706D01*
G02X726205Y1177604I-193J-53D01*
G02X726153Y1177513I-194J50D01*
G01X726071Y1177431D01*
G02X726007Y1177388I-141J141D01*
G01X725969Y1177372D01*
X723939D01*
G03X723543Y1177176I2J-502D01*
G01X723542Y1177175D01*
X723541Y1177174D01*
G02X723472Y1177118I-157J123D01*
G02X723383Y1177097I-89J179D01*
G01X654580D01*
X654506Y1177127D01*
X654478Y1177156D01*
X653958Y1177676D01*
X653929Y1177769D01*
X653938Y1177818D01*
G03X653959Y1178051I-1282J233D01*
G01Y1178052D01*
G03X653699Y1178832I-1302J-1D01*
G01X653698Y1178833D01*
X653680Y1178858D01*
X653649Y1178946D01*
G02X653637Y1179013I188J68D01*
G01Y1180829D01*
G02X653649Y1180896I200J-1D01*
G01X653680Y1180984D01*
X653698Y1181009D01*
X653699Y1181010D01*
G03X653959Y1181790I-1042J781D01*
G01Y1181792D01*
G03X653699Y1182572I-1302J-1D01*
G01X653698Y1182573D01*
X653680Y1182598D01*
X653649Y1182686D01*
G02X653637Y1182753I188J68D01*
G01Y1184569D01*
G02X653649Y1184636I200J-1D01*
G01X653680Y1184724D01*
X653698Y1184749D01*
X653699Y1184750D01*
G03X653959Y1185530I-1042J781D01*
G01Y1185532D01*
G03X653680Y1186337I-1302J0D01*
G01X653659Y1186364D01*
X653637Y1186427D01*
Y1186668D01*
G02X653837Y1186868I200J0D01*
G01X724522D01*
X724551Y1186897D01*
G37*
G36*
G01X726335Y1199440D02*
X726306Y1199412D01*
X725331Y1198437D01*
X725303Y1198408D01*
X725229Y1198378D01*
X653624D01*
G02X653482Y1198437I0J200D01*
G01X653334Y1198585D01*
G02X653314Y1198608I141J142D01*
G02X653275Y1198727I161J119D01*
G01Y1199231D01*
G02X653366Y1199399I200J0D01*
G03X653959Y1200491I-709J1092D01*
G03X653746Y1201203I-1302J-2D01*
G01X653731Y1201226D01*
X653715Y1201278D01*
X653714Y1201306D01*
G02X653738Y1201408I200J7D01*
G01X653905Y1201718D01*
G02X654081Y1201823I176J-95D01*
G01X726165D01*
G02X726365Y1201623I0J-200D01*
G01Y1201226D01*
X726351Y1201175D01*
X726337Y1201152D01*
G03X726158Y1200492I1123J-659D01*
G01Y1200490D01*
G03X726337Y1199830I1302J-1D01*
G01X726351Y1199807D01*
X726365Y1199756D01*
Y1199514D01*
X726335Y1199440D01*
G37*
G36*
G01X724115Y1194497D02*
X724254D01*
G02X724394Y1194440I0J-200D01*
G01X724395Y1194439D01*
X725278Y1193556D01*
G02X725280Y1193554I-140J-142D01*
G02X725337Y1193414I-143J-140D01*
G01Y1191340D01*
X725307Y1191266D01*
X725278Y1191238D01*
X725185Y1191145D01*
G02X725043Y1191086I-142J141D01*
G01X654254D01*
X654249Y1191092D01*
X654236D01*
G02X654141Y1191145I46J194D01*
G01X653696Y1191590D01*
G02X653637Y1191732I141J142D01*
G01Y1191988D01*
X653648Y1192034D01*
X653659Y1192055D01*
G03X653704Y1192198I-402J205D01*
G02X653736Y1192282I198J-27D01*
G03X653959Y1193010I-1079J729D01*
G01Y1193012D01*
G03X653736Y1193740I-1302J-1D01*
G02X653704Y1193824I166J111D01*
G03X653659Y1193967I-447J-62D01*
G01X653648Y1193988D01*
X653637Y1194034D01*
Y1194114D01*
G02X653694Y1194254I200J0D01*
G01X653695Y1194255D01*
X653729Y1194289D01*
G02X653870Y1194348I142J-141D01*
G01X723800D01*
G03X723940Y1194406I-1J200D01*
G01X723975Y1194440D01*
G02X724115Y1194497I140J-143D01*
G37*
G36*
G01X669139Y1348187D02*
G03I-491J0D01*
G37*
G36*
G01X661259D02*
G03I-491J0D01*
G37*
G36*
G01X656899D02*
G03I-491J0D01*
G37*
G36*
G01Y1360099D02*
G03I-491J0D01*
G37*
G36*
G01X669139D02*
G03I-491J0D01*
G37*
G36*
G01X661259D02*
G03I-491J0D01*
G37*
G36*
G01X669139Y1372385D02*
G03I-491J0D01*
G37*
G36*
G01X661259D02*
G03I-491J0D01*
G37*
G36*
G01X656899D02*
G03I-491J0D01*
G37*
G36*
G01Y1384297D02*
G03I-491J0D01*
G37*
G36*
G01X669139D02*
G03I-491J0D01*
G37*
G36*
G01X661259D02*
G03I-491J0D01*
G37*
G36*
G01X669139Y1396583D02*
G03I-491J0D01*
G37*
G36*
G01X661259D02*
G03I-491J0D01*
G37*
G36*
G01X656899D02*
G03I-491J0D01*
G37*
G36*
G01Y1408495D02*
G03I-491J0D01*
G37*
G36*
G01X669139D02*
G03I-491J0D01*
G37*
G36*
G01X661259D02*
G03I-491J0D01*
G37*
G36*
G01X662491Y1461182D02*
G03I-491J0D01*
G37*
G36*
G01Y1456451D02*
G03I-491J0D01*
G37*
G36*
G01X653829Y1460782D02*
G03I-491J0D01*
G37*
G36*
G01X662491Y1481267D02*
G03I-491J0D01*
G37*
G36*
G01Y1476536D02*
G03I-491J0D01*
G37*
G36*
G01Y1471805D02*
G03I-491J0D01*
G37*
G36*
G01Y1465913D02*
G03I-491J0D01*
G37*
G36*
G01X653829Y1480867D02*
G03I-491J0D01*
G37*
G36*
G01Y1470244D02*
G03I-491J0D01*
G37*
G36*
G01Y1476136D02*
G03I-491J0D01*
G37*
G36*
G01Y1465513D02*
G03I-491J0D01*
G37*
G36*
G01Y1496222D02*
G03I-491J0D01*
G37*
G36*
G01Y1485598D02*
G03I-491J0D01*
G37*
G36*
G01Y1491491D02*
G03I-491J0D01*
G37*
G36*
G01X662491Y1496622D02*
G03I-491J0D01*
G37*
G36*
G01Y1491891D02*
G03I-491J0D01*
G37*
G36*
G01Y1487160D02*
G03I-491J0D01*
G37*
G36*
G01X653829Y1500953D02*
G03I-491J0D01*
G37*
G36*
G01Y1506845D02*
G03I-491J0D01*
G37*
G36*
G01Y1511576D02*
G03I-491J0D01*
G37*
G36*
G01X662491Y1511976D02*
G03I-491J0D01*
G37*
G36*
G01Y1502514D02*
G03I-491J0D01*
G37*
G36*
G01Y1507245D02*
G03I-491J0D01*
G37*
G36*
G01X653829Y1516307D02*
G03I-491J0D01*
G37*
G36*
G01X662491Y1558813D02*
G03I-491J0D01*
G37*
G36*
G01Y1578898D02*
G03I-491J0D01*
G37*
G36*
G01X653829Y1572606D02*
G03I-491J0D01*
G37*
G36*
G01Y1578498D02*
G03I-491J0D01*
G37*
G36*
G01Y1567875D02*
G03I-491J0D01*
G37*
G36*
G01Y1563144D02*
G03I-491J0D01*
G37*
G36*
G01X662491Y1574167D02*
G03I-491J0D01*
G37*
G36*
G01Y1568275D02*
G03I-491J0D01*
G37*
G36*
G01Y1563544D02*
G03I-491J0D01*
G37*
G36*
G01Y1583629D02*
G03I-491J0D01*
G37*
G36*
G01X653829Y1587960D02*
G03I-491J0D01*
G37*
G36*
G01Y1593853D02*
G03I-491J0D01*
G37*
G36*
G01Y1583229D02*
G03I-491J0D01*
G37*
G36*
G01X662491Y1594253D02*
G03I-491J0D01*
G37*
G36*
G01Y1589522D02*
G03I-491J0D01*
G37*
G36*
G01Y1598984D02*
G03I-491J0D01*
G37*
G36*
G01Y1604876D02*
G03I-491J0D01*
G37*
G36*
G01Y1609607D02*
G03I-491J0D01*
G37*
G36*
G01X653829Y1609207D02*
G03I-491J0D01*
G37*
G36*
G01Y1603315D02*
G03I-491J0D01*
G37*
G36*
G01Y1598584D02*
G03I-491J0D01*
G37*
G36*
G01Y1618669D02*
G03I-491J0D01*
G37*
G36*
G01Y1613938D02*
G03I-491J0D01*
G37*
G36*
G01X662491Y1614338D02*
G03I-491J0D01*
G37*
G36*
G01X686228Y203641D02*
X697436D01*
X698408Y202669D01*
Y195995D01*
X696854Y194441D01*
X685709D01*
X684997Y195153D01*
Y202410D01*
X686228Y203641D01*
G37*
G36*
G01X685739Y1348187D02*
G03I-491J0D01*
G37*
G36*
G01X681379D02*
G03I-491J0D01*
G37*
G36*
G01X673499D02*
G03I-491J0D01*
G37*
G36*
G01X681379Y1360099D02*
G03I-491J0D01*
G37*
G36*
G01X673499D02*
G03I-491J0D01*
G37*
G36*
G01X685739D02*
G03I-491J0D01*
G37*
G36*
G01Y1372385D02*
G03I-491J0D01*
G37*
G36*
G01X681379D02*
G03I-491J0D01*
G37*
G36*
G01X673499D02*
G03I-491J0D01*
G37*
G36*
G01X681379Y1384297D02*
G03I-491J0D01*
G37*
G36*
G01X673499D02*
G03I-491J0D01*
G37*
G36*
G01X685739D02*
G03I-491J0D01*
G37*
G36*
G01Y1396583D02*
G03I-491J0D01*
G37*
G36*
G01X681379D02*
G03I-491J0D01*
G37*
G36*
G01X673499D02*
G03I-491J0D01*
G37*
G36*
G01X681379Y1408495D02*
G03I-491J0D01*
G37*
G36*
G01X673499D02*
G03I-491J0D01*
G37*
G36*
G01X685739D02*
G03I-491J0D01*
G37*
G36*
G01X679813Y1461182D02*
G03I-491J0D01*
G37*
G36*
G01Y1456451D02*
G03I-491J0D01*
G37*
G36*
G01X671152Y1460782D02*
G03I-491J0D01*
G37*
G36*
G01Y1465513D02*
G03I-491J0D01*
G37*
G36*
G01X679813Y1481267D02*
G03I-491J0D01*
G37*
G36*
G01Y1476536D02*
G03I-491J0D01*
G37*
G36*
G01Y1471805D02*
G03I-491J0D01*
G37*
G36*
G01X671152Y1480867D02*
G03I-491J0D01*
G37*
G36*
G01Y1470244D02*
G03I-491J0D01*
G37*
G36*
G01Y1476136D02*
G03I-491J0D01*
G37*
G36*
G01X679813Y1465913D02*
G03I-491J0D01*
G37*
G36*
G01X671152Y1485598D02*
G03I-491J0D01*
G37*
G36*
G01Y1491491D02*
G03I-491J0D01*
G37*
G36*
G01X679813Y1496622D02*
G03I-491J0D01*
G37*
G36*
G01Y1491891D02*
G03I-491J0D01*
G37*
G36*
G01Y1487160D02*
G03I-491J0D01*
G37*
G36*
G01X671152Y1496222D02*
G03I-491J0D01*
G37*
G36*
G01Y1500953D02*
G03I-491J0D01*
G37*
G36*
G01Y1506845D02*
G03I-491J0D01*
G37*
G36*
G01X679813Y1511976D02*
G03I-491J0D01*
G37*
G36*
G01Y1502514D02*
G03I-491J0D01*
G37*
G36*
G01Y1507245D02*
G03I-491J0D01*
G37*
G36*
G01X671152Y1511576D02*
G03I-491J0D01*
G37*
G36*
G01Y1516307D02*
G03I-491J0D01*
G37*
G36*
G01X679813Y1558813D02*
G03I-491J0D01*
G37*
G36*
G01Y1578898D02*
G03I-491J0D01*
G37*
G36*
G01X671152Y1563144D02*
G03I-491J0D01*
G37*
G36*
G01X679813Y1574167D02*
G03I-491J0D01*
G37*
G36*
G01Y1568275D02*
G03I-491J0D01*
G37*
G36*
G01X671152Y1572606D02*
G03I-491J0D01*
G37*
G36*
G01Y1578498D02*
G03I-491J0D01*
G37*
G36*
G01Y1567875D02*
G03I-491J0D01*
G37*
G36*
G01X679813Y1563544D02*
G03I-491J0D01*
G37*
G36*
G01X671152Y1587960D02*
G03I-491J0D01*
G37*
G36*
G01Y1593853D02*
G03I-491J0D01*
G37*
G36*
G01Y1583229D02*
G03I-491J0D01*
G37*
G36*
G01X679813Y1594253D02*
G03I-491J0D01*
G37*
G36*
G01Y1589522D02*
G03I-491J0D01*
G37*
G36*
G01Y1583629D02*
G03I-491J0D01*
G37*
G36*
G01Y1609607D02*
G03I-491J0D01*
G37*
G36*
G01X671152Y1603315D02*
G03I-491J0D01*
G37*
G36*
G01Y1598584D02*
G03I-491J0D01*
G37*
G36*
G01Y1609207D02*
G03I-491J0D01*
G37*
G36*
G01X679813Y1598984D02*
G03I-491J0D01*
G37*
G36*
G01Y1604876D02*
G03I-491J0D01*
G37*
G36*
G01Y1614338D02*
G03I-491J0D01*
G37*
G36*
G01X671152Y1618669D02*
G03I-491J0D01*
G37*
G36*
G01Y1613938D02*
G03I-491J0D01*
G37*
G36*
G01X697979Y1348187D02*
G03I-491J0D01*
G37*
G36*
G01X693619D02*
G03I-491J0D01*
G37*
G36*
G01Y1360099D02*
G03I-491J0D01*
G37*
G36*
G01X697979D02*
G03I-491J0D01*
G37*
G36*
G01Y1372385D02*
G03I-491J0D01*
G37*
G36*
G01X693619D02*
G03I-491J0D01*
G37*
G36*
G01Y1384297D02*
G03I-491J0D01*
G37*
G36*
G01X697979D02*
G03I-491J0D01*
G37*
G36*
G01Y1396583D02*
G03I-491J0D01*
G37*
G36*
G01X693619D02*
G03I-491J0D01*
G37*
G36*
G01Y1408495D02*
G03I-491J0D01*
G37*
G36*
G01X697979D02*
G03I-491J0D01*
G37*
G36*
G01X697136Y1461183D02*
G03I-491J0D01*
G37*
G36*
G01Y1456452D02*
G03I-491J0D01*
G37*
G36*
G01X688475Y1460782D02*
G03I-491J0D01*
G37*
G36*
G01X697136Y1471806D02*
G03I-491J0D01*
G37*
G36*
G01Y1476537D02*
G03I-491J0D01*
G37*
G36*
G01X688475Y1480867D02*
G03I-491J0D01*
G37*
G36*
G01Y1470244D02*
G03I-491J0D01*
G37*
G36*
G01Y1476136D02*
G03I-491J0D01*
G37*
G36*
G01Y1465513D02*
G03I-491J0D01*
G37*
G36*
G01X697136Y1465914D02*
G03I-491J0D01*
G37*
G36*
G01Y1481268D02*
G03I-491J0D01*
G37*
G36*
G01Y1491891D02*
G03I-491J0D01*
G37*
G36*
G01X688475Y1496222D02*
G03I-491J0D01*
G37*
G36*
G01Y1485598D02*
G03I-491J0D01*
G37*
G36*
G01Y1491491D02*
G03I-491J0D01*
G37*
G36*
G01X697136Y1496622D02*
G03I-491J0D01*
G37*
G36*
G01Y1487160D02*
G03I-491J0D01*
G37*
G36*
G01Y1511977D02*
G03I-491J0D01*
G37*
G36*
G01Y1502515D02*
G03I-491J0D01*
G37*
G36*
G01Y1507246D02*
G03I-491J0D01*
G37*
G36*
G01X688475Y1511576D02*
G03I-491J0D01*
G37*
G36*
G01Y1500953D02*
G03I-491J0D01*
G37*
G36*
G01Y1506845D02*
G03I-491J0D01*
G37*
G36*
G01Y1516307D02*
G03I-491J0D01*
G37*
G36*
G01X697136Y1558813D02*
G03I-491J0D01*
G37*
G36*
G01X688475Y1563144D02*
G03I-491J0D01*
G37*
G36*
G01X697136Y1574167D02*
G03I-491J0D01*
G37*
G36*
G01X688475Y1572606D02*
G03I-491J0D01*
G37*
G36*
G01Y1578498D02*
G03I-491J0D01*
G37*
G36*
G01X697136Y1578898D02*
G03I-491J0D01*
G37*
G36*
G01Y1568275D02*
G03I-491J0D01*
G37*
G36*
G01X688475Y1567875D02*
G03I-491J0D01*
G37*
G36*
G01X697136Y1563544D02*
G03I-491J0D01*
G37*
G36*
G01Y1589522D02*
G03I-491J0D01*
G37*
G36*
G01Y1594253D02*
G03I-491J0D01*
G37*
G36*
G01X688475Y1587960D02*
G03I-491J0D01*
G37*
G36*
G01Y1593853D02*
G03I-491J0D01*
G37*
G36*
G01X697136Y1583629D02*
G03I-491J0D01*
G37*
G36*
G01X688475Y1583229D02*
G03I-491J0D01*
G37*
G36*
G01X697136Y1604876D02*
G03I-491J0D01*
G37*
G36*
G01Y1598984D02*
G03I-491J0D01*
G37*
G36*
G01Y1609607D02*
G03I-491J0D01*
G37*
G36*
G01X688475Y1603315D02*
G03I-491J0D01*
G37*
G36*
G01Y1598584D02*
G03I-491J0D01*
G37*
G36*
G01Y1609207D02*
G03I-491J0D01*
G37*
G36*
G01X697136Y1614338D02*
G03I-491J0D01*
G37*
G36*
G01X688475Y1618669D02*
G03I-491J0D01*
G37*
G36*
G01Y1613938D02*
G03I-491J0D01*
G37*
G36*
G01X703828Y174710D02*
X750303D01*
G02X750443Y174653I0J-200D01*
G01X750444Y174652D01*
X752646Y172450D01*
G02X752648Y172448I-140J-142D01*
G02X752705Y172308I-143J-140D01*
G01Y143109D01*
X752624Y143003D01*
X752558Y142985D01*
G03Y139509I477J-1738D01*
G01X752624Y139491D01*
X752705Y139385D01*
Y104934D01*
G02X752687Y104852I-200J1D01*
G01X752639Y104743D01*
X752609Y104716D01*
G03X752136Y103621I1031J-1095D01*
G03X752296Y102946I1502J0D01*
G01X752317Y102904D01*
X752319Y102814D01*
X752168Y102487D01*
G02X752034Y102377I-182J85D01*
G01X752033D01*
G03X750654Y100625I423J-1752D01*
G03X752333Y98827I1802J0D01*
G01X752371Y98824D01*
X752439Y98792D01*
X752651Y98565D01*
G02X752661Y98553I-148J-134D01*
G02X752705Y98428I-156J-125D01*
G01Y77986D01*
G02X752585Y77803I-200J0D01*
G01X752195Y77632D01*
X752078Y77652D01*
X752034Y77692D01*
G03X751017Y78089I-1017J-1104D01*
G03X749768Y77421I0J-1502D01*
G01X749744Y77386D01*
X749675Y77341D01*
X749344Y77288D01*
G02X749190Y77327I-32J197D01*
G03X748269Y77642I-920J-1187D01*
G01X748239D01*
G03X746767Y76140I30J-1502D01*
G03X748269Y74638I1502J0D01*
G03X749518Y75306I0J1502D01*
G01X749542Y75341D01*
X749611Y75386D01*
X749983Y75446D01*
X750063Y75426D01*
X750096Y75400D01*
G03X750712Y75116I921J1187D01*
G01X750766Y75105D01*
X750847Y75031D01*
X750964Y74640D01*
G02X750914Y74442I-192J-57D01*
G01X750497Y74025D01*
X750458Y74009D01*
G03X749623Y73174I559J-1394D01*
G01X749607Y73135D01*
X749478Y73006D01*
X749450Y72977D01*
X749376Y72947D01*
X703263D01*
G02X703121Y73006I0J200D01*
G01X701805Y74322D01*
X701776Y74350D01*
X701746Y74424D01*
Y172628D01*
G02X701803Y172768I200J0D01*
G01X701804Y172769D01*
X703686Y174651D01*
G02X703688Y174653I142J-140D01*
G02X703828Y174710I140J-143D01*
G37*
G36*
G01X718099Y1348187D02*
G03I-491J0D01*
G37*
G36*
G01X710219D02*
G03I-491J0D01*
G37*
G36*
G01X705859D02*
G03I-491J0D01*
G37*
G36*
G01Y1360099D02*
G03I-491J0D01*
G37*
G36*
G01X718099D02*
G03I-491J0D01*
G37*
G36*
G01X710219D02*
G03I-491J0D01*
G37*
G36*
G01X718099Y1372385D02*
G03I-491J0D01*
G37*
G36*
G01X710219D02*
G03I-491J0D01*
G37*
G36*
G01X705859D02*
G03I-491J0D01*
G37*
G36*
G01Y1384297D02*
G03I-491J0D01*
G37*
G36*
G01X718099D02*
G03I-491J0D01*
G37*
G36*
G01X710219D02*
G03I-491J0D01*
G37*
G36*
G01X718099Y1396583D02*
G03I-491J0D01*
G37*
G36*
G01X710219D02*
G03I-491J0D01*
G37*
G36*
G01X705859D02*
G03I-491J0D01*
G37*
G36*
G01Y1408495D02*
G03I-491J0D01*
G37*
G36*
G01X718099D02*
G03I-491J0D01*
G37*
G36*
G01X710219D02*
G03I-491J0D01*
G37*
G36*
G01X720963Y940310D02*
G03I-590J0D01*
G37*
G36*
G01X725137Y958287D02*
G03I-590J0D01*
G37*
G36*
G01X735997Y1136005D02*
X737625D01*
G02X737698Y1135991I0J-200D01*
G01X737797Y1135952D01*
X737823Y1135929D01*
G03X738564Y1135612I858J980D01*
G01X738600Y1135609D01*
X738663Y1135579D01*
X739955Y1134287D01*
G03X739998Y1134254I142J141D01*
G01X740014Y1134239D01*
G03X741047Y1133810I1034J1032D01*
G01X743540D01*
G02X743681Y1133752I0J-200D01*
G01X744445Y1132988D01*
G02X744504Y1132846I-141J-142D01*
G01Y1126997D01*
G02X744304Y1126797I-200J0D01*
G01X736602D01*
G02X736460Y1126856I0J200D01*
G01X735989Y1127327D01*
X735987D01*
X735559Y1127755D01*
X735529Y1127840D01*
X735534Y1127885D01*
X735570Y1128238D01*
X735617Y1128315D01*
X735655Y1128340D01*
G03X736243Y1129429I-714J1089D01*
G03X733639I-1302J0D01*
G03X733835Y1128742I1302J0D01*
G01X733836Y1128741D01*
G02X733840Y1128539I-171J-104D01*
G01X733670Y1128233D01*
G02X733495Y1128130I-175J97D01*
G01X728798D01*
G02X728612Y1128330I15J200D01*
G01Y1128775D01*
G02X728631Y1128861I200J1D01*
G01X728632Y1128862D01*
Y1128863D01*
G03Y1129995I-1171J566D01*
G01Y1129996D01*
X728631Y1129997D01*
G02X728612Y1130083I181J85D01*
G01Y1132515D01*
G02X728631Y1132601I200J1D01*
G01X728632Y1132602D01*
Y1132603D01*
G03Y1133735I-1171J566D01*
G01Y1133736D01*
X728631Y1133737D01*
G02X728612Y1133823I181J85D01*
G01Y1135292D01*
G02X728669Y1135432I200J0D01*
G01X728670Y1135433D01*
X729183Y1135946D01*
G02X729185Y1135948I142J-140D01*
G02X729325Y1136005I140J-143D01*
G01X730145D01*
G02X730218Y1135991I0J-200D01*
G01X730317Y1135952D01*
X730343Y1135930D01*
G03X731669Y1135694I858J979D01*
G01X731704Y1135708D01*
X732621D01*
G03X732887Y1135794I1J451D01*
G02X733005Y1135833I119J-161D01*
G01X733137D01*
G02X733255Y1135794I-1J-200D01*
G03X733521Y1135708I265J365D01*
G01X734438D01*
X734473Y1135694D01*
G03X735799Y1135930I468J1215D01*
G01X735825Y1135952D01*
X735924Y1135991D01*
G02X735997Y1136005I73J-186D01*
G37*
G36*
G01X734941Y1176749D02*
G03X735631Y1176948I-2J1302D01*
G01X735655Y1176963D01*
X735709Y1176978D01*
X736056D01*
G02X736256Y1176778I0J-200D01*
G01Y1176703D01*
X736254Y1176700D01*
Y1153007D01*
G02X736195Y1152866I-200J1D01*
G01X736168Y1152839D01*
G02X736026Y1152780I-142J141D01*
G01X735953D01*
G02X735880Y1152794I0J200D01*
G01X735846Y1152807D01*
X735818Y1152832D01*
G03X734064I-877J-961D01*
G02X733929Y1152780I-135J148D01*
G01X733358D01*
G02X733216Y1152839I0J200D01*
G01X732704Y1153351D01*
X732675Y1153379D01*
X732645Y1153453D01*
Y1176443D01*
G02X732704Y1176585I200J0D01*
G01X733038Y1176919D01*
G02X733180Y1176978I142J-141D01*
G01X734145D01*
G02X734167Y1176977I2J-200D01*
G02X734216Y1176965I-23J-199D01*
G02X734251Y1176947I-73J-186D01*
G03X734941Y1176749I690J1104D01*
G37*
G36*
G01X734699Y1348187D02*
G03I-491J0D01*
G37*
G36*
G01X730339D02*
G03I-491J0D01*
G37*
G36*
G01X722459D02*
G03I-491J0D01*
G37*
G36*
G01X730339Y1360099D02*
G03I-491J0D01*
G37*
G36*
G01X722459D02*
G03I-491J0D01*
G37*
G36*
G01X734699D02*
G03I-491J0D01*
G37*
G36*
G01Y1372385D02*
G03I-491J0D01*
G37*
G36*
G01X730339D02*
G03I-491J0D01*
G37*
G36*
G01X722459D02*
G03I-491J0D01*
G37*
G36*
G01X730339Y1384297D02*
G03I-491J0D01*
G37*
G36*
G01X722459D02*
G03I-491J0D01*
G37*
G36*
G01X734699D02*
G03I-491J0D01*
G37*
G36*
G01Y1396489D02*
G03I-491J0D01*
G37*
G36*
G01X730339D02*
G03I-491J0D01*
G37*
G36*
G01X722459D02*
G03I-491J0D01*
G37*
G36*
G01X730339Y1408401D02*
G03I-491J0D01*
G37*
G36*
G01X722459D02*
G03I-491J0D01*
G37*
G36*
G01X734699D02*
G03I-491J0D01*
G37*
G36*
G01X737827Y1635533D02*
X776152D01*
G02X776294Y1635474I0J-200D01*
G01X780399Y1631369D01*
G02X780458Y1631227I-141J-142D01*
G01Y1618723D01*
G02X780399Y1618581I-200J0D01*
G01X776440Y1614622D01*
G03X776381Y1614480I141J-142D01*
G01Y1610781D01*
G02X776269Y1610601I-200J0D01*
G03Y1607363I789J-1619D01*
G02X776381Y1607183I-88J-180D01*
G01Y1602378D01*
G02X776259Y1602194I-200J0D01*
G01X775864Y1602027D01*
X775746Y1602049D01*
X775703Y1602091D01*
G03X774658Y1602514I-1045J-1079D01*
G03Y1599510I0J-1502D01*
G03X775703Y1599933I0J1502D01*
G01X775746Y1599975D01*
X775864Y1599997D01*
X776259Y1599830D01*
G02X776381Y1599646I-78J-184D01*
G01Y1596688D01*
G02X776281Y1596515I-200J0D01*
G03Y1593915I752J-1300D01*
G02X776381Y1593742I-100J-173D01*
G01Y1593201D01*
G02X776322Y1593059I-200J0D01*
G01X773108Y1589845D01*
G02X772966Y1589786I-142J141D01*
G01X765744D01*
G02X765603Y1589845I1J200D01*
G01X765403Y1590045D01*
G02X765344Y1590186I141J142D01*
G03X761740I-1802J0D01*
G02X761681Y1590045I-200J1D01*
G01X761481Y1589845D01*
G02X761340Y1589786I-142J141D01*
G01X761322D01*
X761230Y1589840D01*
X761144Y1589992D01*
G02X761140Y1590181I174J98D01*
G03X761304Y1590864I-1338J682D01*
G03X758300I-1502J0D01*
G03X758399Y1590329I1502J1D01*
G01X758417Y1590282D01*
X758405Y1590185D01*
X758190Y1589873D01*
G02X758025Y1589786I-165J113D01*
G01X751963D01*
G02X751811Y1589856I0J200D01*
G01X751585Y1590119D01*
X751561Y1590203D01*
X751568Y1590246D01*
G03X751588Y1590517I-1782J268D01*
G03X747984I-1802J0D01*
G03X748004Y1590246I1802J-3D01*
G01X748011Y1590203D01*
X747987Y1590119D01*
X747761Y1589856D01*
G02X747609Y1589786I-152J130D01*
G01X730065D01*
G02X729923Y1589845I0J200D01*
G01X727203Y1592565D01*
G02X727144Y1592707I141J142D01*
G01Y1619813D01*
G02X727203Y1619955I200J0D01*
G01X731637Y1624389D01*
G03X731696Y1624531I-141J142D01*
G01Y1629402D01*
G02X731755Y1629544I200J0D01*
G01X737685Y1635474D01*
G02X737827Y1635533I142J-141D01*
G37*
G36*
G01X799468Y54588D02*
X827614D01*
X827756Y54446D01*
Y52733D01*
X827614Y52591D01*
X799468D01*
G03X793531Y46654I0J-5937D01*
G01Y7874D01*
G02X787657Y2000I-5874J0D01*
G01X740413D01*
G02X734539Y7874I0J5874D01*
G01Y46261D01*
X736536D01*
Y7874D01*
G03X740411Y3998I3876J0D01*
G01X787657D01*
G03X791534Y7874I0J3877D01*
G01Y46654D01*
G02X799468Y54588I7934J0D01*
G37*
G36*
G01X745724Y429263D02*
X741929D01*
X740488D01*
X739249D01*
X738390Y430122D01*
Y456169D01*
X738899Y456678D01*
X744323D01*
X744750Y456251D01*
Y445974D01*
X745724Y445000D01*
Y429263D01*
G37*
G36*
G01X761024Y444496D02*
X770561D01*
G02X770703Y444437I0J-200D01*
G01X776215Y438925D01*
G03X776357Y438866I142J141D01*
G01X843744D01*
G02X843886Y438807I0J-200D01*
G01X845359Y437334D01*
G02X845418Y437192I-141J-142D01*
G01Y422212D01*
G02X845359Y422070I-200J0D01*
G01X844476Y421187D01*
G02X844334Y421128I-142J141D01*
G01X787762D01*
G02X787620Y421187I0J200D01*
G01X785786Y423020D01*
X762326D01*
X756042Y429304D01*
X746926D01*
G02X746726Y429504I0J200D01*
G01Y444296D01*
G02X746926Y444496I200J0D01*
G01X754245D01*
G02X754373Y444449I-1J-200D01*
G03X756813I1220J1458D01*
G02X756941Y444496I129J-153D01*
G01X758062D01*
G02X758203Y444438I0J-200D01*
G03X759543Y443886I1339J1349D01*
G03X760883Y444438I1J1901D01*
G02X761024Y444496I141J-142D01*
G37*
G36*
G01X799235Y512656D02*
X856979D01*
G02X857119Y512599I0J-200D01*
G01X857120Y512598D01*
X865230Y504488D01*
G02X865232Y504486I-140J-142D01*
G02X865289Y504346I-143J-140D01*
G01Y468605D01*
G02X865230Y468463I-200J0D01*
G01X865054Y468287D01*
G02X865017Y468258I-141J142D01*
G01X865016Y468257D01*
G02X864825Y468248I-104J171D01*
G01X864428Y468441D01*
X864367Y468552D01*
X864374Y468616D01*
G03X864384Y468791I-1492J173D01*
G03X862882Y470293I-1502J0D01*
G03X861380Y468829I0J-1502D01*
G01Y468802D01*
Y468791D01*
G03X861837Y467712I1502J0D01*
G01X861865Y467684D01*
X861913Y467577D01*
G02X861930Y467496I-183J-81D01*
G01Y467286D01*
G02X861913Y467205I-200J0D01*
G01X861865Y467098D01*
X861837Y467070D01*
G03X861380Y465991I1045J-1079D01*
G01Y465953D01*
G03X861656Y465124I1502J39D01*
G02X861634Y464867I-163J-115D01*
G01X861022Y464255D01*
G02X860880Y464196I-142J141D01*
G01X856174D01*
G02X855988Y464323I0J200D01*
G01X855829Y464726D01*
X855858Y464848D01*
X855904Y464889D01*
G03X856385Y465991I-1022J1102D01*
G01Y466010D01*
X856383Y466053D01*
G03X855927Y467070I-1501J-62D01*
G01X855899Y467098D01*
X855851Y467205D01*
G02X855834Y467286I183J81D01*
G01Y467496D01*
G02X855851Y467577I200J0D01*
G01X855899Y467684D01*
X855927Y467712D01*
G03X856384Y468791I-1045J1079D01*
G01Y468829D01*
G03X853380I-1502J-38D01*
G01Y468802D01*
Y468791D01*
G03X853837Y467712I1502J0D01*
G01X853865Y467684D01*
X853913Y467577D01*
G02X853930Y467496I-183J-81D01*
G01Y467286D01*
G02X853913Y467205I-200J0D01*
G01X853865Y467098D01*
X853837Y467070D01*
G03X853384Y466110I1045J-1080D01*
G01X853379Y466044D01*
Y465993D01*
G03X853860Y464889I1503J-2D01*
G01X853906Y464848D01*
X853935Y464726D01*
X853776Y464323D01*
G02X853590Y464196I-186J73D01*
G01X853553D01*
X853516Y464180D01*
G03X853453Y464138I77J-184D01*
G01X853179Y463865D01*
G02X853038Y463807I-141J142D01*
G01X849891D01*
G03X849749Y463748I0J-200D01*
G01X846847Y460846D01*
X846819Y460817D01*
X846745Y460787D01*
X844708D01*
G02X844561Y460852I1J200D01*
G01X844333Y461100D01*
X844306Y461180D01*
X844310Y461222D01*
G03X844317Y461379I-1795J159D01*
G01Y461382D01*
G03X840713I-1802J0D01*
G01Y461379D01*
G03X840720Y461222I1802J2D01*
G01X840724Y461180D01*
X840697Y461100D01*
X840469Y460852D01*
G02X840321Y460787I-148J135D01*
G01X833332D01*
G03X833253Y460771I-1J-200D01*
G01X833221Y460757D01*
X827763D01*
G02X827583Y460869I0J200D01*
G01X827425Y461191D01*
G02X827447Y461403I179J89D01*
G03X827764Y462326I-1185J923D01*
G03X824760I-1502J0D01*
G03X825077Y461403I1502J0D01*
G01X825112Y461358D01*
X825125Y461243D01*
X824941Y460869D01*
G02X824761Y460757I-180J88D01*
G01X819823D01*
X819804Y460739D01*
X811648D01*
G03X811506Y460680I0J-200D01*
G01X804570Y453744D01*
X804542Y453715D01*
X804468Y453685D01*
X802795D01*
X802756Y453703D01*
G03X801937Y453823I-619J-1369D01*
G03X801518Y453703I200J-1489D01*
G01X801478Y453685D01*
X766465D01*
G03X766323Y453626I0J-200D01*
G01X763652Y450955D01*
X763624Y450926D01*
X763550Y450896D01*
X754159D01*
G03X754017Y450837I0J-200D01*
G01X753283Y450103D01*
X753255Y450074D01*
X753181Y450044D01*
X746450D01*
G02X746308Y450103I0J200D01*
G01X746186Y450225D01*
X746157Y450253D01*
X746127Y450327D01*
Y457210D01*
G02X746184Y457350I200J0D01*
G01X746185Y457351D01*
X746980Y458146D01*
G02X746982Y458148I142J-140D01*
G02X747122Y458205I140J-143D01*
G01X747748D01*
G02X747942Y458052I0J-200D01*
G03X750802Y457861I1460J354D01*
G01X750816Y457898D01*
X750870Y457955D01*
X751198Y458102D01*
X751276Y458105D01*
X751313Y458091D01*
G03X752097Y457952I784J2141D01*
G03X753098Y458184I2J2266D01*
G02X753186Y458205I89J-179D01*
G01X754369D01*
G03X754511Y458264I0J200D01*
G01X755340Y459093D01*
X755400Y459122D01*
X755435Y459126D01*
G03X756782Y459775I-255J2252D01*
G01X758957Y461950D01*
G03X759606Y463297I-1603J1602D01*
G01X759610Y463332D01*
X759639Y463392D01*
X760664Y464417D01*
G02X760666Y464419I142J-140D01*
G02X760806Y464476I140J-143D01*
G01X787926D01*
G03X788068Y464535I0J200D01*
G01X797958Y474425D01*
G03X798017Y474567I-141J142D01*
G01Y511438D01*
G02X798074Y511578I200J0D01*
G01X798075Y511579D01*
X799093Y512597D01*
G02X799095Y512599I142J-140D01*
G02X799235Y512656I140J-143D01*
G37*
G36*
G01X738010Y1124859D02*
X744174D01*
G02X744316Y1124800I0J-200D01*
G01X744805Y1124311D01*
G02X744864Y1124169I-141J-142D01*
G01Y1122074D01*
G02X744863Y1122058I-200J4D01*
G03X744859Y1121949I1298J-102D01*
G01Y1121947D01*
G03X744863Y1121838I1302J-7D01*
G02X744864Y1121822I-199J-20D01*
G01Y1118334D01*
G02X744863Y1118318I-200J4D01*
G03X744859Y1118209I1298J-102D01*
G01Y1118207D01*
G03X744863Y1118098I1302J-7D01*
G02X744864Y1118082I-199J-20D01*
G01Y1117749D01*
Y1116740D01*
X744221Y1116097D01*
X739570D01*
X737999D01*
G02X737799Y1116297I0J200D01*
G01Y1122420D01*
Y1124648D01*
X738010Y1124859D01*
G37*
G36*
G01X745469Y1178766D02*
X746809D01*
G02X746951Y1178707I0J-200D01*
G01X747004Y1178654D01*
G02X747050Y1178582I-142J-141D01*
G03X747097Y1178474I480J145D01*
G01X747110Y1178451D01*
X747124Y1178401D01*
Y1177793D01*
X747100Y1177727D01*
X747077Y1177700D01*
G03X746629Y1176475I1454J-1226D01*
G01Y1175680D01*
G03X747077Y1174455I1902J1D01*
G02X747124Y1174326I-153J-129D01*
G01Y1151404D01*
G02X747065Y1151262I-200J0D01*
G01X746911Y1151108D01*
X746883Y1151079D01*
X746809Y1151049D01*
X745872D01*
G02X745730Y1151108I0J200D01*
G01X745588Y1151250D01*
X745587Y1151251D01*
G03X745543Y1151295I-1296J-1252D01*
G01X745542Y1151296D01*
X744820Y1152018D01*
G02X744761Y1152160I141J142D01*
G01Y1178058D01*
G02X744820Y1178200I200J0D01*
G01X745327Y1178707D01*
G02X745469Y1178766I142J-141D01*
G37*
G36*
G01X737257Y1176400D02*
Y1177728D01*
G02X737316Y1177870I200J0D01*
G01X738084Y1178638D01*
G02X738226Y1178697I142J-141D01*
G01X739127D01*
G02X739269Y1178638I0J-200D01*
G01X739403Y1178504D01*
G02X739462Y1178362I-141J-142D01*
G01Y1151610D01*
G02X739403Y1151468I-200J0D01*
G01X738993Y1151058D01*
X738965Y1151029D01*
X738891Y1150999D01*
X737919D01*
G02X737777Y1151058I0J200D01*
G01X737314Y1151521D01*
X737285Y1151549D01*
X737255Y1151623D01*
Y1176397D01*
X737257Y1176400D01*
G37*
G36*
G01X740929Y1175589D02*
X743594D01*
G02X743736Y1175530I0J-200D01*
G01X743760Y1175506D01*
Y1154255D01*
G02X743701Y1154114I-200J1D01*
G01X743680Y1154093D01*
G02X743538Y1154034I-142J141D01*
G01X740841D01*
G02X740699Y1154093I0J200D01*
G01X740620Y1154172D01*
G02X740561Y1154314I141J142D01*
G01Y1175221D01*
G02X740620Y1175363I200J0D01*
G01X740787Y1175530D01*
G02X740929Y1175589I142J-141D01*
G37*
G36*
G01X749019Y1167578D02*
X749214Y1167773D01*
G02X749356Y1167832I142J-141D01*
G01X754256D01*
G02X754398Y1167773I0J-200D01*
G01X754624Y1167547D01*
G02X754683Y1167405I-141J-142D01*
G01Y1158972D01*
G02X754624Y1158830I-200J0D01*
G01X754241Y1158447D01*
G02X754099Y1158388I-142J141D01*
G01X749449D01*
G02X749307Y1158447I0J200D01*
G01X749019Y1158735D01*
G02X748960Y1158877I141J142D01*
G01Y1167436D01*
G02X749019Y1167578I200J0D01*
G37*
G36*
G01X746939Y1348187D02*
G03I-491J0D01*
G37*
G36*
G01X742579D02*
G03I-491J0D01*
G37*
G36*
G01Y1360099D02*
G03I-491J0D01*
G37*
G36*
G01X746939D02*
G03I-491J0D01*
G37*
G36*
G01Y1372385D02*
G03I-491J0D01*
G37*
G36*
G01X742579D02*
G03I-491J0D01*
G37*
G36*
G01Y1384297D02*
G03I-491J0D01*
G37*
G36*
G01X746939D02*
G03I-491J0D01*
G37*
G36*
G01X742579Y1396489D02*
G03I-491J0D01*
G37*
G36*
G01Y1408401D02*
G03I-491J0D01*
G37*
G36*
G01X758944Y1167906D02*
X765851D01*
G02X765991Y1167849I0J-200D01*
G01X765992Y1167848D01*
X766344Y1167496D01*
G02X766346Y1167494I-140J-142D01*
G02X766403Y1167354I-143J-140D01*
G01Y1160613D01*
G02X766284Y1160430I-200J0D01*
G01X765895Y1160257D01*
X765779Y1160276D01*
X765735Y1160316D01*
G03X764862Y1160652I-873J-966D01*
G03X763560Y1159350I0J-1302D01*
G03X763617Y1158967I1302J-2D01*
G01X763632Y1158922D01*
X763616Y1158828D01*
X763396Y1158531D01*
G02X763235Y1158450I-161J119D01*
G01X759009D01*
G02X758848Y1158531I0J200D01*
G01X758629Y1158827D01*
X758613Y1158920D01*
X758627Y1158966D01*
G03X758684Y1159350I-1245J381D01*
G03X757382Y1160652I-1302J0D01*
G01X757381D01*
G03X756390Y1160193I1J-1302D01*
G01X756389D01*
G02X756167Y1160134I-153J129D01*
G01X755816Y1160264D01*
G02X755685Y1160452I69J188D01*
G01Y1165728D01*
G02X755816Y1165916I200J0D01*
G01X756167Y1166046D01*
G02X756389Y1165987I69J-188D01*
G01X756390D01*
G03X757382Y1165528I992J842D01*
G01X757421D01*
Y1165529D01*
G03X758684Y1166830I-39J1301D01*
G01X758685D01*
G03X758578Y1167347I-1303J0D01*
G01X758577D01*
G02X758594Y1167537I184J79D01*
G01X758777Y1167816D01*
G02X758944Y1167906I167J-110D01*
G37*
G36*
G01X767059Y1348187D02*
G03I-491J0D01*
G37*
G36*
G01X759179D02*
G03I-491J0D01*
G37*
G36*
G01X754819D02*
G03I-491J0D01*
G37*
G36*
G01Y1360099D02*
G03I-491J0D01*
G37*
G36*
G01X767059D02*
G03I-491J0D01*
G37*
G36*
G01X759179D02*
G03I-491J0D01*
G37*
G36*
G01X767059Y1372385D02*
G03I-491J0D01*
G37*
G36*
G01X759179D02*
G03I-491J0D01*
G37*
G36*
G01X754819D02*
G03I-491J0D01*
G37*
G36*
G01Y1384297D02*
G03I-491J0D01*
G37*
G36*
G01X767059D02*
G03I-491J0D01*
G37*
G36*
G01X759179D02*
G03I-491J0D01*
G37*
G36*
G01X790157Y1490945D02*
G03I-19685J0D01*
G37*
G36*
G01X767469Y1167234D02*
X767914Y1167679D01*
G02X768056Y1167738I142J-141D01*
G01X773018D01*
G02X773160Y1167679I0J-200D01*
G01X773355Y1167484D01*
G02X773414Y1167342I-141J-142D01*
G01Y1158940D01*
G02X773355Y1158798I-200J0D01*
G01X773098Y1158541D01*
G02X772956Y1158482I-142J141D01*
G01X768150D01*
G02X768008Y1158541I0J200D01*
G01X767469Y1159080D01*
G02X767410Y1159222I141J142D01*
G01Y1167092D01*
G02X767469Y1167234I200J0D01*
G37*
G36*
G01X779299Y1348187D02*
G03I-491J0D01*
G37*
G36*
G01X771419D02*
G03I-491J0D01*
G37*
G36*
G01X779299Y1360099D02*
G03I-491J0D01*
G37*
G36*
G01X771419D02*
G03I-491J0D01*
G37*
G36*
G01X793728Y140296D02*
G03I-507J0D01*
G37*
G36*
G01X788590Y203641D02*
X799798D01*
X800770Y202669D01*
Y195995D01*
X799216Y194441D01*
X788071D01*
X787359Y195153D01*
Y202410D01*
X788590Y203641D01*
G37*
G36*
G01X827738Y1066535D02*
G02I-17700J0D01*
G37*
G36*
G01Y1263386D02*
G02I-17700J0D01*
G37*
G36*
G01X795284Y1411307D02*
G03I-778J0D01*
G37*
G36*
G01X793898Y1457120D02*
X795968D01*
G02X796110Y1457061I0J-200D01*
G01X796377Y1456794D01*
G02X796436Y1456652I-141J-142D01*
G01Y1454280D01*
G03X796495Y1454138I200J0D01*
G01X798553Y1452080D01*
X798564D01*
X798566Y1452078D01*
X798639Y1452048D01*
X803124D01*
G02X803265Y1451989I-1J-200D01*
G01X803322Y1451932D01*
G02X803381Y1451790I-141J-142D01*
G01Y1450328D01*
G03X803440Y1450186I200J0D01*
G01X804247Y1449379D01*
G02X804306Y1449237I-141J-142D01*
G01Y1445912D01*
G02X804247Y1445770I-200J0D01*
G01X803929Y1445452D01*
G02X803787Y1445393I-142J141D01*
G01X794472D01*
G02X794330Y1445452I0J200D01*
G01X793556Y1446226D01*
G02X793497Y1446368I141J142D01*
G01Y1449030D01*
X793586Y1449139D01*
X793656Y1449154D01*
G03Y1452682I-368J1764D01*
G01X793586Y1452697D01*
X793497Y1452806D01*
Y1456719D01*
G02X793556Y1456861I200J0D01*
G01X793756Y1457061D01*
G02X793898Y1457120I142J-141D01*
G37*
G36*
G01X803159Y1459523D02*
X803454D01*
G02X803596Y1459464I0J-200D01*
G01X804478Y1458582D01*
G02X804537Y1458440I-141J-142D01*
G01Y1454106D01*
G02X804478Y1453964I-200J0D01*
G01X803622Y1453108D01*
G02X803480Y1453049I-142J141D01*
G01X799094D01*
G02X798952Y1453108I0J200D01*
G01X797596Y1454464D01*
G02X797537Y1454606I141J142D01*
G01Y1458940D01*
G02X797596Y1459082I200J0D01*
G01X797978Y1459464D01*
G02X798120Y1459523I142J-141D01*
G01X798529D01*
X798552Y1459518D01*
G03X798757Y1459494I205J866D01*
G01X799810D01*
Y1459523D01*
X801878D01*
Y1459494D01*
X802931D01*
G03X803136Y1459518I0J890D01*
G01X803159Y1459523D01*
G37*
G36*
G01X846753Y174205D02*
X850305D01*
G02X850445Y174148I0J-200D01*
G01X850446Y174147D01*
X852648Y171945D01*
G02X852650Y171943I-140J-142D01*
G02X852707Y171803I-143J-140D01*
G01Y138227D01*
X852634Y138124D01*
X852574Y138103D01*
G03X851873Y137587I502J-1416D01*
G01X851852Y137559D01*
X851765Y137501D01*
G02X851698Y137473I-109J168D01*
G01X851579Y137446D01*
X851505Y137457D01*
X851472Y137475D01*
G03X851171Y137612I-894J-1565D01*
G03X850580Y137712I-592J-1703D01*
G03X849989Y137612I1J-1803D01*
G03X849688Y137475I593J-1702D01*
G01X849655Y137457D01*
X849581Y137446D01*
X849462Y137473D01*
G02X849395Y137501I42J196D01*
G01X849307Y137560D01*
X849287Y137588D01*
G03X848084Y138189I-1202J-901D01*
G01X848041D01*
X848040Y138188D01*
G03X846582Y136687I44J-1501D01*
G03X848084Y135185I1502J0D01*
G03X848316Y135203I0J1502D01*
G01X848359Y135210D01*
X848443Y135186D01*
X848707Y134961D01*
G02X848778Y134808I-129J-153D01*
G01Y133610D01*
G02X848707Y133457I-200J0D01*
G01X848443Y133232D01*
X848359Y133208D01*
X848316Y133215D01*
G03X848081Y133233I-232J-1484D01*
G01X848080D01*
G03X846582Y131731I4J-1502D01*
G03X848084Y130229I1502J0D01*
G01X848085D01*
G03X849287Y130830I0J1502D01*
G01X849307Y130858D01*
X849395Y130917D01*
G02X849462Y130945I109J-168D01*
G01X849581Y130972D01*
X849655Y130961D01*
X849688Y130943D01*
G03X849989Y130806I894J1565D01*
G03X850580Y130706I592J1703D01*
G03X851171Y130806I-1J1803D01*
G03X851472Y130943I-593J1702D01*
G01X851505Y130961D01*
X851579Y130972D01*
X851698Y130945D01*
G02X851765Y130917I-42J-196D01*
G01X851852Y130859D01*
X851873Y130831D01*
G03X852574Y130315I1203J900D01*
G01X852634Y130294D01*
X852707Y130191D01*
Y124053D01*
X852634Y123950D01*
X852574Y123929D01*
G03X851873Y123413I502J-1416D01*
G01X851852Y123385D01*
X851765Y123327D01*
G02X851698Y123299I-109J168D01*
G01X851579Y123272D01*
X851505Y123283D01*
X851472Y123301D01*
G03X851171Y123438I-894J-1565D01*
G03X850580Y123538I-592J-1703D01*
G03X849989Y123438I1J-1803D01*
G03X849688Y123301I593J-1702D01*
G01X849655Y123283D01*
X849581Y123272D01*
X849462Y123299D01*
G02X849395Y123327I42J196D01*
G01X849307Y123386D01*
X849287Y123414D01*
G03X848084Y124015I-1202J-901D01*
G01X848041D01*
X848040Y124014D01*
G03X846582Y122513I44J-1501D01*
G03X848084Y121011I1502J0D01*
G03X848316Y121029I0J1502D01*
G01X848359Y121036D01*
X848443Y121012D01*
X848707Y120787D01*
G02X848778Y120634I-129J-153D01*
G01Y119436D01*
G02X848707Y119283I-200J0D01*
G01X848443Y119058D01*
X848359Y119034D01*
X848316Y119041D01*
G03X848081Y119059I-232J-1484D01*
G01X848080D01*
G03X846582Y117557I4J-1502D01*
G03X848084Y116055I1502J0D01*
G01X848085D01*
G03X849287Y116656I0J1502D01*
G01X849307Y116684D01*
X849395Y116743D01*
G02X849462Y116771I109J-168D01*
G01X849581Y116798D01*
X849655Y116787D01*
X849688Y116769D01*
G03X849989Y116632I894J1565D01*
G03X850580Y116532I592J1703D01*
G03X851171Y116632I-1J1803D01*
G03X851472Y116769I-593J1702D01*
G01X851505Y116787D01*
X851579Y116798D01*
X851698Y116771D01*
G02X851765Y116743I-42J-196D01*
G01X851852Y116685D01*
X851873Y116657D01*
G03X852574Y116141I1203J900D01*
G01X852634Y116120D01*
X852707Y116017D01*
Y78102D01*
G02X852681Y78003I-200J0D01*
G01X852621Y77899D01*
X852589Y77865D01*
X852568Y77851D01*
G03X852130Y77421I811J-1264D01*
G01X852129Y77420D01*
Y77419D01*
G02X851995Y77334I-165J113D01*
G01X851706Y77288D01*
G02X851552Y77327I-32J197D01*
G03X850631Y77642I-920J-1187D01*
G01X850601D01*
G03X849129Y76140I30J-1502D01*
G03X850631Y74638I1502J0D01*
G01X850647D01*
X850707Y74639D01*
X850810Y74572D01*
X850977Y74174D01*
G02X850934Y73955I-184J-78D01*
G01X849480Y72501D01*
X849452Y72472D01*
X849378Y72442D01*
X803265D01*
G02X803123Y72501I0J200D01*
G01X801807Y73817D01*
X801778Y73845D01*
X801748Y73919D01*
Y100421D01*
G02X801807Y100563I200J0D01*
G01X802009Y100763D01*
G02X802150Y100821I141J-142D01*
G01X802161D01*
G03Y103825I0J1502D01*
G01X802150D01*
G02X802009Y103883I0J200D01*
G01X801807Y104083D01*
G02X801748Y104225I141J142D01*
G01Y107508D01*
G02X801807Y107650I200J0D01*
G01X802009Y107850D01*
G02X802150Y107908I141J-142D01*
G01X802161D01*
G03Y110912I0J1502D01*
G01X802150D01*
G02X802009Y110970I0J200D01*
G01X801807Y111170D01*
G02X801748Y111312I141J142D01*
G01Y114594D01*
G02X801807Y114736I200J0D01*
G01X802009Y114936D01*
G02X802150Y114994I141J-142D01*
G01X802161D01*
G03Y117998I0J1502D01*
G01X802150D01*
G02X802009Y118056I0J200D01*
G01X801807Y118256D01*
G02X801748Y118398I141J142D01*
G01Y121681D01*
G02X801807Y121823I200J0D01*
G01X802009Y122023D01*
G02X802150Y122081I141J-142D01*
G01X802161D01*
G03Y125085I0J1502D01*
G01X802150D01*
G02X802009Y125143I0J200D01*
G01X801807Y125343D01*
G02X801748Y125485I141J142D01*
G01Y128768D01*
G02X801807Y128910I200J0D01*
G01X802009Y129110D01*
G02X802150Y129168I141J-142D01*
G01X802161D01*
G03Y132172I0J1502D01*
G01X802150D01*
G02X802009Y132230I0J200D01*
G01X801807Y132430D01*
G02X801748Y132572I141J142D01*
G01Y135854D01*
G02X801807Y135996I200J0D01*
G01X802009Y136196D01*
G02X802150Y136254I141J-142D01*
G01X802161D01*
G03Y139258I0J1502D01*
G01X802150D01*
G02X802009Y139316I0J200D01*
G01X801807Y139516D01*
G02X801748Y139658I141J142D01*
G01Y172123D01*
G02X801805Y172263I200J0D01*
G01X801806Y172264D01*
X803688Y174146D01*
G02X803690Y174148I142J-140D01*
G02X803830Y174205I140J-143D01*
G01X843759D01*
G02X843945Y174078I0J-200D01*
G01X844104Y173673D01*
X844077Y173554D01*
X844031Y173512D01*
G03X843454Y172190I1226J-1322D01*
G03X847058I1802J0D01*
G03X846481Y173512I-1803J0D01*
G01X846435Y173554D01*
X846408Y173673D01*
X846567Y174078D01*
G02X846753Y174205I186J-73D01*
G37*
G36*
G01X839764Y388583D02*
G03I-19685J0D01*
G37*
G36*
G01X815644Y1159455D02*
G03I-610J0D01*
G37*
G36*
G01X820583Y1442537D02*
X822380D01*
G02X822522Y1442478I0J-200D01*
G01X822961Y1442039D01*
G02X823020Y1441897I-141J-142D01*
G01Y1439039D01*
G03X823079Y1438897I200J0D01*
G01X824109Y1437867D01*
G03X824251Y1437808I142J141D01*
G01X830525D01*
G02X830667Y1437749I0J-200D01*
G01X831905Y1436511D01*
G02X831964Y1436369I-141J-142D01*
G01Y1427316D01*
G02X831905Y1427174I-200J0D01*
G01X831108Y1426377D01*
G02X830966Y1426318I-142J141D01*
G01X815209D01*
G02X815067Y1426377I0J200D01*
G01X807425Y1434019D01*
G02X807366Y1434161I141J142D01*
G01Y1434960D01*
G03X807307Y1435102I-200J0D01*
G01X807212Y1435197D01*
G03X807070Y1435256I-142J-141D01*
G01X805317D01*
G02X805175Y1435315I0J200D01*
G01X805159Y1435331D01*
X805129Y1435404D01*
Y1438027D01*
G02X805188Y1438169I200J0D01*
G01X809235Y1442216D01*
G02X809376Y1442274I141J-142D01*
G01X820155D01*
G03X820296Y1442333I-1J200D01*
G01X820441Y1442478D01*
G02X820583Y1442537I142J-141D01*
G37*
G36*
G01X808249Y1451036D02*
X807988Y1451297D01*
G02X807982Y1451574I141J142D01*
G03X808292Y1452092I-1107J1014D01*
G02X808339Y1452167I189J-66D01*
G01X808479Y1452307D01*
G03X808538Y1452449I-141J142D01*
G01Y1460097D01*
G03X808479Y1460239I-200J0D01*
G01X806369Y1462350D01*
G02X806310Y1462492I141J142D01*
G01Y1467560D01*
G02X806400Y1467726I200J-1D01*
G01X806720Y1467939D01*
X806820Y1467947D01*
X806867Y1467927D01*
G03X807574Y1467782I708J1657D01*
G01X807576D01*
G03X809378Y1469584I0J1802D01*
G03X807635Y1471385I-1802J0D01*
G01X807634D01*
G02X807501Y1471443I8J200D01*
G01X807061Y1471883D01*
G03X806463Y1472218I-892J-892D01*
G01X806396Y1472234D01*
X806310Y1472342D01*
Y1474446D01*
G02X806369Y1474588I200J0D01*
G01X806668Y1474887D01*
G03X806727Y1475029I-141J142D01*
G01Y1523081D01*
G02X806786Y1523223I200J0D01*
G01X816712Y1533149D01*
G03X816771Y1533291I-141J142D01*
G01Y1620528D01*
G02X816830Y1620670I200J0D01*
G01X822421Y1626261D01*
G02X822563Y1626320I142J-141D01*
G01X925976D01*
G02X926118Y1626261I0J-200D01*
G01X928293Y1624086D01*
G02X928352Y1623944I-141J-142D01*
G01Y1584858D01*
G03X928411Y1584716I200J0D01*
G01X942833Y1570294D01*
G03X942975Y1570235I142J141D01*
G01X957268D01*
G02X957410Y1570176I0J-200D01*
G01X960160Y1567426D01*
G02X960219Y1567284I-141J-142D01*
G01Y1540502D01*
G03X960278Y1540360I200J0D01*
G01X965523Y1535115D01*
G03X965665Y1535056I142J141D01*
G01X1018624D01*
G02X1018766Y1534997I0J-200D01*
G01X1030834Y1522929D01*
G02X1030893Y1522787I-141J-142D01*
G01Y1493284D01*
G02X1030834Y1493142I-200J0D01*
G01X1029903Y1492211D01*
G02X1029761Y1492152I-142J141D01*
G01X948156D01*
G02X948014Y1492211I0J200D01*
G01X944667Y1495558D01*
G03X944525Y1495617I-142J-141D01*
G01X933505D01*
G03X933363Y1495558I0J-200D01*
G01X917110Y1479305D01*
G03X917051Y1479163I141J-142D01*
G01Y1464932D01*
G02X916992Y1464790I-200J0D01*
G01X914123Y1461921D01*
G03X914064Y1461779I141J-142D01*
G01Y1460721D01*
G02X914005Y1460579I-200J0D01*
G01X913461Y1460035D01*
G03X913402Y1459893I141J-142D01*
G01Y1446495D01*
G02X913343Y1446353I-200J0D01*
G01X913215Y1446225D01*
G02X913073Y1446166I-142J141D01*
G01X900184D01*
G02X900042Y1446225I0J200D01*
G01X900030Y1446237D01*
Y1459842D01*
G03X899971Y1459984I-200J0D01*
G01X899324Y1460631D01*
G02X899265Y1460773I141J142D01*
G01Y1462422D01*
G03X899206Y1462564I-200J0D01*
G01X893355Y1468415D01*
G02X893296Y1468557I141J142D01*
G01Y1473901D01*
G03X893237Y1474043I-200J0D01*
G01X887942Y1479338D01*
G03X887800Y1479397I-142J-141D01*
G01X880431D01*
G03X880289Y1479338I0J-200D01*
G01X872219Y1471268D01*
G03X872160Y1471126I141J-142D01*
G01Y1460893D01*
G02X872101Y1460751I-200J0D01*
G01X871408Y1460058D01*
G03X871349Y1459916I141J-142D01*
G01Y1446735D01*
G02X871290Y1446593I-200J0D01*
G01X871083Y1446386D01*
G02X870941Y1446327I-142J141D01*
G01X858073D01*
G02X857931Y1446386I0J200D01*
G01X857913Y1446404D01*
X857883Y1446477D01*
Y1459844D01*
G03X857824Y1459986I-200J0D01*
G01X852356Y1465454D01*
G03X852214Y1465513I-142J-141D01*
G01X829290D01*
G03X829148Y1465454I0J-200D01*
G01X822040Y1458346D01*
G02X821898Y1458287I-142J141D01*
G01X819688D01*
G03X819546Y1458228I0J-200D01*
G01X819332Y1458014D01*
G03X819273Y1457872I141J-142D01*
G01Y1447052D01*
G02X819214Y1446910I-200J0D01*
G01X818639Y1446335D01*
G02X818497Y1446276I-142J141D01*
G01X808508D01*
G02X808308Y1446476I0J200D01*
G01Y1446981D01*
G02X808316Y1447036I200J-1D01*
G03Y1447878I-1443J421D01*
G02X808308Y1447933I192J56D01*
G01Y1450894D01*
G03X808249Y1451036I-200J0D01*
G37*
G36*
G01X820583Y754109D02*
G03I-590J0D01*
G37*
G36*
G01X819724Y863607D02*
G03I-590J0D01*
G37*
G36*
G01X829590Y852000D02*
G03I-590J0D01*
G37*
G36*
G01X827387Y883756D02*
G03I-590J0D01*
G37*
G36*
G01X949468Y54588D02*
X978644D01*
X978785Y54447D01*
Y52732D01*
X978644Y52591D01*
X949468D01*
G03X943531Y46654I0J-5937D01*
G01Y7874D01*
G02X937657Y2000I-5874J0D01*
G01X842776D01*
G02X836902Y7874I0J5874D01*
G01Y46658D01*
G03X836896Y46925I-5938J0D01*
G01X838895D01*
G02X838900Y46654I-7930J-282D01*
G01Y7874D01*
G03X842776Y3998I3876J0D01*
G01X937657D01*
G03X941534Y7874I0J3877D01*
G01Y46654D01*
G02X949468Y54588I7934J0D01*
G37*
G36*
G01X854008Y463194D02*
X915137D01*
X915210Y463164D01*
X915234Y463140D01*
Y446331D01*
G02X915175Y446189I-200J0D01*
G01X912423Y443437D01*
G02X912281Y443378I-142J141D01*
G01X908735D01*
X908629Y443456D01*
X908610Y443520D01*
G03X905736I-1437J-440D01*
G01X905717Y443456D01*
X905611Y443378D01*
X887868D01*
G03X887726Y443319I0J-200D01*
G01X883222Y438815D01*
G03X883163Y438673I141J-142D01*
G01Y431574D01*
X883159Y431570D01*
Y411794D01*
G03X883218Y411652I200J0D01*
G01X885108Y409762D01*
G02X885167Y409620I-141J-142D01*
G01Y408144D01*
G02X885108Y408002I-200J0D01*
G01X884834Y407728D01*
G02X884692Y407669I-142J141D01*
G01X876436D01*
G03X876294Y407610I0J-200D01*
G01X875808Y407124D01*
G02X875666Y407065I-142J141D01*
G01X873852D01*
G02X873674Y407175I1J200D01*
G01X873487Y407543D01*
X873496Y407656D01*
X873530Y407701D01*
G03X873820Y408589I-1212J887D01*
G03X872318Y410091I-1502J0D01*
G03X870880Y409023I0J-1502D01*
G01X870866Y408975D01*
X870797Y408905D01*
X870390Y408774D01*
X870294Y408790D01*
X870254Y408820D01*
G03X869342Y409129I-912J-1193D01*
G03X867840Y407627I0J-1502D01*
G03X867845Y407499I1502J-5D01*
G01X867849Y407456D01*
X867823Y407378D01*
X867594Y407130D01*
G02X867447Y407065I-148J135D01*
G01X845687D01*
G02X845526Y407147I0J200D01*
G03X844994Y407855I-25445J-18566D01*
G01X844973Y407881D01*
X844952Y407944D01*
Y416124D01*
G02X845011Y416266I200J0D01*
G01X851385Y422640D01*
G03X851444Y422782I-141J142D01*
G01Y429918D01*
X851414Y429991D01*
X851397Y430008D01*
Y454947D01*
X851427Y455020D01*
X851428Y455021D01*
Y459934D01*
G02X851523Y460104I200J0D01*
G03X852235Y461382I-791J1278D01*
G01Y461416D01*
X852234Y461458D01*
X852264Y461533D01*
X853866Y463135D01*
G02X854008Y463194I142J-141D01*
G37*
G36*
G01X891184Y1294933D02*
X901256D01*
G02X901397Y1294874I-1J-200D01*
G01X902333Y1293939D01*
G03X902372Y1293901I1598J1601D01*
G01X902373Y1293899D01*
X902527Y1293746D01*
G03X904126Y1293084I1599J1600D01*
G01X915722D01*
G02X915864Y1293025I0J-200D01*
G01X924912Y1283977D01*
G03X926511Y1283314I1600J1599D01*
G01X963447D01*
G02X963589Y1283256I1J-200D01*
G01X976528Y1270317D01*
G02X976571Y1270252I-142J-141D01*
G01X982535Y1255852D01*
G02X982550Y1255776I-185J-76D01*
G01Y1184293D01*
G02X982491Y1184151I-200J0D01*
G01X978615Y1180276D01*
G03X978556Y1180134I141J-142D01*
G01Y1159946D01*
G02X978497Y1159804I-200J0D01*
G01X977099Y1158406D01*
X977071Y1158377D01*
X976997Y1158347D01*
X976982D01*
G03X976782Y1158147I0J-200D01*
G01Y1114293D01*
G02X976723Y1114151I-200J0D01*
G01X975831Y1113258D01*
G02X975689Y1113199I-142J141D01*
G01X965549D01*
G02X965407Y1113258I0J200D01*
G01X964514Y1114151D01*
G02X964455Y1114293I141J142D01*
G01Y1155805D01*
G03X964396Y1155947I-200J0D01*
G01X962988Y1157355D01*
G03X962846Y1157414I-142J-141D01*
G01X931137D01*
G03X930995Y1157355I0J-200D01*
G01X928473Y1154833D01*
G03X928414Y1154691I141J-142D01*
G01Y1119892D01*
G02X928355Y1119750I-200J0D01*
G01X927732Y1119127D01*
G02X927590Y1119068I-142J141D01*
G01X920633D01*
G03X920491Y1119009I0J-200D01*
G01X918820Y1117338D01*
G03X918761Y1117196I141J-142D01*
G01Y1107088D01*
G03X918820Y1106946I200J0D01*
G01X920238Y1105528D01*
G03X920380Y1105469I142J141D01*
G01X921548D01*
X921621Y1105439D01*
X921646Y1105414D01*
X950520D01*
G02X950661Y1105355I-1J-200D01*
G01X952055Y1103961D01*
G02X952114Y1103819I-141J-142D01*
G01Y1097989D01*
G02X952055Y1097847I-200J0D01*
G01X951760Y1097552D01*
G02X951619Y1097494I-141J142D01*
G01X949530D01*
G02X949389Y1097552I0J200D01*
G01X948932Y1098009D01*
G03X948790Y1098068I-142J-141D01*
G01X922218D01*
G03X922076Y1098009I0J-200D01*
G01X921492Y1097425D01*
G03X921433Y1097283I141J-142D01*
G01Y1088051D01*
G03X921492Y1087909I200J0D01*
G01X922509Y1086892D01*
G02X922568Y1086750I-141J-142D01*
G01Y1072827D01*
G02X922368Y1072627I-200J0D01*
G01X898667D01*
G02X898525Y1072686I0J200D01*
G01X898156Y1073055D01*
G02X898097Y1073197I141J142D01*
G01Y1076487D01*
G03X898038Y1076629I-200J0D01*
G01X897564Y1077103D01*
G03X897422Y1077162I-142J-141D01*
G01X893751D01*
G02X893609Y1077221I0J200D01*
G01X884833Y1085997D01*
G02X884774Y1086139I141J142D01*
G01Y1097289D01*
G03X884715Y1097431I-200J0D01*
G01X882792Y1099354D01*
G02X882734Y1099495I142J141D01*
G01Y1101831D01*
G03X882675Y1101972I-200J-1D01*
G01X882654Y1101994D01*
G02X882595Y1102135I141J142D01*
G01Y1103333D01*
G02X882654Y1103475I200J0D01*
G01X883064Y1103885D01*
G02X883206Y1103944I142J-141D01*
G01X891123D01*
G02X891291Y1103852I0J-200D01*
G01X891501Y1103527D01*
X891509Y1103426D01*
X891488Y1103379D01*
G03X891354Y1102760I1368J-620D01*
G03X894358I1502J0D01*
G03X894224Y1103379I-1502J-1D01*
G01X894203Y1103426D01*
X894211Y1103527D01*
X894421Y1103852D01*
G02X894589Y1103944I168J-108D01*
G01X898341D01*
G03X898483Y1104003I0J200D01*
G01X900419Y1105939D01*
G03X900478Y1106081I-141J142D01*
G01Y1155805D01*
G03X900419Y1155947I-200J0D01*
G01X899011Y1157355D01*
G03X898869Y1157414I-142J-141D01*
G01X867160D01*
G03X867018Y1157355I0J-200D01*
G01X864496Y1154833D01*
G03X864437Y1154691I141J-142D01*
G01Y1119892D01*
G02X864378Y1119750I-200J0D01*
G01X863755Y1119127D01*
G02X863613Y1119068I-142J141D01*
G01X841907D01*
G02X841765Y1119127I0J200D01*
G01X839117Y1121775D01*
G02X839058Y1121917I141J142D01*
G01Y1163857D01*
X839028Y1163930D01*
X839007Y1163951D01*
Y1243219D01*
G02X839066Y1243361I200J0D01*
G01X889689Y1293984D01*
X889757Y1294014D01*
X889795Y1294015D01*
G03X891063Y1294825I-66J1501D01*
G01X891089Y1294875D01*
X891184Y1294933D01*
G37*
G36*
G01X866770Y834686D02*
X869672D01*
G02X869814Y834627I0J-200D01*
G01X869964Y834477D01*
G02X870023Y834335I-141J-142D01*
G01Y820115D01*
G02X869964Y819973I-200J0D01*
G01X869580Y819589D01*
G02X869438Y819530I-142J141D01*
G01X864970D01*
X863500Y821000D01*
Y831500D01*
X863646Y831646D01*
X866628Y834627D01*
G02X866770Y834686I142J-141D01*
G37*
G36*
G01X894884Y1071008D02*
X905640D01*
G02X905760Y1070968I0J-200D01*
G02X905782Y1070949I-119J-160D01*
G01X906757Y1069974D01*
G02X906776Y1069952I-141J-141D01*
G02X906816Y1069832I-160J-120D01*
G01Y1005824D01*
X905618Y1004626D01*
X871101D01*
X863386Y1012341D01*
X851457D01*
G02X851337Y1012381I0J200D01*
G02X851315Y1012400I119J160D01*
G01X849629Y1014086D01*
G02X849610Y1014108I141J141D01*
G02X849570Y1014228I160J120D01*
G01Y1015780D01*
G03X850023Y1016855I-1049J1075D01*
G03X849570Y1017930I-1502J0D01*
G01Y1067483D01*
G02X849610Y1067603I200J0D01*
G02X849629Y1067625I160J-119D01*
G01X852734Y1070730D01*
G02X852756Y1070749I141J-141D01*
G02X852876Y1070789I120J-160D01*
G01X864727D01*
G02X864847Y1070749I0J-200D01*
G02X864869Y1070730I-119J-160D01*
G01X865079Y1070520D01*
G02X865098Y1070498I-141J-141D01*
G02X865138Y1070378I-160J-120D01*
G01Y1029358D01*
G03X865197Y1029216I200J0D01*
G01X866336Y1028077D01*
G03X866478Y1028018I142J141D01*
G01X891821D01*
G03X891963Y1028077I0J200D01*
G01X893920Y1030034D01*
G03X893979Y1030176I-141J142D01*
G01Y1070103D01*
X894884Y1071008D01*
G37*
G36*
G01X851295Y1106495D02*
X854045D01*
G02X854187Y1106436I0J-200D01*
G01X855852Y1104771D01*
G03X855994Y1104712I142J141D01*
G01X856957D01*
G02X857098Y1104653I-1J-200D01*
G01X857450Y1104302D01*
G03X857591Y1104244I141J142D01*
G01X879181D01*
G02X879381Y1104044I0J-200D01*
G01Y1102985D01*
G02X879322Y1102843I-200J0D01*
G01X879132Y1102653D01*
G02X878991Y1102594I-142J141D01*
G01X862594D01*
G02X862453Y1102653I1J200D01*
G01X862047Y1103059D01*
G03X861905Y1103118I-142J-141D01*
G01X860421D01*
X860410Y1103108D01*
X857808D01*
G03X857667Y1103049I1J-200D01*
G01X857065Y1102448D01*
G02X856924Y1102389I-142J141D01*
G01X856750D01*
G03X856608Y1102330I0J-200D01*
G01X855754Y1101476D01*
G03X855695Y1101334I141J-142D01*
G01Y1071990D01*
G02X855495Y1071790I-200J0D01*
G01X852876D01*
G03X852635Y1071766I-2J-1201D01*
G01X852615Y1071762D01*
X849512D01*
G02X849370Y1071821I0J200D01*
G01X848624Y1072567D01*
G02X848565Y1072709I141J142D01*
G01Y1103765D01*
G02X848624Y1103907I200J0D01*
G01X851153Y1106436D01*
G02X851295Y1106495I142J-141D01*
G37*
G36*
G01X884992Y1083942D02*
X892445Y1076488D01*
X892903Y1076030D01*
X895289D01*
Y1073302D01*
X892504Y1070517D01*
Y1031106D01*
G02X892445Y1030964I-200J0D01*
G01X891842Y1030361D01*
G02X891700Y1030302I-142J141D01*
G01X867307D01*
G02X867165Y1030361I0J200D01*
G01X866198Y1031328D01*
G02X866139Y1031469I141J142D01*
G01Y1070793D01*
G03X866081Y1070934I-200J0D01*
G01X866071Y1070945D01*
G02X866012Y1071086I141J142D01*
G01Y1071218D01*
X865302Y1071928D01*
X858446D01*
X858045Y1072329D01*
Y1072897D01*
Y1102011D01*
X858140Y1102106D01*
X861502D01*
X862015Y1101593D01*
X881638D01*
X881732Y1101499D01*
Y1097653D01*
X882518Y1096867D01*
X883685Y1095700D01*
Y1085249D01*
X884851Y1084083D01*
X884992Y1083942D01*
G37*
G36*
G01X856230Y1107021D02*
Y1114742D01*
G02X856289Y1114884I200J0D01*
G01X857725Y1116320D01*
G02X857867Y1116379I142J-141D01*
G01X863936D01*
G03X864078Y1116438I0J200D01*
G01X865867Y1118227D01*
G03X865926Y1118369I-141J142D01*
G01Y1153829D01*
G02X865985Y1153971I200J0D01*
G01X867732Y1155718D01*
G02X867874Y1155777I142J-141D01*
G01X898792D01*
G02X898934Y1155718I0J-200D01*
G01X899138Y1155514D01*
G02X899197Y1155372I-141J-142D01*
G01Y1106284D01*
G02X899138Y1106142I-200J0D01*
G01X898300Y1105304D01*
G02X898158Y1105245I-142J141D01*
G01X858006D01*
G02X857864Y1105304I0J200D01*
G01X856289Y1106879D01*
G02X856230Y1107021I141J142D01*
G37*
G36*
G01X872712Y1442356D02*
X873303D01*
G02X873445Y1442297I0J-200D01*
G01X873906Y1441836D01*
G02X873965Y1441694I-141J-142D01*
G01Y1425969D01*
G02X873906Y1425827I-200J0D01*
G01X873512Y1425433D01*
G02X873370Y1425374I-142J141D01*
G01X857566D01*
G02X857424Y1425433I0J200D01*
G01X857000Y1425857D01*
G02X856941Y1425999I141J142D01*
G01Y1441772D01*
G02X857000Y1441914I200J0D01*
G01X857353Y1442267D01*
G02X857494Y1442326I142J-141D01*
G01X872638D01*
X872712Y1442356D01*
G37*
G36*
G01X876032Y568363D02*
X887866D01*
G02X888008Y568304I0J-200D01*
G01X888500Y567812D01*
Y566566D01*
X886297Y564363D01*
X876558D01*
X874583Y562388D01*
Y557825D01*
X873644Y556886D01*
X869727D01*
X869120Y557493D01*
Y567654D01*
X869829Y568363D01*
X871194D01*
X876032D01*
G37*
G36*
G01X897032Y601532D02*
X897424D01*
G02X897566Y601473I0J-200D01*
G01X899086Y599953D01*
G02X899145Y599811I-141J-142D01*
G01Y593796D01*
G02X899086Y593654I-200J0D01*
G01X898264Y592832D01*
G02X898123Y592774I-141J142D01*
G01X892625D01*
X892615Y592764D01*
X891041D01*
G03X890900Y592705I1J-200D01*
G01X888735Y590540D01*
G03X888676Y590399I141J-142D01*
G01Y590303D01*
G02X888618Y590162I-200J0D01*
G01X888600Y590144D01*
G03X888541Y590002I141J-142D01*
G01Y575308D01*
G02X888482Y575166I-200J0D01*
G01X887666Y574350D01*
G02X887524Y574291I-142J141D01*
G01X878597D01*
X877184Y575704D01*
Y579393D01*
X876375Y580202D01*
X875781Y580796D01*
Y600735D01*
G02X875840Y600877I200J0D01*
G01X876435Y601472D01*
G02X876577Y601531I142J-141D01*
G01X897031D01*
X897032Y601532D01*
G37*
G36*
G01X884390Y604304D02*
X884008Y603922D01*
G02X883866Y603863I-142J141D01*
G01X874032D01*
G02X873890Y603922I0J200D01*
G01X873508Y604304D01*
G02X873449Y604446I141J142D01*
G01Y609780D01*
G02X873508Y609922I200J0D01*
G01X873890Y610304D01*
G02X874032Y610363I142J-141D01*
G01X883866D01*
G02X884008Y610304I0J-200D01*
G01X884390Y609922D01*
G02X884449Y609780I-141J-142D01*
G01Y604446D01*
G02X884390Y604304I-200J0D01*
G37*
G36*
G01X873908Y744597D02*
G03I-590J0D01*
G37*
G36*
G01X872581Y834790D02*
X877267D01*
G02X877409Y834731I0J-200D01*
G01X880469Y831671D01*
G02X880528Y831529I-141J-142D01*
G01Y830123D01*
G03X880526Y830067I1234J-72D01*
G01Y824161D01*
G02X880468Y824020I-200J0D01*
G01X876639Y820191D01*
G02X876497Y820132I-142J141D01*
G01X872916D01*
G02X872774Y820191I0J200D01*
G01X872356Y820609D01*
G02X872297Y820751I141J142D01*
G01Y834506D01*
G02X872356Y834648I200J0D01*
G01X872439Y834731D01*
G02X872581Y834790I142J-141D01*
G37*
G36*
G01X895184Y548863D02*
X899866D01*
G02X900008Y548804I0J-200D01*
G01X900390Y548422D01*
G02X900449Y548280I-141J-142D01*
G01Y542446D01*
G02X900390Y542304I-200J0D01*
G01X899508Y541422D01*
G02X899366Y541363I-142J141D01*
G01X890532D01*
G02X890390Y541422I0J200D01*
G01X889508Y542304D01*
G02X889449Y542446I141J142D01*
G01Y548280D01*
G02X889508Y548422I200J0D01*
G01X889890Y548804D01*
G02X890032Y548863I142J-141D01*
G01X892714D01*
G02X892831Y548825I0J-200D01*
G03X893949Y548462I1117J1538D01*
G03X895067Y548825I1J1901D01*
G02X895184Y548863I117J-162D01*
G37*
G36*
G01X889678Y569701D02*
X888508Y570871D01*
Y573666D01*
X889678Y574836D01*
Y589984D01*
G02X889737Y590126I200J0D01*
G01X891314Y591703D01*
G02X891456Y591762I142J-141D01*
G01X893030D01*
X893040Y591772D01*
X910736D01*
G02X910878Y591713I0J-200D01*
G01X912467Y590124D01*
G02X912526Y589982I-141J-142D01*
G01Y570089D01*
G02X912467Y569947I-200J0D01*
G01X911019Y568499D01*
G03X910960Y568357I141J-142D01*
G01Y567531D01*
X910214Y566785D01*
X897267D01*
X895205Y568847D01*
X890532D01*
X889678Y569701D01*
G37*
G36*
G01X901390Y559304D02*
X900508Y558422D01*
G02X900366Y558363I-142J141D01*
G01X897032D01*
G03X896890Y558304I0J-200D01*
G01X896508Y557922D01*
G02X896366Y557863I-142J141D01*
G01X888532D01*
G02X888390Y557922I0J200D01*
G01X888008Y558304D01*
G02X887949Y558446I141J142D01*
G01Y561280D01*
Y564402D01*
X889838Y566291D01*
X895212D01*
X896055D01*
X896626Y565720D01*
X900778D01*
X901449Y565049D01*
Y560780D01*
Y559446D01*
G02X901390Y559304I-200J0D01*
G37*
G36*
G01X889673Y780371D02*
G03I-590J0D01*
G37*
G36*
G01X909412Y874533D02*
X911236D01*
G02X911396Y874452I-1J-200D01*
G01X911580Y874205D01*
X911595Y874108D01*
X911580Y874062D01*
G03X911512Y873639I1284J-423D01*
G01Y873638D01*
G03X912864Y872286I1352J0D01*
G03X913231Y872337I-1J1352D01*
G01X913277Y872350D01*
X913370Y872332D01*
X913608Y872147D01*
G02X913685Y871990I-123J-158D01*
G01Y870112D01*
G02X913626Y869970I-200J0D01*
G01X913207Y869551D01*
G02X913079Y869492I-142J141D01*
G01X912469D01*
X912112Y869261D01*
Y868567D01*
X912200Y868510D01*
G03X912203Y868508I112J165D01*
G01X912419Y868368D01*
G03X912433Y868360I106J169D01*
G01X912469Y868336D01*
X912513D01*
X913089D01*
G02X913206Y868279I-24J-198D01*
G01X913626Y867859D01*
G02X913628Y867857I-140J-142D01*
G02X913685Y867717I-143J-140D01*
G01Y866962D01*
G02X913626Y866820I-200J0D01*
G01X913207Y866401D01*
G02X913079Y866342I-142J141D01*
G01X912469D01*
X912112Y866111D01*
Y865417D01*
X912200Y865360D01*
G03X912203Y865358I112J165D01*
G01X912419Y865218D01*
G03X912433Y865210I106J169D01*
G01X912469Y865186D01*
X912513D01*
X913089D01*
G02X913206Y865129I-24J-198D01*
G01X913626Y864709D01*
G02X913628Y864707I-140J-142D01*
G02X913685Y864567I-143J-140D01*
G01Y860663D01*
G02X913626Y860521I-200J0D01*
G01X913208Y860103D01*
G02X913066Y860044I-142J141D01*
G01X912527D01*
X912469D01*
X912433Y860021D01*
G03X912419Y860012I101J-173D01*
G01X912241Y859896D01*
X912112Y859812D01*
Y859118D01*
X912469Y858888D01*
X913085D01*
G02X913202Y858834I-21J-199D01*
G02X913206Y858830I-139J-143D01*
G01X913626Y858410D01*
G02X913631Y858405I-139J-144D01*
G02X913685Y858269I-146J-137D01*
G01Y855204D01*
G02X913626Y855062I-200J0D01*
G01X913610Y855046D01*
G02X913544Y855002I-142J141D01*
G01X913513Y854989D01*
G03X913448Y854946I76J-185D01*
G01X912671Y854169D01*
G03X912612Y854027I141J-142D01*
G01Y853945D01*
G02X912521Y853777I-200J0D01*
G01X912471Y853744D01*
X912469D01*
X912112Y853513D01*
Y852879D01*
X912031Y852720D01*
G03X911617Y852232I834J-1127D01*
G01X911591Y852182D01*
X911496Y852124D01*
X911030Y852120D01*
X910934Y852177D01*
X910908Y852227D01*
G03X909836Y852939I-1194J-635D01*
G01X909704Y853005D01*
X909703Y853006D01*
Y853312D01*
G03X909644Y853454I-200J0D01*
G01X909490Y853608D01*
G03X909348Y853667I-142J-141D01*
G01X903162D01*
Y853715D01*
X902477Y854400D01*
G02X902420Y854517I141J141D01*
G01Y855079D01*
Y855137D01*
X902397Y855173D01*
G03X902388Y855187I-173J-101D01*
G01X902272Y855365D01*
X902188Y855494D01*
X901494D01*
X901264Y855137D01*
Y854527D01*
G02X901205Y854399I-200J14D01*
G01X900532Y853726D01*
X900504Y853697D01*
X900430Y853667D01*
X895052D01*
G02X894910Y853726I0J200D01*
G01X893945Y854691D01*
G03X893599Y854972I-1538J-1540D01*
G01X893561Y854998D01*
X893515Y855073D01*
X893478Y855428D01*
G02X893536Y855590I199J20D01*
G01X893625Y855679D01*
G02X893753Y855738I142J-141D01*
G01X894363D01*
X894720Y855969D01*
Y856663D01*
X894632Y856720D01*
G03X894629Y856722I-112J-165D01*
G01X894413Y856862D01*
G03X894399Y856870I-106J-169D01*
G01X894363Y856894D01*
X894319D01*
X893743D01*
G02X893626Y856951I24J198D01*
G01X893258Y857319D01*
X893229Y857347D01*
X893199Y857421D01*
Y858319D01*
G02X893256Y858459I200J0D01*
G01X893624Y858827D01*
G02X893766Y858886I142J-141D01*
G01X894305D01*
X894363D01*
X894399Y858909D01*
G03X894413Y858918I-101J173D01*
G01X894591Y859034D01*
X894720Y859118D01*
Y859812D01*
X894363Y860042D01*
X893747D01*
G02X893630Y860096I21J199D01*
G02X893626Y860100I139J143D01*
G01X893258Y860468D01*
X893229Y860496D01*
X893199Y860570D01*
Y861469D01*
G02X893256Y861609I200J0D01*
G01X893624Y861977D01*
G02X893766Y862036I142J-141D01*
G01X894305D01*
X894363D01*
X894399Y862059D01*
G03X894413Y862068I-101J173D01*
G01X894591Y862184D01*
X894720Y862268D01*
Y862962D01*
X894363Y863192D01*
X893747D01*
G02X893630Y863246I21J199D01*
G02X893626Y863250I139J143D01*
G01X893258Y863618D01*
X893229Y863646D01*
X893199Y863720D01*
Y867769D01*
G02X893252Y867904I200J-1D01*
G01X893625Y868277D01*
G02X893753Y868336I142J-141D01*
G01X894363D01*
X894720Y868567D01*
Y869261D01*
X894632Y869318D01*
G03X894629Y869320I-112J-165D01*
G01X894413Y869460D01*
G03X894399Y869468I-106J-169D01*
G01X894363Y869492D01*
X894319D01*
X893743D01*
G02X893626Y869549I24J198D01*
G01X893258Y869917D01*
X893229Y869945D01*
X893199Y870019D01*
Y874195D01*
G02X893256Y874335I200J0D01*
G01X893395Y874474D01*
G02X893397Y874476I142J-140D01*
G02X893537Y874533I140J-143D01*
G01X897420D01*
G02X897556Y874479I-1J-200D01*
G01X898055Y873980D01*
G02X898114Y873852I-141J-142D01*
G01Y873242D01*
X898345Y872884D01*
X898440D01*
X898930D01*
X899039D01*
X899095Y872972D01*
G03X899098Y872976I-158J122D01*
G01X899238Y873192D01*
G03X899246Y873206I-169J106D01*
G01X899270Y873242D01*
Y873286D01*
Y873839D01*
G02X899329Y873981I200J0D01*
G01X899822Y874474D01*
G02X899824Y874476I142J-140D01*
G02X899964Y874533I140J-143D01*
G01X900568D01*
G02X900708Y874476I0J-200D01*
G01X901205Y873979D01*
G02X901262Y873862I-141J-141D01*
G01Y873300D01*
Y873242D01*
X901285Y873206D01*
G03X901294Y873192I173J101D01*
G01X901435Y872975D01*
G03X901442Y872965I167J110D01*
G01X901494Y872884D01*
X901589D01*
X902079D01*
X902188D01*
X902244Y872972D01*
G03X902247Y872976I-158J122D01*
G01X902257Y872991D01*
X902418Y873242D01*
Y873852D01*
G02X902477Y873980I200J-14D01*
G01X902971Y874474D01*
G02X902976Y874479I144J-139D01*
G02X903112Y874533I137J-146D01*
G01X903718D01*
G02X903858Y874476I0J-200D01*
G01X904355Y873979D01*
G02X904412Y873862I-141J-141D01*
G01Y873300D01*
Y873242D01*
X904435Y873206D01*
G03X904444Y873192I173J101D01*
G01X904585Y872975D01*
G03X904592Y872965I167J110D01*
G01X904644Y872884D01*
X904739D01*
X905229D01*
X905338D01*
X905394Y872972D01*
G03X905397Y872976I-158J122D01*
G01X905407Y872991D01*
X905568Y873242D01*
Y873852D01*
G02X905627Y873980I200J-14D01*
G01X906121Y874474D01*
G02X906126Y874479I144J-139D01*
G02X906262Y874533I137J-146D01*
G01X906868D01*
G02X907004Y874479I-1J-200D01*
G01X907503Y873980D01*
G02X907562Y873852I-141J-142D01*
G01Y873242D01*
X907793Y872884D01*
X907888D01*
X908378D01*
X908487D01*
X908543Y872972D01*
G03X908546Y872976I-158J122D01*
G01X908686Y873192D01*
G03X908694Y873206I-169J106D01*
G01X908718Y873242D01*
Y873286D01*
Y873839D01*
G02X908777Y873981I200J0D01*
G01X909270Y874474D01*
G02X909272Y874476I142J-140D01*
G02X909412Y874533I140J-143D01*
G37*
G36*
G01X907160Y850377D02*
X908349D01*
G02X908489Y850320I0J-200D01*
G01X908490Y850319D01*
X908936Y849873D01*
G02X908938Y849871I-140J-142D01*
G02X908995Y849731I-143J-140D01*
G01Y849644D01*
X908952Y849560D01*
X908913Y849531D01*
G03X908362Y848442I801J-1089D01*
G03X908924Y847345I1352J0D01*
G02X908987Y847271I-116J-163D01*
G01X908995Y847254D01*
Y847051D01*
G03X908994Y847022I1200J-56D01*
G01Y846527D01*
G02X908974Y846438I-200J-2D01*
G01X908964Y846418D01*
G03X908650Y846128I749J-1126D01*
G02X908493Y846051I-158J123D01*
G01X907786D01*
G02X907629Y846128I1J200D01*
G03X905501I-1064J-836D01*
G02X905344Y846051I-158J123D01*
G01X901488D01*
G02X901331Y846128I1J200D01*
G03X899203I-1064J-836D01*
G02X899046Y846051I-158J123D01*
G01X898370D01*
G02X898211Y846129I0J200D01*
G03X897629Y846571I-1094J-836D01*
G01X897590Y846587D01*
X895894Y848283D01*
X895865Y848311D01*
X895835Y848385D01*
Y849694D01*
G02X895892Y849834I200J0D01*
G01X895893Y849835D01*
X896408Y850350D01*
X896529Y850374D01*
X896585Y850349D01*
G03X897118Y850240I532J1243D01*
G03X897673Y850359I0J1352D01*
G01X897713Y850377D01*
X899672D01*
X899712Y850359D01*
G03X900267Y850240I555J1233D01*
G03X900822Y850359I0J1352D01*
G01X900862Y850377D01*
X905970D01*
X906010Y850359D01*
G03X906565Y850240I555J1233D01*
G03X907120Y850359I0J1352D01*
G01X907160Y850377D01*
G37*
G36*
G01X883160Y994245D02*
G03I-551J0D01*
G37*
G36*
G01X907548Y381101D02*
X935512D01*
G02X935654Y381042I0J-200D01*
G01X937689Y379007D01*
G02X937748Y378865I-141J-142D01*
G01Y373732D01*
G03X937763Y373655I200J-1D01*
G01X937792Y373587D01*
G02X937807Y373510I-185J-76D01*
G01Y372262D01*
G02X937748Y372120I-200J0D01*
G01X936786Y371157D01*
X936595Y370967D01*
G03X936584Y370956I844J-855D01*
G01Y370955D01*
X936301Y370672D01*
G03X936242Y370531I141J-142D01*
G01Y366898D01*
G02X936188Y366762I-200J1D01*
G01X936133Y366703D01*
G02X936076Y366661I-145J138D01*
G01X935984Y366615D01*
X935950Y366611D01*
G03Y363035I225J-1788D01*
G01X935984Y363031D01*
X936076Y362985D01*
G02X936133Y362943I-88J-180D01*
G01X936188Y362884D01*
G02X936242Y362748I-146J-137D01*
G01Y356549D01*
G02X936109Y356361I-200J0D01*
G01X935754Y356235D01*
G02X935531Y356299I-66J189D01*
G03X934128Y356970I-1403J-1131D01*
G03Y353366I0J-1802D01*
G03X935915Y354938I0J1802D01*
G01X935919Y354966D01*
X935941Y355017D01*
X935959Y355039D01*
G02X936049Y355101I154J-127D01*
G01X936388Y355218D01*
G02X936595Y355170I65J-189D01*
G01X936981Y354784D01*
X937748Y354016D01*
G02X937807Y353875I-141J-142D01*
G01Y348527D01*
G02X937748Y348385I-200J0D01*
G01X936176Y346813D01*
G03X934976Y345613I277J-1477D01*
G01X934841Y345478D01*
X934813Y345449D01*
X934739Y345419D01*
X929123D01*
G03X927963Y345842I-1160J-1379D01*
G01X924563D01*
G03X923403Y345419I0J-1802D01*
G01X922856D01*
G03X923417Y346622I-1009J1203D01*
G03X920277I-1570J0D01*
G03X920838Y345419I1570J0D01*
G01X920631D01*
G03X919353Y345951I-1278J-1269D01*
G01X915953D01*
G03X914675Y345419I0J-1801D01*
G01X910458D01*
G02X910316Y345478I0J200D01*
G01X905413Y350381D01*
G02X905354Y350523I141J142D01*
G01Y353181D01*
G02X905410Y353319I200J-1D01*
G01X905493Y353405D01*
X905621Y353465D01*
G03Y357059I-138J1797D01*
G01X905493Y357119D01*
X905410Y357205D01*
G02X905354Y357343I144J139D01*
G01Y360302D01*
X905434Y360408D01*
X905499Y360426D01*
G03Y363890I-500J1732D01*
G01X905434Y363908D01*
X905354Y364014D01*
Y365028D01*
G02X905426Y365181I200J-1D01*
G01X905698Y365406D01*
X905784Y365428D01*
X905828Y365420D01*
G03X906161Y365389I333J1771D01*
G03Y368993I0J1802D01*
G03X905828Y368962I0J-1802D01*
G01X905784Y368954D01*
X905698Y368976D01*
X905426Y369201D01*
G02X905354Y369354I128J154D01*
G01Y370403D01*
G02X905433Y370562I200J0D01*
G01X905724Y370783D01*
X905816Y370801D01*
X905861Y370788D01*
G03X906344Y370722I483J1736D01*
G03Y374326I0J1802D01*
G03X905861Y374260I0J-1802D01*
G01X905816Y374247D01*
X905724Y374265D01*
X905433Y374486D01*
G02X905354Y374645I121J159D01*
G01Y378907D01*
G02X905413Y379049I200J0D01*
G01X907406Y381042D01*
G02X907548Y381101I142J-141D01*
G37*
G36*
G01X919982Y545094D02*
X923181D01*
G02X923323Y545035I0J-200D01*
G01X925509Y542849D01*
G02X925568Y542707I-141J-142D01*
G01Y531543D01*
Y530428D01*
X924438Y529298D01*
X906885D01*
X905899Y530284D01*
Y533378D01*
X908006Y535485D01*
Y544256D01*
G02X908065Y544398I200J0D01*
G01X908702Y545035D01*
G02X908844Y545094I142J-141D01*
G01X915640D01*
G02X915793Y545023I0J-200D01*
G01X916019Y544755D01*
X916042Y544671D01*
X916034Y544627D01*
G03X916009Y544325I1777J-299D01*
G03X919613I1802J0D01*
G03X919588Y544627I-1802J3D01*
G01X919580Y544671D01*
X919603Y544755D01*
X919829Y545023D01*
G02X919982Y545094I153J-129D01*
G37*
G36*
G01X903264Y565596D02*
X910134D01*
G02X910275Y565537I-1J-200D01*
G01X910390Y565422D01*
G02X910449Y565280I-141J-142D01*
G01Y559741D01*
X907759Y557051D01*
Y554810D01*
X907892Y554677D01*
X908449Y554120D01*
Y550446D01*
G02X908390Y550304I-200J0D01*
G01X907508Y549422D01*
G03X907449Y549280I141J-142D01*
G01Y545281D01*
G02X907390Y545140I-200J1D01*
G01X907063Y544812D01*
G03X907004Y544671I141J-142D01*
G01Y542462D01*
X906974Y542388D01*
X906949Y542363D01*
X903532D01*
G02X903390Y542422I0J200D01*
G01X903008Y542804D01*
G02X902949Y542946I141J142D01*
G01Y565280D01*
G02X903008Y565422I200J0D01*
G01X903123Y565537D01*
G02X903264Y565596I142J-141D01*
G37*
G36*
G01X906506Y605968D02*
X930801D01*
X930875Y605938D01*
X930903Y605909D01*
X931890Y604922D01*
G02X931949Y604780I-141J-142D01*
G01Y601321D01*
G02X931892Y601182I-200J1D01*
G01X931669Y600954D01*
X931598Y600923D01*
X931558Y600922D01*
G03X930092Y599420I36J-1502D01*
G03X931356Y597937I1502J0D01*
G02X931523Y597768I-31J-198D01*
G03X931903Y596804I2219J318D01*
G01X931920Y596779D01*
X931938Y596721D01*
Y596053D01*
X931920Y595995D01*
X931903Y595970D01*
G03X931512Y594919I1838J-1282D01*
G02X931352Y594744I-199J21D01*
G03X930145Y593271I295J-1473D01*
G03X930525Y592273I1502J0D01*
G01X930550Y592244D01*
X930576Y592173D01*
X930567Y591823D01*
X930537Y591753D01*
X930510Y591725D01*
G03X930076Y590669I1068J-1056D01*
G03X931340Y589186I1502J0D01*
G02X931507Y589017I-31J-198D01*
G03X931887Y588053I2219J318D01*
G01X931904Y588028D01*
X931922Y587970D01*
Y587302D01*
X931904Y587244D01*
X931887Y587219D01*
G03X931488Y586074I1838J-1283D01*
G02X931328Y585890I-200J12D01*
G03X930118Y584417I292J-1473D01*
G03X930623Y583294I1501J0D01*
G01X930656Y583265D01*
X930690Y583188D01*
X930691Y582802D01*
X930657Y582726D01*
X930625Y582697D01*
G03X930125Y581578I1002J-1119D01*
G03X933129I1502J0D01*
G03X932624Y582701I-1501J0D01*
G01X932591Y582730D01*
X932557Y582807D01*
X932556Y583193D01*
X932590Y583269D01*
X932622Y583298D01*
G03X932926Y583675I-1002J1119D01*
G02X933151Y583769I174J-99D01*
G03X933478Y583708I573J2167D01*
G01X933555Y583699D01*
X933656Y583586D01*
Y571180D01*
G02X933597Y571038I-200J0D01*
G01X933227Y570668D01*
X933199Y570640D01*
X933127Y570609D01*
X932768Y570606D01*
X932696Y570635D01*
X932667Y570662D01*
G03X931627Y571080I-1040J-1085D01*
G03X930254Y570187I0J-1502D01*
G01X930239Y570153D01*
X930008Y569922D01*
G02X929866Y569863I-142J141D01*
G01X926492D01*
X926418Y569893D01*
X926390Y569922D01*
X925008Y571304D01*
G02X924949Y571446I141J142D01*
G01Y579780D01*
G03X924890Y579922I-200J0D01*
G01X924832Y579980D01*
G02X924827Y580258I141J142D01*
G01X924836Y580267D01*
X924841Y580272D01*
G03X925401Y581578I-1243J1306D01*
G01Y581616D01*
G03X923599Y583380I-1802J-38D01*
G03X921797Y581578I0J-1802D01*
G01Y581563D01*
G02X921597Y581363I-200J0D01*
G01X913992D01*
X913918Y581393D01*
X913890Y581422D01*
X913586Y581726D01*
G02X913528Y581867I142J141D01*
G01Y590397D01*
G03X913469Y590538I-200J-1D01*
G01X913192Y590815D01*
G03X913187Y590820I-852J-847D01*
G02X913184Y590823I140J143D01*
G03X913175Y590833I-898J-799D01*
G01X911234Y592774D01*
X911214D01*
X911137Y592806D01*
G03X911061Y592821I-76J-185D01*
G01X905750D01*
X905676Y592851D01*
X905648Y592880D01*
X905442Y593086D01*
G02X905383Y593228I141J142D01*
G01Y604886D01*
X905413Y604960D01*
X905442Y604988D01*
X906364Y605909D01*
G02X906506Y605968I142J-141D01*
G37*
G36*
G01X911174Y834363D02*
X914438D01*
X914611Y834190D01*
Y829104D01*
G03X914577I-17J-1971D01*
G03Y825162I0J-1971D01*
G03X915101Y825233I0J1971D01*
G01X915246Y825109D01*
G02X915316Y824957I-130J-152D01*
G01Y817864D01*
X915286Y817791D01*
X915278Y817783D01*
Y816666D01*
G03X915337Y816524I200J0D01*
G01X916668Y815193D01*
G03X916810Y815134I142J141D01*
G01X919044D01*
G02X919186Y815075I0J-200D01*
G01X920018Y814243D01*
G02X920077Y814101I-141J-142D01*
G01Y810917D01*
G03X920136Y810775I200J0D01*
G01X920322Y810589D01*
X920347Y810547D01*
X920354Y810524D01*
G03X921349Y809529I1436J441D01*
G01X921372Y809522D01*
X921414Y809497D01*
X923768Y807143D01*
G02X923827Y807001I-141J-142D01*
G01Y800118D01*
G02X923768Y799976I-200J0D01*
G01X923544Y799752D01*
X923500Y799727D01*
X923474Y799719D01*
G03X922974Y799475I397J-1448D01*
G02X922854Y799435I-120J160D01*
G01X918960D01*
G02X918818Y799494I0J200D01*
G01X918486Y799826D01*
G02X918427Y799968I141J142D01*
G01Y803952D01*
G03X918368Y804094I-200J0D01*
G01X915127Y807335D01*
X915112Y807366D01*
G03X914701Y807777I-801J-390D01*
G01X914670Y807792D01*
X914087Y808375D01*
G03X913945Y808434I-142J-141D01*
G01X910012D01*
G02X909870Y808493I0J200D01*
G01X908593Y809770D01*
G02X908534Y809911I141J142D01*
G01Y814408D01*
X908565Y814482D01*
X908566Y814483D01*
X910232D01*
G03X910374Y814542I0J200D01*
G01X910643Y814811D01*
G03X910702Y814953I-141J142D01*
G01Y815956D01*
X910902Y816156D01*
Y817127D01*
G03X910739Y817640I-890J-1D01*
G01X910720Y817665D01*
X910702Y817724D01*
Y818850D01*
G03X910643Y818992I-200J0D01*
G01X910629Y819006D01*
X910604Y819048D01*
X910597Y819071D01*
G03X910290Y819577I-1180J-370D01*
G01X909262Y820606D01*
G02X909203Y820748I141J142D01*
G01Y829122D01*
X909214Y829167D01*
X909225Y829188D01*
G03X909383Y829764I-1341J677D01*
G01X909385Y829801D01*
X909414Y829865D01*
X910647Y831098D01*
G03X910706Y831240I-141J142D01*
G01Y833895D01*
G02X910765Y834037I200J0D01*
G01X911032Y834304D01*
G02X911174Y834363I142J-141D01*
G37*
G36*
G01X906024Y839834D02*
X907131D01*
G02X907273Y839775I0J-200D01*
G01X907646Y839402D01*
G02X907705Y839260I-141J-142D01*
G01Y837224D01*
X907702Y837221D01*
Y836528D01*
X907705Y836525D01*
Y836501D01*
G03X907764Y836359I200J0D01*
G01X908718Y835405D01*
G02X908777Y835263I-141J-142D01*
G01Y831447D01*
G02X908718Y831305I-200J0D01*
G01X908656Y831243D01*
X908536Y831220D01*
X908479Y831245D01*
G03X907884Y831368I-595J-1378D01*
G03X907201Y831204I-1J-1502D01*
G01X907180Y831193D01*
X907134Y831182D01*
X905698D01*
G02X905556Y831241I0J200D01*
G01X905455Y831342D01*
G02X905396Y831484I141J142D01*
G01Y839206D01*
G02X905455Y839348I200J0D01*
G01X905882Y839775D01*
G02X906024Y839834I142J-141D01*
G37*
G36*
G01X911084Y851063D02*
X911098D01*
X911441Y851060D01*
G02X911543Y851031I-2J-200D01*
G01X911591Y851002D01*
X911605Y850975D01*
G03X912864Y850190I1259J617D01*
G03X912872I4J1402D01*
G01X912899D01*
G03X913139Y850216I-31J1402D01*
G01X913148Y850218D01*
X913180Y850221D01*
X913186Y850222D01*
G02X913327Y850164I0J-200D01*
G01X913628Y849863D01*
G02X913681Y849762I-143J-140D01*
G01Y849760D01*
G02X913685Y849723I-196J-40D01*
G01Y848894D01*
G02X913663Y848803I-200J0D01*
G02X913629Y848756I-177J92D01*
G01X912974Y848101D01*
G03X912958Y848084I867J-832D01*
G01X912681Y847807D01*
G03X912622Y847665I141J-142D01*
G01Y847645D01*
G02X912606Y847567I-200J0D01*
G01X912591Y847531D01*
X912576Y847516D01*
X912307Y847340D01*
X912112Y847214D01*
Y846520D01*
X912469Y846290D01*
X912528D01*
X912563Y846255D01*
G02X912582Y846233I-141J-141D01*
G02X912622Y846113I-160J-120D01*
G01Y845936D01*
G03X912681Y845794I200J0D01*
G01X913367Y845109D01*
X913467Y845008D01*
X913469Y845006D01*
G03X913498Y844977I864J835D01*
G01X913501Y844975D01*
X913631Y844845D01*
G02X913684Y844727I-146J-137D01*
G02X913685Y844708I-199J-20D01*
G01Y839921D01*
G02X913676Y839860I-200J-2D01*
G01X913659Y839808D01*
G02X913631Y839752I-191J60D01*
G03X913293Y838700I1464J-1051D01*
G03Y838698I1802J-1D01*
G01Y838675D01*
G03X913374Y838166I1802J26D01*
G01X913383Y838137D01*
X913384Y838085D01*
X913377Y838058D01*
G02X913325Y837966I-194J49D01*
G01X911780Y836421D01*
G02X911730Y836385I-140J142D01*
G02X911639Y836363I-91J178D01*
G01X909551D01*
G02X909460Y836385I0J200D01*
G02X909410Y836421I90J178D01*
G01X909265Y836566D01*
G02X909208Y836683I141J141D01*
G01Y837222D01*
X909117Y837280D01*
X909116Y837281D01*
X909023Y837341D01*
X908972Y837374D01*
X908922Y837406D01*
G02X908854Y837520I128J154D01*
G02X908850Y837560I196J40D01*
G01Y840787D01*
G03X908791Y840929I-200J0D01*
G01X907957Y841763D01*
G02X907908Y841843I141J142D01*
G01X907894Y841888D01*
X907901Y841935D01*
G03X907917Y842142I-1336J207D01*
G01Y842154D01*
G03X906565Y843495I-1352J-11D01*
G03X905482Y842953I0J-1353D01*
G01X905473Y842942D01*
X905430Y842908D01*
X905388Y842875D01*
X905371Y842867D01*
G03X905221Y842793I471J-1143D01*
G03X904995Y842624I622J-1068D01*
G02X904875Y842579I-127J155D01*
G01X901662D01*
G02X901607Y842587I1J200D01*
G01X901504Y842690D01*
X901489Y842722D01*
Y842723D01*
G03X901127Y843186I-1221J-581D01*
G03X900899Y843338I-860J-1043D01*
G01X900895Y843353D01*
G02X900889Y843400I194J49D01*
G01Y844036D01*
G02X900896Y844086I200J-2D01*
G01X900899Y844098D01*
G03X901334Y844463I-632J1195D01*
G01X901392Y844537D01*
G02X901424Y844540I35J-197D01*
G01X901493D01*
X901494Y844538D01*
X902188D01*
X902209Y844570D01*
G02X902262Y844578I56J-192D01*
G01X904570D01*
X904609Y844561D01*
X904614Y844558D01*
X904615D01*
G03X904633Y844550I90J178D01*
G01X904642Y844536D01*
X905343D01*
X905500Y844459D01*
G03X907686Y844536I1065J835D01*
G02X907697Y844538I41J-196D01*
G01X908378D01*
X908487D01*
X908543Y844625D01*
G03X908546Y844630I-170J105D01*
G01X908718Y844896D01*
Y844954D01*
X908754Y844991D01*
G02X908776Y845010I141J-141D01*
G02X908896Y845050I120J-160D01*
G01X909018D01*
G03X909160Y845109I0J200D01*
G01X909937Y845886D01*
G03X909996Y846028I-141J142D01*
G01Y847020D01*
G02X910024Y847121I200J-1D01*
G01X910134Y847157D01*
G03Y849727I-420J1285D01*
G01X910024Y849763D01*
G02X909996Y849864I172J102D01*
G01Y850170D01*
G02X910024Y850271I200J-1D01*
G01X910134Y850307D01*
G03X910902Y850946I-420J1285D01*
G01X910909Y850957D01*
X911084Y851063D01*
G37*
G36*
G01X981220Y1142054D02*
X997232D01*
G02X997374Y1141995I0J-200D01*
G01X1001532Y1137837D01*
G02X1001591Y1137695I-141J-142D01*
G01Y1125606D01*
G02X1001575Y1125528I-200J0D01*
G01X990507Y1099324D01*
G02X990404Y1099219I-184J78D01*
G01X990118Y1099092D01*
X990044Y1099089D01*
X990007Y1099101D01*
G03X989513Y1099185I-495J-1418D01*
G03X988011Y1097683I0J-1502D01*
G03X988840Y1096340I1502J0D01*
G01X988875Y1096323D01*
X988925Y1096267D01*
X989033Y1095974D01*
G02X989030Y1095827I-187J-70D01*
G01X982858Y1081216D01*
G02X982672Y1081093I-185J77D01*
G01X982242Y1081097D01*
X982141Y1081165D01*
X982119Y1081221D01*
G03X980726Y1082161I-1393J-562D01*
G03Y1079157I0J-1502D01*
G03X981294Y1079268I1J1502D01*
G01X981350Y1079291D01*
X981469Y1079267D01*
X981772Y1078961D01*
G02X981813Y1078743I-143J-140D01*
G01X981566Y1078156D01*
X981431Y1078090D01*
X981359Y1078110D01*
G03X980969Y1078161I-388J-1451D01*
G03X979467Y1076659I0J-1502D01*
G03X980201Y1075368I1502J0D01*
G01X980266Y1075330D01*
X980312Y1075188D01*
X970809Y1052689D01*
G03X970793Y1052611I184J-78D01*
G01Y1011668D01*
G02X970734Y1011526I-200J0D01*
G01X963931Y1004723D01*
G02X963789Y1004664I-142J141D01*
G01X912835D01*
G02X912693Y1004723I0J200D01*
G01X911568Y1005848D01*
G02X911509Y1005990I141J142D01*
G01Y1008407D01*
X911510Y1008415D01*
G03X911514Y1008536I-1497J110D01*
G03X911510Y1008657I-1501J11D01*
G01X911509Y1008665D01*
Y1069193D01*
G02X911568Y1069335I200J0D01*
G01X912904Y1070671D01*
G02X913046Y1070730I142J-141D01*
G01X916631D01*
G03X916708Y1070745I1J200D01*
G01X916776Y1070774D01*
G02X916853Y1070789I76J-185D01*
G01X928704D01*
G02X928724Y1070788I0J-200D01*
G01X929114Y1070398D01*
Y1031468D01*
G03X929115Y1031438I1201J25D01*
G01Y1029358D01*
G03X929174Y1029216I200J0D01*
G01X930313Y1028077D01*
G03X930455Y1028018I142J141D01*
G01X955798D01*
G03X955940Y1028077I0J200D01*
G01X957897Y1030034D01*
G03X957956Y1030176I-141J142D01*
G01Y1079237D01*
G02X958139Y1079436I200J0D01*
G03Y1083026I-158J1795D01*
G02X957956Y1083225I17J199D01*
G01Y1100356D01*
G02X958015Y1100498I200J0D01*
G01X965601Y1108084D01*
G03X965660Y1108226I-141J142D01*
G01Y1110783D01*
G02X965719Y1110925I200J0D01*
G01X966612Y1111818D01*
G02X966754Y1111877I142J-141D01*
G01X976465D01*
G03X976607Y1111936I0J200D01*
G01X978667Y1113996D01*
G03X978726Y1114138I-141J142D01*
G01Y1139560D01*
G02X978785Y1139702I200J0D01*
G01X981078Y1141995D01*
G02X981220Y1142054I142J-141D01*
G37*
G36*
G01X915135Y1442486D02*
X915186D01*
X916000Y1441672D01*
G02X916059Y1441530I-141J-142D01*
G01Y1425928D01*
G02X916000Y1425786I-200J0D01*
G01X915368Y1425154D01*
G02X915226Y1425095I-142J141D01*
G01X899918D01*
G02X899776Y1425154I0J200D01*
G01X899010Y1425920D01*
G02X898951Y1426062I141J142D01*
G01Y1441812D01*
G02X899010Y1441954I200J0D01*
G01X899162Y1442106D01*
G02X899303Y1442164I141J-142D01*
G01X914731D01*
G03X914872Y1442223I-1J200D01*
G01X915135Y1442486D01*
G37*
G36*
G01X914338Y580362D02*
X921261D01*
G02X921389Y580303I-14J-200D01*
G01X923390Y578302D01*
G02X923449Y578160I-141J-142D01*
G01Y572035D01*
G03X923508Y571893I200J0D01*
G01X923881Y571520D01*
G02X923940Y571378I-141J-142D01*
G01Y571256D01*
G02X923740Y571056I-200J0D01*
G01X923723D01*
X923706Y571058D01*
G03X923453Y571080I-256J-1480D01*
G03Y568076I0J-1502D01*
G03X924649Y568670I0J1501D01*
G01X924676Y568705D01*
X924751Y568746D01*
X925096Y568769D01*
G02X925251Y568711I14J-199D01*
G01X925265Y568697D01*
X925338Y568667D01*
X928118D01*
G02X928260Y568608I0J-200D01*
G01X928612Y568256D01*
G02X928671Y568114I-141J-142D01*
G01Y566425D01*
G02X928612Y566283I-200J0D01*
G01X927875Y565546D01*
G02X927733Y565487I-142J141D01*
G01X922391D01*
G03X922249Y565428I0J-200D01*
G01X919410D01*
G02X919268Y565487I0J200D01*
G01X918575Y566180D01*
X918546Y566208D01*
X918516Y566282D01*
Y567193D01*
G02X918575Y567335I200J0D01*
G01X918608Y567368D01*
G03X918667Y567510I-141J142D01*
G01Y568760D01*
G03X918608Y568902I-200J0D01*
G01X918173Y569337D01*
G03X918031Y569396I-142J-141D01*
G01X914217D01*
G02X914075Y569455I0J200D01*
G01X913645Y569885D01*
G02X913586Y570027I141J142D01*
G01Y571409D01*
G03X913571Y571485I-200J0D01*
G01X913543Y571552D01*
G02X913528Y571629I185J76D01*
G01Y579551D01*
G02X913587Y579693I200J0D01*
G01X914197Y580303D01*
G02X914338Y580362I142J-141D01*
G37*
G36*
G01X928949Y612780D02*
Y608446D01*
G02X928890Y608304I-200J0D01*
G01X928508Y607922D01*
G02X928366Y607863I-142J141D01*
G01X919032D01*
G02X918890Y607922I0J200D01*
G01X918508Y608304D01*
G02X918449Y608446I141J142D01*
G01Y612780D01*
G02X918508Y612922I200J0D01*
G01X918890Y613304D01*
G02X919032Y613363I142J-141D01*
G01X928366D01*
G02X928508Y613304I0J-200D01*
G01X928890Y612922D01*
G02X928949Y612780I-141J-142D01*
G37*
G36*
G01X915696Y849323D02*
X916236D01*
G02X916378Y849264I0J-200D01*
G01X918353Y847289D01*
G02X918412Y847148I-141J-142D01*
G01Y846625D01*
G02X918328Y846462I-200J0D01*
G03X917839Y845851I835J-1169D01*
G01X917824Y845815D01*
X917724Y845715D01*
X917696Y845686D01*
X917622Y845656D01*
X917398D01*
X917297Y845725D01*
X917274Y845783D01*
G03X916014Y846645I-1260J-490D01*
G03X914719Y845680I0J-1351D01*
G01X914683Y845656D01*
X914320D01*
X914278D01*
X914205Y845686D01*
X914134Y845757D01*
X914119Y845795D01*
G03X913699Y846356I-1255J-502D01*
G02X913623Y846513I124J157D01*
G01Y847222D01*
G02X913699Y847379I200J0D01*
G03X913991Y847696I-836J1063D01*
G02X914017Y847727I166J-112D01*
G01X915554Y849264D01*
G02X915696Y849323I142J-141D01*
G37*
G36*
G01X930865Y859373D02*
X931795D01*
G02X931936Y859314I-1J-200D01*
G01X933889Y857362D01*
G03X934031Y857303I142J141D01*
G01X934409D01*
G02X934551Y857244I0J-200D01*
G01X935458Y856337D01*
G02X935517Y856195I-141J-142D01*
G01Y855785D01*
G02X935458Y855643I-200J0D01*
G01X935438Y855623D01*
X935365Y855593D01*
X924219D01*
G02X924078Y855652I1J200D01*
G01X923420Y856309D01*
G02X923361Y856448I141J142D01*
G01X923356Y856766D01*
X923383Y856837D01*
X923410Y856866D01*
G03X923521Y857000I-1099J1023D01*
G02X923541Y857023I161J-120D01*
G01X923721Y857203D01*
G02X923882Y857260I141J-142D01*
G01X924236Y857225D01*
X924311Y857180D01*
X924337Y857142D01*
G03X925462Y856539I1125J748D01*
G03X926814Y857891I0J1352D01*
G03X926692Y858452I-1351J0D01*
G01X926671Y858499D01*
X926678Y858600D01*
X926888Y858926D01*
G02X927056Y859018I168J-108D01*
G01X929793D01*
X929830D01*
G02X929834Y859019I49J-188D01*
G03X930742Y859331I-8J1501D01*
G01X930768Y859351D01*
X930800Y859362D01*
G02X930865Y859373I65J-189D01*
G37*
G36*
G01X921221Y855594D02*
X922636D01*
G02X922756Y855554I0J-200D01*
G02X922772Y855541I-118J-162D01*
G01X923110Y855203D01*
G02X923112Y855201I-140J-142D01*
G02X923169Y855061I-143J-140D01*
G01Y854334D01*
G03X923228Y854192I200J0D01*
G01X923404Y854016D01*
G03X923546Y853957I142J141D01*
G01X924008D01*
G03X924084Y853972I0J200D01*
G01X924121Y853988D01*
X924236D01*
X924290Y854073D01*
G03X924295Y854080I-160J120D01*
G01X924308Y854101D01*
X924310Y854104D01*
X926552D01*
G02X926694Y854045I0J-200D01*
G01X926819Y853920D01*
G03X926961Y853861I142J141D01*
G01X936964D01*
G02X937106Y853802I0J-200D01*
G01X938091Y852817D01*
G02X938093Y852815I-140J-142D01*
G02X938150Y852675I-143J-140D01*
G01Y848224D01*
G02X938091Y848082I-200J0D01*
G01X937954Y847945D01*
X937926Y847916D01*
X937852Y847886D01*
X931465D01*
G02X931314Y847955I0J200D01*
G03X928820I-1247J-1088D01*
G02X928669Y847886I-151J131D01*
G01X927538D01*
G02X927396Y847945I0J200D01*
G01X925663Y849678D01*
G02X925611Y849868I142J141D01*
G01X925695Y850198D01*
X925770Y850274D01*
X925822Y850289D01*
G03X926814Y851592I-360J1303D01*
G03X924110I-1352J0D01*
G01Y851590D01*
G03X924143Y851294I1352J1D01*
G01X924148Y851272D01*
Y851250D01*
G02X923948Y851050I-200J0D01*
G01X923827D01*
G02X923627Y851250I0J200D01*
G01Y851272D01*
X923632Y851294D01*
G03X923665Y851590I-1319J297D01*
G01Y851592D01*
G03X922519Y852928I-1352J0D01*
G01X922486Y852933D01*
X922430Y852962D01*
X922060Y853332D01*
Y853632D01*
G03X922002Y853772I-200J-1D01*
G01X921345Y854429D01*
G03X921204Y854488I-142J-141D01*
G01X920811D01*
G02X920611Y854688I0J200D01*
G01Y854984D01*
G02X920668Y855124I200J0D01*
G01X921079Y855535D01*
G02X921081Y855537I142J-140D01*
G02X921221Y855594I140J-143D01*
G37*
G36*
G01X917302Y854003D02*
X917806D01*
G02X917948Y853944I0J-200D01*
G01X918353Y853539D01*
G02X918412Y853398I-141J-142D01*
G01Y853001D01*
G02X918353Y852860I-200J1D01*
G01X917569Y852076D01*
G03X917510Y851934I141J-142D01*
G01Y851022D01*
G02X917451Y850880I-200J0D01*
G01X917284Y850713D01*
G02X917142Y850654I-142J141D01*
G01X914528D01*
G02X914386Y850713I0J200D01*
G01X914362Y850737D01*
X914332Y850810D01*
Y852027D01*
G03X914273Y852169I-200J0D01*
G01X913677Y852765D01*
G02X913618Y852907I141J142D01*
G01Y853537D01*
G02X913637Y853623I200J1D01*
G01X913644Y853638D01*
G03X913940Y853924I-780J1104D01*
G02X914100Y854003I159J-121D01*
G01X914667D01*
G02X914809Y853944I0J-200D01*
G01X915307Y853446D01*
X915312D01*
X915342Y853416D01*
G03X915484Y853357I142J141D01*
G01X916490D01*
G03X916632Y853416I0J200D01*
G01X917160Y853944D01*
G02X917302Y854003I142J-141D01*
G37*
G36*
G01X948869Y1084041D02*
X956422Y1076488D01*
G02X956481Y1076346I-141J-142D01*
G01Y1031106D01*
G02X956422Y1030964I-200J0D01*
G01X955819Y1030361D01*
G02X955677Y1030302I-142J141D01*
G01X931284D01*
G02X931142Y1030361I0J200D01*
G01X930175Y1031328D01*
G02X930116Y1031469I141J142D01*
G01Y1070793D01*
G03X930115Y1070813I-200J0D01*
G01X928810Y1072118D01*
X925884D01*
X925164Y1072838D01*
Y1075764D01*
Y1085406D01*
X925268Y1085510D01*
Y1086649D01*
X922572Y1089345D01*
Y1095116D01*
X923972Y1096516D01*
X947733D01*
X947757Y1096492D01*
X951974D01*
X952296Y1096170D01*
Y1092845D01*
X948869Y1089418D01*
Y1084041D01*
G37*
G36*
G01X929962Y1153971D02*
X931709Y1155718D01*
G02X931851Y1155777I142J-141D01*
G01X962769D01*
G02X962911Y1155718I0J-200D01*
G01X963115Y1155514D01*
G02X963174Y1155372I-141J-142D01*
G01Y1108466D01*
G02X963115Y1108324I-200J0D01*
G01X961265Y1106474D01*
G02X961123Y1106415I-142J141D01*
G01X922144D01*
G02X922002Y1106474I0J200D01*
G01X920936Y1107540D01*
G02X920877Y1107682I141J142D01*
G01Y1117435D01*
G02X920936Y1117577I200J0D01*
G01X921268Y1117909D01*
G02X921410Y1117968I142J-141D01*
G01X929502D01*
G03X929644Y1118027I0J200D01*
G01X929844Y1118227D01*
G03X929903Y1118369I-141J142D01*
G01Y1153829D01*
G02X929962Y1153971I200J0D01*
G37*
G36*
G01X939256Y188812D02*
X950464D01*
X951436Y187840D01*
Y181166D01*
X949882Y179612D01*
X938737D01*
X938025Y180324D01*
Y187581D01*
X939256Y188812D01*
G37*
G36*
G01X940483Y371800D02*
X954032D01*
G02X954174Y371741I0J-200D01*
G01X957341Y368574D01*
G02X957400Y368432I-141J-142D01*
G01Y363284D01*
X957391Y363254D01*
G03X957321Y362802I1432J-453D01*
G03X957391Y362350I1502J1D01*
G01X957400Y362320D01*
Y356122D01*
G02X957341Y355980I-200J0D01*
G01X955917Y354556D01*
G02X955775Y354497I-142J141D01*
G01X940116D01*
G02X939974Y354556I0J200D01*
G01X939561Y354969D01*
G02X939502Y355111I141J142D01*
G01Y360998D01*
G02X939561Y361139I200J-1D01*
G03X940001Y362202I-1062J1062D01*
G03X939561Y363265I-1502J1D01*
G02X939502Y363406I141J142D01*
G01Y370819D01*
G02X939561Y370961I200J0D01*
G01X940341Y371741D01*
G02X940483Y371800I142J-141D01*
G37*
G36*
G01X940548Y809474D02*
X943017D01*
G02X943163Y809411I0J-200D01*
G01X943390Y809170D01*
X943418Y809094D01*
X943416Y809052D01*
G03X943414Y808965I1500J-78D01*
G03X944916Y807463I1502J0D01*
G03X945761Y807724I-1J1502D01*
G01X945808Y807755D01*
X945918Y807761D01*
X946280Y807570D01*
G02X946386Y807393I-94J-176D01*
G01Y801598D01*
G03X946913Y800148I2262J1D01*
G01X946969Y800081D01*
G03X947105Y799932I1737J1448D01*
G01X947955Y799081D01*
G02X948014Y798940I-141J-142D01*
G01Y796938D01*
G02X947993Y796849I-200J0D01*
G03X947807Y796051I1616J-797D01*
G03X947993Y795253I1802J-1D01*
G02X948014Y795164I-179J-89D01*
G01Y788902D01*
G02X947955Y788760I-200J0D01*
G01X947414Y788219D01*
X947386Y788190D01*
X947312Y788160D01*
X947140D01*
X947131Y788161D01*
G03X946970Y788168I-159J-1795D01*
G03X946809Y788161I-2J-1802D01*
G01X946800Y788160D01*
X944434D01*
G02X944268Y788249I0J200D01*
G01X944055Y788567D01*
X944045Y788666D01*
X944064Y788713D01*
G03X944178Y789286I-1388J574D01*
G03X941174I-1502J0D01*
G03X941288Y788713I1502J1D01*
G01X941307Y788666D01*
X941297Y788567D01*
X941084Y788249D01*
G02X940918Y788160I-166J111D01*
G01X935407D01*
G02X935265Y788219I0J200D01*
G01X934459Y789025D01*
X934430Y789053D01*
X934400Y789127D01*
Y796865D01*
G02X934460Y797008I200J0D01*
G03Y799586I-1258J1289D01*
G02X934400Y799729I140J143D01*
G01Y807157D01*
G02X934459Y807299I200J0D01*
G01X934496Y807336D01*
G02X934637Y807394I141J-142D01*
G01X937240D01*
G02X937352Y807360I1J-200D01*
G03X938357Y807054I1005J1497D01*
G03X940159Y808856I0J1802D01*
G03X940150Y809034I-1802J-2D01*
G01X940146Y809077D01*
X940172Y809157D01*
X940400Y809408D01*
G02X940548Y809474I148J-134D01*
G37*
G36*
G01X938441Y821655D02*
X946188D01*
G02X946388Y821455I0J-200D01*
G01Y817740D01*
G02X946188Y817540I-200J0D01*
G01X938206D01*
G02X938064Y817599I0J200D01*
G01X937547Y818116D01*
G02X937488Y818258I141J142D01*
G01Y820702D01*
G02X937547Y820844I200J0D01*
G01X938299Y821596D01*
G02X938441Y821655I142J-141D01*
G37*
G36*
G01X932365Y828917D02*
X936235D01*
G02X936377Y828858I0J-200D01*
G01X938217Y827018D01*
G03X938359Y826959I142J141D01*
G01X940936D01*
G02X941078Y826900I0J-200D01*
G01X941161Y826817D01*
G02X941220Y826675I-141J-142D01*
G01Y824148D01*
G02X941161Y824006I-200J0D01*
G01X940894Y823739D01*
G02X940752Y823680I-142J141D01*
G01X936934D01*
G03X936792Y823621I0J-200D01*
G01X933766Y820595D01*
G02X933624Y820536I-142J141D01*
G01X930649D01*
X930247Y820938D01*
Y826620D01*
G02X930370Y826683I147J-135D01*
G03X931965Y828473I-207J1790D01*
G01Y828509D01*
X931964Y828550D01*
X931993Y828624D01*
X932222Y828857D01*
G02X932365Y828917I143J-140D01*
G37*
G36*
G01X940598Y855063D02*
X943221D01*
X943336Y854954D01*
X943340Y854874D01*
G03X944840Y853455I1500J83D01*
G01X944843D01*
G03X945060Y853471I-2J1502D01*
G01X945104Y853478D01*
X945186Y853454D01*
X945449Y853227D01*
G02X945518Y853075I-131J-151D01*
G01Y850124D01*
G03X945200Y849200I1182J-924D01*
G03X945518Y848276I1500J0D01*
G01Y838935D01*
G02X945459Y838793I-200J0D01*
G01X944524Y837858D01*
G02X944382Y837799I-142J141D01*
G01X940900D01*
G02X940758Y837858I0J200D01*
G01X939772Y838844D01*
G02X939713Y838986I141J142D01*
G01Y854178D01*
G02X939772Y854320I200J0D01*
G01X940456Y855004D01*
G02X940598Y855063I142J-141D01*
G37*
G36*
G01X931026Y845494D02*
X937640D01*
G02X937782Y845435I0J-200D01*
G01X938114Y845103D01*
G02X938173Y844961I-141J-142D01*
G01Y842305D01*
G03X937200Y842628I-973J-1304D01*
G03X935572Y841000I0J-1628D01*
G03X936460Y839550I1628J0D01*
G01X935443D01*
X935432Y839539D01*
X931124D01*
G02X931018Y839570I1J200D01*
G03X930899Y839636I-738J-1191D01*
G01X930870Y839651D01*
X928999Y841522D01*
G02X928940Y841664I141J142D01*
G01Y844475D01*
G02X928999Y844617I200J0D01*
G01X929632Y845250D01*
G03X930067Y845192I437J1617D01*
G03X931026Y845494I0J1674D01*
G37*
G36*
G01X933534Y862023D02*
X945211D01*
G02X945353Y861964I0J-200D01*
G01X945865Y861452D01*
G02X945924Y861310I-141J-142D01*
G01Y857241D01*
X945894Y857167D01*
X945865Y857139D01*
X945227Y856500D01*
G02X945147Y856451I-142J141D01*
G01X945103Y856437D01*
X945056Y856443D01*
X945054D01*
G03X944840Y856459I-219J-1486D01*
G03X944123Y856276I1J-1502D01*
G02X944027Y856252I-95J176D01*
G01X936963D01*
G02X936821Y856311I0J200D01*
G01X932463Y860669D01*
G02X932404Y860811I141J142D01*
G01Y860893D01*
G02X932463Y861034I200J-1D01*
G01X933393Y861964D01*
G02X933534Y862023I142J-141D01*
G37*
G36*
G01X944222Y880100D02*
Y876371D01*
X944053Y876202D01*
X940642D01*
G02X940500Y876143I-142J141D01*
G01X938060D01*
G02X937919Y876202I1J200D01*
G01X937830Y876290D01*
G03X937689Y876348I-141J-142D01*
G01X931855D01*
X931479D01*
X930482Y877345D01*
X930444Y877383D01*
Y881557D01*
X930541Y881654D01*
X930777D01*
X932455D01*
X933216Y880893D01*
X933515Y880594D01*
X933909Y880200D01*
X944122D01*
X944222Y880100D01*
G37*
G36*
G01X931250Y875347D02*
X937274D01*
G02X937416Y875288I0J-200D01*
G01X937440Y875264D01*
G03X937175Y874396I1289J-868D01*
G03X940283I1554J0D01*
G03X940211Y874865I-1554J1D01*
G01X943847D01*
X944417Y874295D01*
Y870567D01*
X944223Y870373D01*
X941130D01*
X940817Y870060D01*
Y869754D01*
G02X940617Y869554I-200J0D01*
G01X940524D01*
G03X939462Y869115I-1J-1501D01*
G01X938765Y868417D01*
G02X938623Y868358I-142J141D01*
G01X932328D01*
G03X931385Y868024I1J-1501D01*
G01X931358Y868002D01*
X931294Y867979D01*
X931030D01*
G02X930888Y868038I0J200D01*
G01X930471Y868455D01*
G02X930412Y868597I141J142D01*
G01Y874509D01*
G02X930471Y874651I200J0D01*
G01X931108Y875288D01*
G02X931250Y875347I142J-141D01*
G37*
G36*
G01X941438Y1310181D02*
G03I-590J0D01*
G37*
G36*
G01X934841Y1441273D02*
X1047232D01*
G02X1047374Y1441214I0J-200D01*
G01X1048453Y1440135D01*
G02X1048512Y1439993I-141J-142D01*
G01Y1438497D01*
G03X1048571Y1438355I200J0D01*
G01X1049132Y1437794D01*
X1049160Y1437738D01*
X1049165Y1437707D01*
G03X1050944Y1436195I1779J291D01*
G03X1051346Y1436240I2J1802D01*
G01X1051368Y1436246D01*
X1053367D01*
G03X1054605Y1436759I0J1750D01*
G01X1054671Y1436824D01*
G02X1054812Y1436882I141J-142D01*
G01X1054849D01*
G03X1055521Y1436748I672J1618D01*
G03X1056230Y1436898I0J1751D01*
G01X1056269Y1436916D01*
X1056770D01*
Y1436928D01*
X1058198D01*
Y1436916D01*
X1058366D01*
X1058420Y1436901D01*
X1058444Y1436886D01*
G03X1059448Y1436600I1003J1615D01*
G03X1060452Y1436886I1J1901D01*
G01X1060476Y1436901D01*
X1060530Y1436916D01*
X1060707D01*
G02X1060848Y1436858I0J-200D01*
G01X1061916Y1435790D01*
G02X1061975Y1435648I-141J-142D01*
G01Y1425111D01*
G02X1061916Y1424969I-200J0D01*
G01X1042103Y1405156D01*
G02X1041961Y1405097I-142J141D01*
G01X993808D01*
G02X993666Y1405156I0J200D01*
G01X982440Y1416382D01*
G03X982298Y1416441I-142J-141D01*
G01X963100D01*
G02X962958Y1416500I0J200D01*
G01X959002Y1420456D01*
G03X958860Y1420515I-142J-141D01*
G01X935298D01*
G02X935156Y1420574I0J200D01*
G01X933143Y1422587D01*
G02X933084Y1422729I141J142D01*
G01Y1439516D01*
G02X933143Y1439658I200J0D01*
G01X934699Y1441214D01*
G02X934841Y1441273I142J-141D01*
G37*
G36*
G01X953995Y1480218D02*
Y1451739D01*
G02X953936Y1451597I-200J0D01*
G01X953385Y1451046D01*
G02X953243Y1450987I-142J141D01*
G01X930042D01*
G02X929900Y1451046I0J200D01*
G01X929535Y1451411D01*
G02X929476Y1451553I141J142D01*
G01Y1480717D01*
G02X929535Y1480859I200J0D01*
G01X930754Y1482078D01*
G02X930896Y1482137I142J-141D01*
G01X952076D01*
G02X952218Y1482078I0J-200D01*
G01X953936Y1480360D01*
G02X953995Y1480218I-141J-142D01*
G37*
G36*
G01X1082583Y1640789D02*
X1112196D01*
G02X1112338Y1640730I0J-200D01*
G01X1114474Y1638594D01*
G02X1114533Y1638452I-141J-142D01*
G01Y1541829D01*
G02X1114474Y1541687I-200J0D01*
G01X1112830Y1540043D01*
G02X1112688Y1539984I-142J141D01*
G01X1108902D01*
G02X1108702Y1540184I0J200D01*
G01Y1565918D01*
G03X1108262Y1566980I-1502J0D01*
G01X1105100Y1570142D01*
G03X1104038Y1570582I-1062J-1062D01*
G01X1092326D01*
G03X1091264Y1570142I0J-1502D01*
G01X1083048Y1561926D01*
G03X1082608Y1560864I1062J-1062D01*
G01Y1552895D01*
G02X1082485Y1552710I-200J0D01*
G01X1082428Y1552687D01*
X1082311Y1552710D01*
X1065511Y1569510D01*
G03X1065369Y1569569I-142J-141D01*
G01X1048406D01*
G03X1048264Y1569510I0J-200D01*
G01X1025702Y1546948D01*
G02X1025560Y1546889I-142J141D01*
G01X1004660D01*
G02X1004518Y1546948I0J200D01*
G01X1002426Y1549040D01*
G02X1002367Y1549182I141J142D01*
G01Y1567409D01*
G03X1002308Y1567551I-200J0D01*
G01X997473Y1572386D01*
G03X997331Y1572445I-142J-141D01*
G01X973413D01*
G02X973271Y1572504I0J200D01*
G01X962344Y1583431D01*
G03X962202Y1583490I-142J-141D01*
G01X951547D01*
G02X951405Y1583549I0J200D01*
G01X944425Y1590529D01*
G02X944366Y1590671I141J142D01*
G01Y1628715D01*
G02X944425Y1628857I200J0D01*
G01X947991Y1632423D01*
G02X948133Y1632482I142J-141D01*
G01X1037599D01*
G02X1037741Y1632423I0J-200D01*
G01X1074051D01*
G03X1074193Y1632482I0J200D01*
G01X1082441Y1640730D01*
G02X1082583Y1640789I142J-141D01*
G37*
G36*
G01X996733Y174223D02*
X1000330D01*
G02X1000470Y174166I0J-200D01*
G01X1000471Y174165D01*
X1002673Y171963D01*
G02X1002675Y171961I-140J-142D01*
G02X1002732Y171821I-143J-140D01*
G01Y147970D01*
G02X1002710Y147879I-200J0D01*
G02X1002620Y147791I-178J92D01*
G01X1002247Y147607D01*
X1002134Y147618D01*
X1002089Y147653D01*
G03X1001175Y147963I-914J-1192D01*
G03Y144959I0J-1502D01*
G03X1002089Y145269I0J1502D01*
G01X1002134Y145303D01*
X1002248Y145315D01*
X1002620Y145131D01*
G02X1002710Y145043I-88J-180D01*
G01X1002732Y145000D01*
Y138235D01*
X1002657Y138131D01*
X1002596Y138110D01*
G03X1001874Y137588I479J-1423D01*
G01X1001853Y137560D01*
X1001765Y137501D01*
G02X1001698Y137473I-109J168D01*
G01X1001579Y137446D01*
X1001505Y137457D01*
X1001472Y137475D01*
G03X1001171Y137612I-894J-1565D01*
G03X1000580Y137712I-592J-1703D01*
G03X999989Y137612I1J-1803D01*
G03X999688Y137475I593J-1702D01*
G01X999655Y137457D01*
X999581Y137446D01*
X999462Y137473D01*
G02X999395Y137501I42J196D01*
G01X999307Y137560D01*
X999287Y137588D01*
G03X998084Y138189I-1202J-901D01*
G01X998041D01*
X998040Y138188D01*
G03X996582Y136687I44J-1501D01*
G03X998084Y135185I1502J0D01*
G03X998316Y135203I0J1502D01*
G01X998359Y135210D01*
X998443Y135186D01*
X998707Y134961D01*
G02X998778Y134808I-129J-153D01*
G01Y133610D01*
G02X998707Y133457I-200J0D01*
G01X998443Y133232D01*
X998359Y133208D01*
X998316Y133215D01*
G03X998081Y133233I-232J-1484D01*
G01X998080D01*
G03X996582Y131731I4J-1502D01*
G03X998084Y130229I1502J0D01*
G01X998085D01*
G03X999287Y130830I0J1502D01*
G01X999307Y130858D01*
X999395Y130917D01*
G02X999462Y130945I109J-168D01*
G01X999581Y130972D01*
X999655Y130961D01*
X999688Y130943D01*
G03X999989Y130806I894J1565D01*
G03X1000580Y130706I592J1703D01*
G03X1001171Y130806I-1J1803D01*
G03X1001472Y130943I-593J1702D01*
G01X1001505Y130961D01*
X1001579Y130972D01*
X1001698Y130945D01*
G02X1001765Y130917I-42J-196D01*
G01X1001853Y130858D01*
X1001874Y130830D01*
G03X1002596Y130308I1201J901D01*
G01X1002657Y130287D01*
X1002732Y130183D01*
Y124061D01*
X1002657Y123957D01*
X1002596Y123936D01*
G03X1001874Y123414I479J-1423D01*
G01X1001853Y123386D01*
X1001765Y123327D01*
G02X1001698Y123299I-109J168D01*
G01X1001579Y123272D01*
X1001505Y123283D01*
X1001472Y123301D01*
G03X1001171Y123438I-894J-1565D01*
G03X1000580Y123538I-592J-1703D01*
G03X999989Y123438I1J-1803D01*
G03X999688Y123301I593J-1702D01*
G01X999655Y123283D01*
X999581Y123272D01*
X999462Y123299D01*
G02X999395Y123327I42J196D01*
G01X999307Y123386D01*
X999287Y123414D01*
G03X998084Y124015I-1202J-901D01*
G01X998041D01*
X998040Y124014D01*
G03X996582Y122513I44J-1501D01*
G03X998084Y121011I1502J0D01*
G03X998316Y121029I0J1502D01*
G01X998359Y121036D01*
X998443Y121012D01*
X998707Y120787D01*
G02X998778Y120634I-129J-153D01*
G01Y119436D01*
G02X998707Y119283I-200J0D01*
G01X998443Y119058D01*
X998359Y119034D01*
X998316Y119041D01*
G03X998081Y119059I-232J-1484D01*
G01X998080D01*
G03X996582Y117557I4J-1502D01*
G03X998084Y116055I1502J0D01*
G01X998085D01*
G03X999287Y116656I0J1502D01*
G01X999307Y116684D01*
X999395Y116743D01*
G02X999462Y116771I109J-168D01*
G01X999581Y116798D01*
X999655Y116787D01*
X999688Y116769D01*
G03X999989Y116632I894J1565D01*
G03X1000580Y116532I592J1703D01*
G03X1001171Y116632I-1J1803D01*
G03X1001472Y116769I-593J1702D01*
G01X1001505Y116787D01*
X1001579Y116798D01*
X1001698Y116771D01*
G02X1001765Y116743I-42J-196D01*
G01X1001853Y116684D01*
X1001874Y116656D01*
G03X1002596Y116134I1201J901D01*
G01X1002657Y116113D01*
X1002732Y116009D01*
Y78063D01*
G02X1002632Y77890I-200J0D01*
G03X1002130Y77421I747J-1303D01*
G01X1002106Y77386D01*
X1002037Y77341D01*
X1001706Y77288D01*
G02X1001552Y77327I-32J197D01*
G03X1000631Y77642I-920J-1187D01*
G01X1000601D01*
G03X999129Y76140I30J-1502D01*
G03X1000631Y74638I1502J0D01*
G01X1000653D01*
X1000715Y74639D01*
X1000816Y74573D01*
X1000984Y74175D01*
G02X1000941Y73955I-184J-78D01*
G01X999505Y72519D01*
X999477Y72490D01*
X999403Y72460D01*
X953290D01*
G02X953148Y72519I0J200D01*
G01X951832Y73835D01*
X951803Y73863D01*
X951773Y73937D01*
Y100421D01*
G02X951831Y100562I200J0D01*
G01X952058Y100791D01*
X952129Y100821D01*
X952170D01*
G03Y103825I-9J1502D01*
G01X952129D01*
X952058Y103855D01*
X951831Y104084D01*
G02X951773Y104225I142J141D01*
G01Y107508D01*
G02X951831Y107649I200J0D01*
G01X952058Y107878D01*
X952129Y107908D01*
X952170D01*
G03Y110912I-9J1502D01*
G01X952129D01*
X952058Y110942D01*
X951831Y111171D01*
G02X951773Y111312I142J141D01*
G01Y114594D01*
G02X951831Y114735I200J0D01*
G01X952058Y114964D01*
X952129Y114994D01*
X952170D01*
G03Y117998I-9J1502D01*
G01X952129D01*
X952058Y118028D01*
X951831Y118257D01*
G02X951773Y118398I142J141D01*
G01Y121681D01*
G02X951831Y121822I200J0D01*
G01X952058Y122051D01*
X952129Y122081D01*
X952170D01*
G03Y125085I-9J1502D01*
G01X952129D01*
X952058Y125115D01*
X951831Y125344D01*
G02X951773Y125485I142J141D01*
G01Y128768D01*
G02X951831Y128909I200J0D01*
G01X952058Y129138D01*
X952129Y129168D01*
X952170D01*
G03Y132172I-9J1502D01*
G01X952129D01*
X952058Y132202D01*
X951831Y132431D01*
G02X951773Y132572I142J141D01*
G01Y135854D01*
G02X951831Y135995I200J0D01*
G01X952058Y136224D01*
X952129Y136254D01*
X952170D01*
G03Y139258I-9J1502D01*
G01X952129D01*
X952058Y139288D01*
X951831Y139517D01*
G02X951773Y139658I142J141D01*
G01Y172141D01*
G02X951830Y172281I200J0D01*
G01X951831Y172282D01*
X953713Y174164D01*
G02X953715Y174166I142J-140D01*
G02X953855Y174223I140J-143D01*
G01X993779D01*
X993789D01*
G02X993958Y174112I-10J-200D01*
G02X993966Y174094I-178J-90D01*
G01X994122Y173688D01*
X994093Y173568D01*
X994047Y173526D01*
G03X993454Y172190I1208J-1336D01*
G03X997058I1802J0D01*
G03X996465Y173526I-1801J0D01*
G01X996419Y173568D01*
X996390Y173688D01*
X996546Y174094D01*
G02X996554Y174112I186J-72D01*
G02X996723Y174223I179J-89D01*
G01X996733D01*
G37*
G36*
G01X974952Y292294D02*
G03X976125Y292857I0J1503D01*
G02X976281Y292932I156J-125D01*
G01X1004627D01*
G02X1004795Y292839I-1J-200D01*
G03X1006063Y292143I1268J807D01*
G03X1007166Y292626I0J1501D01*
G02X1007172Y292632I144J-138D01*
G02X1007454I141J-142D01*
G02X1007460Y292626I-138J-144D01*
G03X1008563Y292143I1103J1018D01*
G03X1009315Y292345I0J1501D01*
G01X1009316Y292344D01*
G03X1011272Y291534I1956J1957D01*
G01X1020913D01*
G02X1021084Y291438I0J-200D01*
G01X1021262Y291145D01*
G02X1021269Y290951I-171J-103D01*
G01Y290950D01*
G03X1021102Y290262I1334J-688D01*
G03X1024106I1502J0D01*
G03X1023939Y290950I-1501J0D01*
G01Y290951D01*
G02X1023946Y291145I178J91D01*
G01X1024124Y291438D01*
G02X1024295Y291534I171J-104D01*
G01X1027271D01*
G02X1027413Y291475I0J-200D01*
G01X1027626Y291262D01*
G02Y290980I-142J-141D01*
G01X1027591Y290945D01*
X1027500Y290916D01*
X1027453Y290923D01*
G03X1027216Y290942I-238J-1483D01*
G03Y287938I0J-1502D01*
G03X1028708Y289264I0J1502D01*
G01X1028714Y289320D01*
X1028786Y289410D01*
X1028872Y289440D01*
G03X1028682Y288709I1311J-731D01*
G03X1030184Y287207I1502J0D01*
G03X1031440Y287885I0J1502D01*
G02X1031640Y287972I167J-110D01*
G03X1032097Y287934I457J2729D01*
G01X1035637D01*
G02X1035822Y287810I0J-200D01*
G02X1035779Y287593I-185J-76D01*
G01X1035092Y286905D01*
G02X1034950Y286846I-142J141D01*
G01X1020925D01*
G03X1020047Y286482I0J-1241D01*
G01X1011420Y277855D01*
G02X1011278Y277796I-142J141D01*
G01X978700D01*
G02X978558Y277855I0J200D01*
G01X965425Y290988D01*
G02X965366Y291130I141J142D01*
G01Y295900D01*
G03X964556Y297856I-2767J0D01*
G01X960229Y302183D01*
G02X960170Y302325I141J142D01*
G01Y306662D01*
G02X960294Y306847I200J0D01*
G01X960350Y306871D01*
X960468Y306847D01*
X973452Y293863D01*
G03X973450Y293797I1500J-78D01*
G01Y293795D01*
G03X974952Y292294I1502J1D01*
G37*
G36*
G01X1037203Y474679D02*
X1016554Y454030D01*
G02X1016412Y453971I-142J141D01*
G01X952938D01*
G02X952796Y454030I0J200D01*
G01X948402Y458424D01*
G02X948344Y458565I142J141D01*
G01Y473276D01*
G03X948342Y473347I-2241J-28D01*
G01Y473351D01*
Y476959D01*
G02X948452Y477138I200J0D01*
G01X948771Y477298D01*
G02X948980Y477280I90J-179D01*
G03X949875Y476984I895J1206D01*
G01X949876D01*
G03Y479988I0J1502D01*
G01X949875D01*
G03X948980Y479692I0J-1502D01*
G02X948771Y479674I-119J161D01*
G01X948452Y479834D01*
G02X948342Y480013I90J179D01*
G01Y482417D01*
G02X948449Y482594I200J0D01*
G01X948761Y482759D01*
G02X948787Y482770I91J-178D01*
G02X948969Y482746I68J-188D01*
G03X949822Y482480I853J1236D01*
G01X949823D01*
G03Y485484I0J1502D01*
G01X949822D01*
G03X948969Y485218I0J-1502D01*
G02X948787Y485194I-114J164D01*
G02X948761Y485205I65J189D01*
G01X948449Y485370D01*
X948400Y485396D01*
X948342Y485491D01*
Y486417D01*
G02X948449Y486594I200J0D01*
G01X948761Y486759D01*
G02X948787Y486770I91J-178D01*
G02X948969Y486746I68J-188D01*
G03X949822Y486480I853J1236D01*
G01X949823D01*
G03Y489484I0J1502D01*
G01X949822D01*
G03X948969Y489218I0J-1502D01*
G02X948787Y489194I-114J164D01*
G02X948761Y489205I65J189D01*
G01X948449Y489370D01*
X948400Y489396D01*
X948342Y489491D01*
Y490417D01*
G02X948449Y490594I200J0D01*
G01X948761Y490759D01*
G02X948787Y490770I91J-178D01*
G02X948969Y490746I68J-188D01*
G03X949822Y490480I853J1236D01*
G01X949823D01*
G03Y493484I0J1502D01*
G01X949822D01*
G03X948969Y493218I0J-1502D01*
G02X948787Y493194I-114J164D01*
G02X948761Y493205I65J189D01*
G01X948449Y493370D01*
X948400Y493396D01*
X948342Y493491D01*
Y498417D01*
G02X948449Y498594I200J0D01*
G01X948761Y498759D01*
G02X948787Y498770I91J-178D01*
G02X948969Y498746I68J-188D01*
G03X949822Y498480I853J1236D01*
G01X949823D01*
G03Y501484I0J1502D01*
G01X949818D01*
G02X949633Y501607I0J200D01*
G01X949491Y501949D01*
G02X949534Y502167I185J77D01*
G01X949734Y502367D01*
G02X949876Y502426I142J-141D01*
G01X997193D01*
G03X997335Y502485I0J200D01*
G01X998520Y503670D01*
G03X998579Y503812I-141J142D01*
G01Y528361D01*
X998609Y528435D01*
X998638Y528463D01*
X1021283Y551108D01*
G02X1021425Y551167I142J-141D01*
G01X1074764D01*
G03X1074906Y551226I0J200D01*
G01X1083094Y559414D01*
X1083122Y559443D01*
X1083196Y559473D01*
X1094759D01*
G02X1094900Y559415I0J-200D01*
G01X1095134Y559182D01*
G02X1095192Y559040I-142J-141D01*
G01Y549445D01*
G02X1095133Y549303I-200J0D01*
G01X1094980Y549150D01*
G02X1094838Y549091I-142J141D01*
G01X1089082D01*
G03X1088940Y549032I0J-200D01*
G01X1080995Y541087D01*
G02X1080853Y541028I-142J141D01*
G01X1051027D01*
G03X1050885Y540969I0J-200D01*
G01X1037321Y527405D01*
G03X1037262Y527263I141J-142D01*
G01Y474781D01*
X1037232Y474707D01*
X1037203Y474679D01*
G37*
G36*
G01X956928Y536733D02*
Y554389D01*
X956910Y554407D01*
Y615308D01*
X956940Y615381D01*
X956965Y615406D01*
X971726D01*
G02X971868Y615347I0J-200D01*
G01X972279Y614936D01*
G02X972338Y614794I-141J-142D01*
G01Y573216D01*
G03X972397Y573074I200J0D01*
G01X975778Y569693D01*
G03X975920Y569634I142J141D01*
G01X982054D01*
G03X982196Y569693I0J200D01*
G01X982959Y570456D01*
X984909Y572407D01*
G03X984968Y572549I-141J142D01*
G01Y576750D01*
G02X985027Y576892I200J0D01*
G01X985616Y577481D01*
G02X985758Y577540I142J-141D01*
G01X990124D01*
G02X990266Y577481I0J-200D01*
G01X990756Y576991D01*
G02X990815Y576849I-141J-142D01*
G01Y570820D01*
G02X990756Y570678I-200J0D01*
G01X988674Y568596D01*
G03X988615Y568454I141J-142D01*
G01Y556856D01*
X988644Y556827D01*
Y551474D01*
G03X988703Y551332I200J0D01*
G01X990350Y549685D01*
G03X990492Y549626I142J141D01*
G01X993653D01*
G02X993795Y549567I0J-200D01*
G01X994680Y548682D01*
G02X994739Y548540I-141J-142D01*
G01Y536820D01*
G02X994680Y536678I-200J0D01*
G01X994050Y536048D01*
G02X993908Y535989I-142J141D01*
G01X957672D01*
G02X957530Y536048I0J200D01*
G01X956987Y536591D01*
G02X956928Y536733I141J142D01*
G37*
G36*
G01X965076Y819975D02*
Y805494D01*
G02X965017Y805352I-200J0D01*
G01X964131Y804466D01*
G02X963989Y804407I-142J141D01*
G01X960709D01*
G02X960567Y804466I0J200D01*
G01X959146Y805887D01*
G02X959087Y806029I141J142D01*
G01Y819975D01*
X959603Y820491D01*
X964560D01*
X965076Y819975D01*
G37*
G36*
G01X952086Y822207D02*
X956327D01*
G02X956467Y822150I0J-200D01*
G01X956468Y822149D01*
X956920Y821697D01*
G02X956922Y821695I-140J-142D01*
G02X956979Y821555I-143J-140D01*
G01Y806699D01*
G02X956920Y806557I-200J0D01*
G01X956536Y806173D01*
X956508Y806144D01*
X956434Y806114D01*
X951110D01*
G02X950910Y806314I0J200D01*
G01Y821031D01*
G02X950968Y821172I200J0D01*
G01X951944Y822148D01*
G02X952086Y822207I142J-141D01*
G37*
G36*
G01X962118Y927643D02*
G03I-639J0D01*
G37*
G36*
G01X958794Y1450939D02*
X955821D01*
G02X955679Y1450998I0J200D01*
G01X955197Y1451480D01*
G02X955138Y1451622I141J142D01*
G01Y1485156D01*
G02X955197Y1485298I200J0D01*
G01X957042Y1487143D01*
G02X957184Y1487202I142J-141D01*
G01X1039022D01*
G02X1039221Y1487027I0J-200D01*
G03X1049670Y1467295I31305J3945D01*
G02X1049738Y1467144I-132J-150D01*
G01Y1452449D01*
G02X1049679Y1452307I-200J0D01*
G01X1048392Y1451020D01*
G02X1048250Y1450961I-142J141D01*
G01X958816D01*
X958794Y1450939D01*
G37*
G36*
G01X1010253Y342225D02*
X1033041D01*
G02X1033183Y342166I0J-200D01*
G01X1034760Y340589D01*
G02X1034819Y340447I-141J-142D01*
G01Y338873D01*
X1034829Y338863D01*
Y321167D01*
G02X1034770Y321025I-200J0D01*
G01X1033181Y319436D01*
G02X1033039Y319377I-142J141D01*
G01X1013199D01*
X1011959Y318137D01*
Y310641D01*
G02X1011853Y310465I-200J0D01*
G01X1011492Y310272D01*
X1011383Y310278D01*
X1011336Y310309D01*
G03X1010499Y310564I-837J-1246D01*
G03Y307560I0J-1502D01*
G03X1011336Y307815I0J1501D01*
G01X1011383Y307846D01*
X1011492Y307852D01*
X1011853Y307659D01*
G02X1011959Y307483I-94J-176D01*
G01Y301735D01*
G02X1011862Y301564I-200J0D01*
G03X1011141Y300426I773J-1287D01*
G01X1011137Y300391D01*
X1011108Y300330D01*
X1010381Y299603D01*
G02X1010240Y299544I-142J141D01*
G01X1002571D01*
G02X1002418Y299616I1J200D01*
G01X1002192Y299886D01*
X1002169Y299970D01*
X1002177Y300014D01*
G03X1002200Y300276I-1479J262D01*
G03X999196I-1502J0D01*
G03X999219Y300014I1502J0D01*
G01X999227Y299970D01*
X999204Y299886D01*
X998978Y299616D01*
G02X998825Y299544I-154J128D01*
G01X977206D01*
G02X977064Y299603I0J200D01*
G01X973787Y302880D01*
Y323525D01*
G02X973846Y323667I200J0D01*
G01X973998Y323819D01*
G02X974140Y323878I142J-141D01*
G01X985109D01*
G02X985200Y323900I91J-177D01*
G01X985306D01*
X985314Y323896D01*
X987315D01*
G02X987455Y323838I-1J-200D01*
G01X987464Y323829D01*
G02X987474Y323820I-129J-153D01*
G01X987489Y323805D01*
G03X988337Y323452I851J848D01*
G01X991922D01*
G02X992064Y323394I1J-200D01*
G01X992652Y322806D01*
Y322805D01*
G03X993502Y322452I851J849D01*
G01X998213D01*
G03X999065Y322807I-1J1202D01*
G02X999418Y322954I354J-353D01*
G01X999420D01*
G02X999920Y322478I0J-501D01*
G01Y322476D01*
X999930Y322287D01*
G03X999947Y322216I200J10D01*
G01X1000098Y321878D01*
G03X1000139Y321818I183J81D01*
G01X1001152Y320806D01*
Y320805D01*
G03X1002002Y320452I851J849D01*
G01X1008669D01*
G03X1008810Y320511I-1J200D01*
G01X1009595Y321296D01*
G03X1009654Y321437I-141J142D01*
G01Y341626D01*
G02X1009713Y341768I200J0D01*
G01X1010111Y342166D01*
G02X1010253Y342225I142J-141D01*
G37*
G36*
G01X974017Y345018D02*
G03I-679J0D01*
G37*
G36*
G01X972398Y851242D02*
G03I-590J0D01*
G37*
G36*
G01X969944Y1545913D02*
Y1564282D01*
G02X970003Y1564424I200J0D01*
G01X972304Y1566725D01*
G02X972446Y1566784I142J-141D01*
G01X993823D01*
G02X993965Y1566725I0J-200D01*
G01X995797Y1564893D01*
G02X995856Y1564751I-141J-142D01*
G01Y1547091D01*
G02X995797Y1546949I-200J0D01*
G01X993903Y1545055D01*
G02X993761Y1544996I-142J141D01*
G01X970861D01*
G02X970719Y1545055I0J200D01*
G01X970003Y1545771D01*
G02X969944Y1545913I141J142D01*
G37*
G36*
G01X1051831Y54588D02*
X1080886D01*
X1081101Y54373D01*
Y52806D01*
X1080886Y52591D01*
X1051831D01*
G03X1045894Y46654I0J-5937D01*
G01Y7874D01*
G02X1040020Y2000I-5874J0D01*
G01X992776D01*
G02X986902Y7874I0J5874D01*
G01Y46654D01*
G03Y46659I-5936J2D01*
G01X988900D01*
G02Y46654I-7934J-2D01*
G01Y7874D01*
G03X992776Y3998I3876J0D01*
G01X1040020D01*
G03X1043896Y7874I0J3876D01*
G01Y46654D01*
G02X1051831Y54588I7935J-1D01*
G37*
G36*
G01X1008254Y321454D02*
X1002003D01*
G02X1001869Y321506I0J200D01*
G01X1001521Y321853D01*
X1000978Y322396D01*
G02X1000937Y322456I142J141D01*
G01X1000922Y322489D01*
Y322491D01*
X1000921Y322515D01*
G03X999420Y323956I-1501J-61D01*
G01X999416D01*
G03X998912Y323868I3J-1502D01*
G03X998686Y323765I508J-1413D01*
G02X998598Y323740I-97J175D01*
G03X997833Y323488I70J-1501D01*
G02X997831Y323486I-140J138D01*
G02X997722Y323454I-109J168D01*
G01X993503D01*
G02X993473Y323456I-2J200D01*
G02X993374Y323501I30J198D01*
G01X992771Y324103D01*
G03X992756Y324118I-857J-842D01*
G01X992479Y324395D01*
G03X992337Y324454I-142J-141D01*
G01X988338D01*
G02X988255Y324472I0J200D01*
G02X988206Y324505I86J181D01*
G01X987869Y324840D01*
G03X987729Y324898I-141J-142D01*
G01X985549D01*
X985542Y324902D01*
X985509D01*
X985445Y324929D01*
X985420Y324954D01*
Y328371D01*
G02X985424Y328409I200J-2D01*
G02X985477Y328511I196J-37D01*
G01X985863Y328897D01*
G02X985965Y328950I139J-143D01*
G02X986003Y328954I40J-196D01*
G01X1008337D01*
G02X1008375Y328950I-2J-200D01*
G02X1008477Y328897I-37J-196D01*
G01X1008594Y328780D01*
G02X1008652Y328639I-142J-141D01*
G01Y321852D01*
G02X1008593Y321710I-200J0D01*
G01X1008396Y321513D01*
G02X1008254Y321454I-142J141D01*
G37*
G36*
G01X991920Y336719D02*
Y332037D01*
G02X991861Y331895I-200J0D01*
G01X991479Y331513D01*
G02X991337Y331454I-142J141D01*
G01X985503D01*
G02X985361Y331513I0J200D01*
G01X984479Y332395D01*
G02X984420Y332537I141J142D01*
G01Y338133D01*
X987952Y341665D01*
X991440D01*
X991920Y341185D01*
Y339189D01*
G02X991882Y339072I-200J0D01*
G03X991518Y337954I1538J-1119D01*
G03X991882Y336836I1902J1D01*
G02X991920Y336719I-162J-117D01*
G37*
G36*
G01X1012393Y581389D02*
X1074492D01*
X1081116D01*
X1084634Y577871D01*
X1093461D01*
G02X1093603Y577812I0J-200D01*
G01X1094232Y577183D01*
G02X1094291Y577041I-141J-142D01*
G01Y576767D01*
G02X1094232Y576626I-200J1D01*
G01X1094230Y576623D01*
X1094200Y576550D01*
Y561392D01*
G02X1094141Y561251I-200J1D01*
G01X1094133Y561243D01*
G02X1093991Y561184I-142J141D01*
G01X1082177D01*
G03X1082035Y561125I0J-200D01*
G01X1073316Y552406D01*
G02X1073174Y552347I-142J141D01*
G01X991904D01*
G02X991762Y552406I0J200D01*
G01X990576Y553592D01*
G02X990517Y553734I141J142D01*
G01Y567086D01*
G02X990576Y567228I200J0D01*
G01X996484Y573136D01*
G02X996626Y573195I142J-141D01*
G01X1004033D01*
G03X1004175Y573254I0J200D01*
G01X1012251Y581330D01*
G02X1012393Y581389I142J-141D01*
G37*
G36*
G01X985620Y781204D02*
G03I-590J0D01*
G37*
G36*
G01X988919Y781445D02*
G03I-590J0D01*
G37*
G36*
G01X985553Y785387D02*
G03I-590J0D01*
G37*
G36*
G01X979903Y814316D02*
G03I-590J0D01*
G37*
G36*
G01X989410Y858903D02*
G03I-590J0D01*
G37*
G36*
G01X979317Y1284908D02*
G03I-590J0D01*
G37*
G36*
G01X1011420Y355871D02*
Y347361D01*
X1012408Y346373D01*
X1015255D01*
X1015764Y345864D01*
Y343696D01*
X1015353Y343285D01*
X1010751D01*
G02X1010610Y343226I-142J141D01*
G01X1009838D01*
G03X1009697Y343168I0J-200D01*
G01X1009541Y343013D01*
G02X1009400Y342954I-142J141D01*
G01X1008503D01*
G02X1008361Y343013I0J200D01*
G01X1007479Y343895D01*
G02X1007420Y344037I141J142D01*
G01Y355371D01*
G02X1007479Y355513I200J0D01*
G01X1008361Y356395D01*
G02X1008503Y356454I142J-141D01*
G01X1010837D01*
G02X1010979Y356395I0J-200D01*
G01X1011361Y356013D01*
G02X1011420Y355871I-141J-142D01*
G37*
G36*
G01X1000979Y335395D02*
G02X1000920Y335537I141J142D01*
G01Y343371D01*
G02X1000979Y343513I200J0D01*
G01X1001361Y343895D01*
G02X1001503Y343954I142J-141D01*
G01X1004337D01*
G02X1004479Y343895I0J-200D01*
G01X1004861Y343513D01*
G02X1004920Y343371I-141J-142D01*
G01Y331537D01*
G02X1004861Y331395I-200J0D01*
G01X1003979Y330513D01*
G02X1003837Y330454I-142J141D01*
G01X1002804D01*
X1002141Y331117D01*
Y333478D01*
X1000979Y334640D01*
Y335395D01*
G37*
G36*
G01X1040551Y388583D02*
G03I-19685J0D01*
G37*
G36*
G01X1000415Y819488D02*
G03I-590J0D01*
G37*
G36*
G01X1005736Y880804D02*
X1010582D01*
X1010776Y880610D01*
Y874249D01*
X1010217Y873690D01*
X1004667D01*
X1003976Y874381D01*
Y879997D01*
X1004783Y880804D01*
X1005736D01*
G37*
G36*
G01X1024519Y950422D02*
Y931522D01*
X1023819Y930822D01*
X1004119D01*
X1003619Y931322D01*
Y939722D01*
X1003819Y939922D01*
X1010819D01*
X1011419Y939322D01*
Y937422D01*
X1012269Y936572D01*
X1016969D01*
X1017919Y937522D01*
Y950522D01*
Y953222D01*
X1018119Y953422D01*
X1018519Y953822D01*
X1024119D01*
X1024519Y953422D01*
Y950422D01*
G37*
G36*
G01X1004219Y950722D02*
X1010819D01*
X1011819Y949722D01*
Y948222D01*
X1012819Y947222D01*
X1016519D01*
X1016819Y946922D01*
Y942722D01*
X1016619Y942522D01*
X1004019D01*
X1003719Y942822D01*
Y950222D01*
X1004219Y950722D01*
G37*
G36*
G01X1036285Y326520D02*
X1047903D01*
G02X1048045Y326461I0J-200D01*
G01X1048966Y325539D01*
G02X1049025Y325397I-141J-142D01*
G01Y307350D01*
G02X1048966Y307208I-200J0D01*
G01X1047481Y305723D01*
G03X1047428Y305628I141J-141D01*
G01X1047421Y305601D01*
X1047395Y305554D01*
X1045177Y303336D01*
G02X1045035Y303277I-142J141D01*
G01X1025507D01*
G02X1025365Y303336I0J200D01*
G01X1024420Y304281D01*
G02X1024361Y304423I141J142D01*
G01Y304908D01*
X1024391Y304981D01*
X1024420Y305009D01*
Y308527D01*
Y317871D01*
G02X1024479Y318013I200J0D01*
G01X1024783Y318317D01*
G02X1024924Y318376I142J-141D01*
G01X1033040D01*
X1033455D01*
G03X1033595Y318434I-1J200D01*
G01X1033873Y318712D01*
X1033876Y318714D01*
G03X1033890Y318728I-842J856D01*
G01X1035478Y320316D01*
G03X1035495Y320334I-865J834D01*
G01X1035830Y320669D01*
Y320686D01*
X1035863Y320767D01*
G03X1035878Y320842I-185J76D01*
G01Y326113D01*
G02X1035937Y326255I200J0D01*
G01X1036143Y326461D01*
G02X1036285Y326520I142J-141D01*
G37*
G36*
G01X1023418Y317565D02*
Y309535D01*
Y305424D01*
X1022644Y304650D01*
X1014047D01*
X1013531Y305166D01*
Y309843D01*
G02X1013472Y309985I141J142D01*
G01Y317161D01*
G02X1013531Y317303I200J0D01*
G01X1014545Y318317D01*
G02X1014686Y318376I142J-141D01*
G01X1022608D01*
G02X1022749Y318317I-1J-200D01*
G01X1023360Y317706D01*
G02X1023418Y317565I-142J-141D01*
G37*
G36*
G01X1019985Y356122D02*
X1043792D01*
G02X1043934Y356063I0J-200D01*
G01X1044529Y355468D01*
G02X1044588Y355326I-141J-142D01*
G01Y348196D01*
G02X1044538Y348064I-200J0D01*
G03Y345552I1427J-1256D01*
G02X1044588Y345420I-150J-132D01*
G01Y334872D01*
X1044589Y334871D01*
Y334479D01*
G02X1044530Y334337I-200J0D01*
G01X1043010Y332817D01*
X1042982Y332788D01*
X1042908Y332758D01*
X1036853D01*
G02X1036711Y332817I0J200D01*
G01X1035889Y333639D01*
G02X1035830Y333780I141J142D01*
G01Y339278D01*
X1035820Y339288D01*
Y340448D01*
Y340863D01*
G03X1035762Y341003I-200J-1D01*
G01X1035485Y341280D01*
X1035484Y341281D01*
G03X1035468Y341298I-883J-815D01*
G01X1033892Y342874D01*
G03X1033874Y342891I-834J-865D01*
G01X1033597Y343168D01*
G03X1033457Y343226I-141J-142D01*
G01X1033361D01*
G02X1033329Y343228I-4J200D01*
G02X1033219Y343285I33J198D01*
G01X1033201Y343303D01*
G03X1033059Y343362I-142J-141D01*
G01X1018365D01*
G02X1018223Y343421I0J200D01*
G01X1017407Y344237D01*
X1017378Y344265D01*
X1017348Y344339D01*
Y354613D01*
G02X1017407Y354755I200J0D01*
G01X1018653Y356001D01*
G02X1018795Y356060I142J-141D01*
G01X1019800D01*
G03X1019907Y356091I0J200D01*
G01X1019932Y356106D01*
X1019985Y356122D01*
G37*
G36*
G01X1019965Y783056D02*
G03I-590J0D01*
G37*
G36*
G01X1018634Y793592D02*
G03I-590J0D01*
G37*
G36*
G01X1015177Y802788D02*
G03I-590J0D01*
G37*
G36*
G01X1026449Y802275D02*
G03I-590J0D01*
G37*
G36*
G01X1016390Y807535D02*
G03I-590J0D01*
G37*
G36*
G01X1012553Y880998D02*
X1017302D01*
X1018271Y880029D01*
Y872469D01*
Y871203D01*
X1017434Y870366D01*
X1012070D01*
X1011907Y870529D01*
Y872112D01*
Y880352D01*
X1012553Y880998D01*
G37*
G36*
G01X1025919Y945322D02*
X1030819D01*
X1033919D01*
X1035819D01*
X1036619Y944522D01*
Y931522D01*
X1035919Y930822D01*
X1034319D01*
X1026219D01*
X1025619Y931422D01*
Y945022D01*
X1025919Y945322D01*
G37*
G36*
G01X1048605Y1066535D02*
G02I-17700J0D01*
G37*
G36*
G01Y1263386D02*
G02I-17700J0D01*
G37*
G36*
G01X1040952Y203641D02*
X1052160D01*
X1053132Y202669D01*
Y195995D01*
X1051578Y194441D01*
X1040433D01*
X1039721Y195153D01*
Y202410D01*
X1040952Y203641D01*
G37*
G36*
G01X1031378Y301312D02*
X1043606D01*
G02X1043772Y301224I0J-200D01*
G01X1043985Y300908D01*
X1043996Y300810D01*
X1043977Y300763D01*
G03X1043848Y300093I1673J-670D01*
G03X1045650Y298291I1802J0D01*
G03X1047410Y299706I0J1802D01*
G01X1047422Y299760D01*
X1047496Y299839D01*
X1047886Y299953D01*
G02X1048083Y299902I55J-192D01*
G01X1048572Y299414D01*
G03X1048713Y299356I141J142D01*
G01X1055632D01*
G02X1055817Y299232I0J-200D01*
G01X1055841Y299175D01*
X1055817Y299058D01*
X1051365Y294605D01*
G02X1051223Y294546I-142J141D01*
G01X1039034D01*
G02X1038854Y294658I0J200D01*
G01X1038671Y295032D01*
X1038682Y295145D01*
X1038717Y295191D01*
G03X1039094Y296293I-1426J1103D01*
G03X1037291Y298096I-1803J0D01*
G01X1033891D01*
G03X1032184Y296872I0J-1802D01*
G01X1032167Y296823D01*
X1032091Y296754D01*
X1031709Y296665D01*
G02X1031523Y296718I-45J195D01*
G01X1030904Y297336D01*
G03X1028948Y298146I-1956J-1957D01*
G01X1026960D01*
G02X1026775Y298270I0J200D01*
G01X1026752Y298327D01*
X1026775Y298444D01*
X1027745Y299414D01*
G02X1027909Y299471I141J-142D01*
G01X1028265Y299431D01*
X1028342Y299383D01*
X1028366Y299343D01*
G03X1029639Y298639I1273J799D01*
G03X1031141Y300141I0J1502D01*
G03X1031012Y300750I-1502J0D01*
G01X1030991Y300797D01*
X1030999Y300897D01*
X1031210Y301221D01*
G02X1031378Y301312I168J-109D01*
G37*
G36*
G01X1043470Y794924D02*
G03I-590J0D01*
G37*
G36*
G01X1028745Y879413D02*
G03I-590J0D01*
G37*
G36*
G01X1056192Y175015D02*
X1102667D01*
G02X1102807Y174958I0J-200D01*
G01X1102808Y174957D01*
X1105010Y172755D01*
G02X1105012Y172753I-140J-142D01*
G02X1105069Y172613I-143J-140D01*
G01Y147990D01*
G02X1104959Y147811I-200J0D01*
G01X1104641Y147650D01*
G02X1104431Y147668I-90J178D01*
G03X1103537Y147963I-894J-1207D01*
G03Y144959I0J-1502D01*
G03X1104431Y145254I0J1502D01*
G02X1104641Y145272I120J-160D01*
G01X1104959Y145111D01*
G02X1105069Y144932I-90J-179D01*
G01Y138227D01*
X1104996Y138124D01*
X1104936Y138103D01*
G03X1104235Y137587I502J-1416D01*
G01X1104214Y137559D01*
X1104127Y137501D01*
G02X1104060Y137473I-109J168D01*
G01X1103941Y137446D01*
X1103867Y137457D01*
X1103834Y137475D01*
G03X1103533Y137612I-894J-1565D01*
G03X1102942Y137712I-592J-1703D01*
G03X1102351Y137612I1J-1803D01*
G03X1102050Y137475I593J-1702D01*
G01X1102017Y137457D01*
X1101943Y137446D01*
X1101824Y137473D01*
G02X1101757Y137501I42J196D01*
G01X1101669Y137560D01*
X1101649Y137588D01*
G03X1100446Y138189I-1202J-901D01*
G01X1100403D01*
X1100402Y138188D01*
G03X1098944Y136687I44J-1501D01*
G03X1100446Y135185I1502J0D01*
G03X1100678Y135203I0J1502D01*
G01X1100721Y135210D01*
X1100805Y135186D01*
X1101069Y134961D01*
G02X1101140Y134808I-129J-153D01*
G01Y133610D01*
G02X1101069Y133457I-200J0D01*
G01X1100805Y133232D01*
X1100721Y133208D01*
X1100678Y133215D01*
G03X1100443Y133233I-232J-1484D01*
G01X1100442D01*
G03X1098944Y131731I4J-1502D01*
G03X1100446Y130229I1502J0D01*
G01X1100447D01*
G03X1101649Y130830I0J1502D01*
G01X1101669Y130858D01*
X1101757Y130917D01*
G02X1101824Y130945I109J-168D01*
G01X1101943Y130972D01*
X1102017Y130961D01*
X1102050Y130943D01*
G03X1102351Y130806I894J1565D01*
G03X1102942Y130706I592J1703D01*
G03X1103533Y130806I-1J1803D01*
G03X1103834Y130943I-593J1702D01*
G01X1103867Y130961D01*
X1103941Y130972D01*
X1104060Y130945D01*
G02X1104127Y130917I-42J-196D01*
G01X1104214Y130859D01*
X1104235Y130831D01*
G03X1104936Y130315I1203J900D01*
G01X1104996Y130294D01*
X1105069Y130191D01*
Y124053D01*
X1104996Y123950D01*
X1104936Y123929D01*
G03X1104235Y123413I502J-1416D01*
G01X1104214Y123385D01*
X1104127Y123327D01*
G02X1104060Y123299I-109J168D01*
G01X1103941Y123272D01*
X1103867Y123283D01*
X1103834Y123301D01*
G03X1103533Y123438I-894J-1565D01*
G03X1102942Y123538I-592J-1703D01*
G03X1102351Y123438I1J-1803D01*
G03X1102050Y123301I593J-1702D01*
G01X1102017Y123283D01*
X1101943Y123272D01*
X1101824Y123299D01*
G02X1101757Y123327I42J196D01*
G01X1101669Y123386D01*
X1101649Y123414D01*
G03X1100446Y124015I-1202J-901D01*
G01X1100403D01*
X1100402Y124014D01*
G03X1098944Y122513I44J-1501D01*
G03X1100446Y121011I1502J0D01*
G03X1100678Y121029I0J1502D01*
G01X1100721Y121036D01*
X1100805Y121012D01*
X1101069Y120787D01*
G02X1101140Y120634I-129J-153D01*
G01Y119436D01*
G02X1101069Y119283I-200J0D01*
G01X1100805Y119058D01*
X1100721Y119034D01*
X1100678Y119041D01*
G03X1100443Y119059I-232J-1484D01*
G01X1100442D01*
G03X1098944Y117557I4J-1502D01*
G03X1100446Y116055I1502J0D01*
G01X1100447D01*
G03X1101649Y116656I0J1502D01*
G01X1101669Y116684D01*
X1101757Y116743D01*
G02X1101824Y116771I109J-168D01*
G01X1101943Y116798D01*
X1102017Y116787D01*
X1102050Y116769D01*
G03X1102351Y116632I894J1565D01*
G03X1102942Y116532I592J1703D01*
G03X1103533Y116632I-1J1803D01*
G03X1103834Y116769I-593J1702D01*
G01X1103867Y116787D01*
X1103941Y116798D01*
X1104060Y116771D01*
G02X1104127Y116743I-42J-196D01*
G01X1104214Y116685D01*
X1104235Y116657D01*
G03X1104936Y116141I1203J900D01*
G01X1104996Y116120D01*
X1105069Y116017D01*
Y78102D01*
G02X1105043Y78003I-200J0D01*
G01X1104983Y77899D01*
X1104951Y77865D01*
X1104930Y77851D01*
G03X1104492Y77421I811J-1264D01*
G01X1104491Y77420D01*
Y77419D01*
G02X1104357Y77334I-165J113D01*
G01X1104068Y77288D01*
G02X1103914Y77327I-32J197D01*
G03X1102993Y77642I-920J-1187D01*
G01X1102963D01*
G03X1101491Y76140I30J-1502D01*
G03X1102466Y74734I1501J0D01*
G01X1102514Y74716D01*
X1102580Y74639D01*
X1102662Y74261D01*
G02X1102618Y74088I-196J-42D01*
G01X1102613Y74082D01*
X1101842Y73311D01*
X1101814Y73282D01*
X1101740Y73252D01*
X1055627D01*
G02X1055485Y73311I0J200D01*
G01X1054169Y74627D01*
X1054140Y74655D01*
X1054110Y74729D01*
Y100421D01*
G02X1054169Y100563I200J0D01*
G01X1054371Y100763D01*
G02X1054512Y100821I141J-142D01*
G01X1054523D01*
G03Y103825I0J1502D01*
G01X1054512D01*
G02X1054371Y103883I0J200D01*
G01X1054169Y104083D01*
G02X1054110Y104225I141J142D01*
G01Y107508D01*
G02X1054169Y107650I200J0D01*
G01X1054371Y107850D01*
G02X1054512Y107908I141J-142D01*
G01X1054523D01*
G03Y110912I0J1502D01*
G01X1054512D01*
G02X1054371Y110970I0J200D01*
G01X1054169Y111170D01*
G02X1054110Y111312I141J142D01*
G01Y114594D01*
G02X1054169Y114736I200J0D01*
G01X1054371Y114936D01*
G02X1054512Y114994I141J-142D01*
G01X1054523D01*
G03Y117998I0J1502D01*
G01X1054512D01*
G02X1054371Y118056I0J200D01*
G01X1054169Y118256D01*
G02X1054110Y118398I141J142D01*
G01Y121681D01*
G02X1054169Y121823I200J0D01*
G01X1054371Y122023D01*
G02X1054512Y122081I141J-142D01*
G01X1054523D01*
G03Y125085I0J1502D01*
G01X1054512D01*
G02X1054371Y125143I0J200D01*
G01X1054169Y125343D01*
G02X1054110Y125485I141J142D01*
G01Y128768D01*
G02X1054169Y128910I200J0D01*
G01X1054371Y129110D01*
G02X1054512Y129168I141J-142D01*
G01X1054523D01*
G03Y132172I0J1502D01*
G01X1054512D01*
G02X1054371Y132230I0J200D01*
G01X1054169Y132430D01*
G02X1054110Y132572I141J142D01*
G01Y135854D01*
G02X1054169Y135996I200J0D01*
G01X1054371Y136196D01*
G02X1054512Y136254I141J-142D01*
G01X1054523D01*
G03Y139258I0J1502D01*
G01X1054512D01*
G02X1054371Y139316I0J200D01*
G01X1054169Y139516D01*
G02X1054110Y139658I141J142D01*
G01Y172933D01*
G02X1054167Y173073I200J0D01*
G01X1054168Y173074D01*
X1056050Y174956D01*
G02X1056052Y174958I142J-140D01*
G02X1056192Y175015I140J-143D01*
G37*
G36*
G01X1050920Y307430D02*
Y312871D01*
G02X1050979Y313013I200J0D01*
G01X1051361Y313395D01*
G02X1051503Y313454I142J-141D01*
G01X1055837D01*
G02X1055979Y313395I0J-200D01*
G01X1056361Y313013D01*
G02X1056420Y312871I-141J-142D01*
G01Y303537D01*
X1057074Y302883D01*
Y301103D01*
X1056328Y300357D01*
X1049045D01*
X1048541Y300861D01*
Y305051D01*
X1050920Y307430D01*
G37*
G36*
G01X1047503Y358454D02*
X1062739D01*
G02X1062881Y358395I0J-200D01*
G01X1065080Y356196D01*
G02X1065139Y356054I-141J-142D01*
G01Y343082D01*
G02X1065080Y342940I-200J0D01*
G01X1063999Y341859D01*
G02X1063857Y341800I-142J141D01*
G01X1056778D01*
G02X1056636Y341859I0J200D01*
G01X1051100Y347395D01*
G03X1050958Y347454I-142J-141D01*
G01X1048092D01*
G02X1047951Y347513I1J200D01*
G01X1047311Y348153D01*
G03X1047010Y348397I-1342J-1348D01*
G02X1046920Y348564I110J167D01*
G01Y357828D01*
X1046950Y357901D01*
X1046961Y357912D01*
G02X1047020Y358054I200J0D01*
G01X1047361Y358395D01*
G02X1047503Y358454I142J-141D01*
G37*
G36*
G01X1046334Y800835D02*
G03I-590J0D01*
G37*
G36*
G01X1058551Y931919D02*
G03I-590J0D01*
G37*
G36*
G01X1044143Y1035384D02*
G03I-590J0D01*
G37*
G36*
G01X1052964Y1348187D02*
G03I-491J0D01*
G37*
G36*
G01Y1360099D02*
G03I-491J0D01*
G37*
G36*
G01Y1372385D02*
G03I-491J0D01*
G37*
G36*
G01Y1384297D02*
G03I-491J0D01*
G37*
G36*
G01X1090157Y1490945D02*
G03I-19685J0D01*
G37*
G36*
G01X1822917Y265289D02*
X1818815Y261187D01*
G02X1818748Y261143I-141J142D01*
G01X1818714Y261129D01*
X1483306D01*
G03X1483164Y261070I0J-200D01*
G01X1483061Y260967D01*
G02X1483011Y260931I-140J142D01*
G02X1482920Y260909I-91J178D01*
G01X1072674D01*
G02X1072474Y261109I0J200D01*
G01Y270852D01*
G02X1072478Y270890I200J-2D01*
G02X1072531Y270992I196J-37D01*
G01X1085804Y284265D01*
X1085845Y284280D01*
G03X1086738Y285173I-517J1410D01*
G01X1086753Y285214D01*
X1088180Y286641D01*
G02X1088234Y286680I143J-140D01*
G01X1088264Y286694D01*
X1088298Y286698D01*
G03X1089620Y288020I-170J1492D01*
G01X1089624Y288054D01*
X1089638Y288084D01*
G02X1089677Y288138I179J-89D01*
G01X1111762Y310223D01*
G02X1111806Y310256I141J-142D01*
G01X1134980D01*
G03X1135342Y310279I6J2766D01*
G01X1135355Y310281D01*
X1136033D01*
G03X1136174Y310340I-1J200D01*
G01X1136653Y310818D01*
X1136662Y310826D01*
G03X1136936Y311066I-1682J2196D01*
G01X1140212Y314341D01*
G02X1140354Y314400I142J-141D01*
G01X1148967D01*
G03X1149329Y314424I-2J2767D01*
G01X1149342Y314426D01*
X1168965D01*
G02X1168992Y314424I-1J-200D01*
G02X1169099Y314371I-31J-198D01*
G01X1169578Y313892D01*
G03X1171514Y313090I1938J1940D01*
G01X1176219D01*
G02X1176368Y313011I-11J-200D01*
G01X1176566Y312752D01*
G02X1176597Y312682I-164J-115D01*
G01X1176601Y312660D01*
X1176607Y312629D01*
X1176604Y312617D01*
G03X1176544Y312237I1441J-422D01*
G01Y312235D01*
G03X1176543Y312203I1500J-63D01*
G01Y312184D01*
G03X1178045Y310691I1502J9D01*
G03X1179546Y312126I0J1503D01*
G01X1179548Y312174D01*
Y312193D01*
G03X1179232Y313115I-1503J0D01*
G01X1179207Y313147D01*
X1179197Y313182D01*
G02X1179191Y313261I192J54D01*
G01X1179208Y313402D01*
X1179225Y313542D01*
G02X1179250Y313617I198J-24D01*
G01X1179268Y313649D01*
X1179300Y313674D01*
G03X1179546Y313892I-1692J2157D01*
G01X1180186Y314533D01*
X1180190Y314537D01*
G02X1180304Y314590I137J-146D01*
G02X1180327Y314591I20J-199D01*
G01X1181017D01*
X1181040Y314586D01*
G03X1181379Y314547I340J1463D01*
G03X1181718Y314586I-1J1502D01*
G01X1181741Y314591D01*
X1199539D01*
X1199546D01*
G02X1199724Y314467I-7J-200D01*
G03X1202502I1389J572D01*
G02X1202680Y314591I185J-76D01*
G01X1213081D01*
G02X1213222Y314532I-1J-200D01*
G01X1223055Y304700D01*
G03X1223196Y304641I142J141D01*
G01X1225667D01*
X1225674Y304640D01*
G03X1225871Y304634I183J2760D01*
G01X1234600D01*
X1234601D01*
G03X1234798Y304640I14J2766D01*
G01X1234805Y304641D01*
X1236564D01*
G03X1236705Y304700I-1J200D01*
G01X1242894Y310888D01*
G02X1243035Y310947I142J-141D01*
G01X1287528D01*
G02X1287566Y310943I-2J-200D01*
G02X1287668Y310890I-37J-196D01*
G01X1299333Y299225D01*
G03X1299475Y299166I142J141D01*
G01X1353608D01*
G03X1353749Y299224I0J200D01*
G01X1364394Y309869D01*
G02X1364496Y309922I139J-143D01*
G02X1364534Y309926I40J-196D01*
G01X1594466D01*
G02X1594608Y309867I0J-200D01*
G01X1594888Y309587D01*
G03X1595030Y309528I142J141D01*
G01X1698547D01*
G03X1698689Y309587I0J200D01*
G01X1698969Y309867D01*
G02X1699111Y309926I142J-141D01*
G01X1817810D01*
G02X1817848Y309922I-2J-200D01*
G02X1817950Y309869I-37J-196D01*
G01X1822918Y304901D01*
G02X1822971Y304799I-143J-139D01*
G02X1822975Y304761I-196J-40D01*
G01Y265430D01*
G02X1822953Y265339I-200J0D01*
G02X1822917Y265289I-178J90D01*
G37*
G36*
G01X1071368Y1012252D02*
G03I-590J0D01*
G37*
G36*
G01X1067523Y1040567D02*
G03I-590J0D01*
G37*
G36*
G01X1060762Y1050481D02*
G03I-590J0D01*
G37*
G36*
G01X1099613Y1141870D02*
X1099361Y1141725D01*
G02X1099261Y1141698I-100J173D01*
G01X1099209D01*
X1099162Y1141726D01*
G03X1098524Y1141901I-638J-1077D01*
G01X1098495D01*
G03X1097271Y1140649I28J-1252D01*
G03X1098523Y1139397I1252J0D01*
G01X1098524D01*
G03X1099162Y1139572I0J1252D01*
G01X1099185Y1139586D01*
X1099237Y1139600D01*
X1099262D01*
G02X1099362Y1139573I0J-200D01*
G01X1099486Y1139502D01*
X1099611Y1139430D01*
G02X1099676Y1139370I-100J-174D01*
G02X1099686Y1139353I-167J-110D01*
G01X1099692Y1139341D01*
G02X1099712Y1139255I-180J-87D01*
G01Y1138302D01*
G02X1099613Y1138130I-200J1D01*
G01X1099361Y1137985D01*
G02X1099261Y1137958I-100J173D01*
G01X1099209D01*
X1099162Y1137986D01*
G03X1098524Y1138161I-638J-1077D01*
G01X1098495D01*
G03X1097271Y1136909I28J-1252D01*
G03X1097887Y1135831I1251J0D01*
G02X1097975Y1135671I-112J-166D01*
G01Y1134413D01*
Y1134407D01*
G02X1097887Y1134247I-200J6D01*
G03X1097271Y1133169I635J-1078D01*
G03X1098523Y1131917I1252J0D01*
G01X1098524D01*
G03X1099162Y1132092I0J1252D01*
G01X1099185Y1132106D01*
X1099237Y1132120D01*
X1099262D01*
G02X1099362Y1132093I0J-200D01*
G01X1099486Y1132022D01*
X1099611Y1131950D01*
G02X1099676Y1131890I-100J-174D01*
G02X1099686Y1131873I-167J-110D01*
G01X1099692Y1131861D01*
G02X1099712Y1131775I-180J-87D01*
G01Y1130822D01*
G02X1099613Y1130650I-200J1D01*
G01X1099361Y1130505D01*
G02X1099261Y1130478I-100J173D01*
G01X1099209D01*
X1099162Y1130506D01*
G03X1098524Y1130681I-638J-1077D01*
G01X1098495D01*
G03X1097271Y1129429I28J-1252D01*
G03X1098523Y1128177I1252J0D01*
G01X1098524D01*
G03X1099162Y1128352I0J1252D01*
G01X1099185Y1128366D01*
X1099237Y1128380D01*
X1099262D01*
G02X1099362Y1128353I0J-200D01*
G01X1099486Y1128282D01*
X1099611Y1128210D01*
G02X1099676Y1128150I-100J-174D01*
G02X1099686Y1128133I-167J-110D01*
G01X1099692Y1128121D01*
G02X1099712Y1128035I-180J-87D01*
G01Y1127081D01*
G02X1099613Y1126909I-200J1D01*
G01X1099361Y1126764D01*
G02X1099261Y1126737I-100J173D01*
G01X1099209D01*
X1099162Y1126765D01*
G03X1098524Y1126940I-638J-1077D01*
G01X1098495D01*
G03X1097271Y1125688I28J-1252D01*
G03X1098523Y1124436I1252J0D01*
G01X1098524D01*
G03X1099162Y1124611I0J1252D01*
G01X1099185Y1124625D01*
X1099237Y1124639D01*
X1099262D01*
G02X1099362Y1124612I0J-200D01*
G01X1099486Y1124541D01*
X1099611Y1124469D01*
G02X1099676Y1124409I-100J-174D01*
G02X1099686Y1124392I-167J-110D01*
G01X1099692Y1124380D01*
G02X1099712Y1124294I-180J-87D01*
G01Y1123537D01*
G03X1099771Y1123395I200J0D01*
G01X1099886Y1123280D01*
G02X1099940Y1123173I-143J-139D01*
G02X1099943Y1123140I-197J-35D01*
G01Y1122735D01*
Y1122721D01*
G02X1099813Y1122547I-200J14D01*
G01X1099799Y1122543D01*
G02X1099672Y1122547I-58J192D01*
G01X1099643Y1122558D01*
X1099594Y1122598D01*
X1099575Y1122627D01*
G03X1098523Y1123200I-1052J-679D01*
G03Y1120696I0J-1252D01*
G01X1098524D01*
G03X1099273Y1120945I0J1252D01*
G01X1099298Y1120964D01*
X1099418Y1121005D01*
G02X1099507Y1120985I2J-200D01*
G01X1099830Y1120828D01*
G02X1099861Y1120810I-84J-181D01*
G02X1099941Y1120674I-118J-161D01*
G02X1099943Y1120648I-198J-28D01*
G01Y1119508D01*
G02X1099941Y1119482I-200J2D01*
G02X1099861Y1119346I-198J25D01*
G02X1099830Y1119328I-115J163D01*
G01X1099507Y1119171D01*
G02X1099418Y1119151I-87J180D01*
G01X1099297Y1119193D01*
X1099283Y1119203D01*
G03X1098523Y1119460I-760J-995D01*
G03Y1116956I0J-1252D01*
G03X1099565Y1117513I0J1253D01*
G01X1099576Y1117530D01*
G02X1099787Y1117616I168J-109D01*
G01X1099833Y1117603D01*
X1099864Y1117593D01*
X1099903Y1117541D01*
G02X1099943Y1117421I-160J-120D01*
G01Y1117158D01*
G02X1099898Y1117032I-200J0D01*
G02X1099885Y1117017I-157J123D01*
G01X1098646Y1115778D01*
G02X1098584Y1115736I-141J142D01*
G01X1098548Y1115720D01*
X1098508D01*
G03X1097309Y1114775I15J-1252D01*
G02X1097297Y1114741I-194J49D01*
G02X1097115Y1114624I-182J83D01*
G01X1096191D01*
G02X1096009Y1114741I0J200D01*
G02X1095997Y1114775I182J83D01*
G03X1093569I-1214J-307D01*
G02X1093557Y1114741I-194J49D01*
G02X1093375Y1114624I-182J83D01*
G01X1092451D01*
G02X1092269Y1114741I0J200D01*
G02X1092257Y1114775I182J83D01*
G03X1089829I-1214J-307D01*
G02X1089817Y1114741I-194J49D01*
G02X1089635Y1114624I-182J83D01*
G01X1088641D01*
X1088533Y1114708D01*
X1088516Y1114775D01*
G03X1086088I-1214J-307D01*
G01X1086071Y1114708D01*
X1085963Y1114624D01*
X1084961D01*
G02X1084885Y1114639I0J200D01*
G01X1084859Y1114650D01*
G03X1084804Y1114664I-76J-185D01*
G01X1084776Y1114775D01*
G03X1083562Y1115720I-1214J-307D01*
G03X1082358Y1114810I0J-1251D01*
G01Y1114809D01*
G02X1082166Y1114665I-192J56D01*
G01X1081219D01*
G02X1081098Y1114706I0J200D01*
G01X1081071Y1114726D01*
X1081035Y1114778D01*
X1081026Y1114811D01*
G03X1078618I-1204J-342D01*
G01X1078609Y1114778D01*
X1078573Y1114726D01*
X1078546Y1114706D01*
G02X1078425Y1114665I-121J159D01*
G01X1077479D01*
G02X1077358Y1114706I0J200D01*
G01X1077331Y1114726D01*
X1077295Y1114778D01*
X1077286Y1114811D01*
G03X1076082Y1115720I-1204J-343D01*
G03X1075157Y1115312I0J-1253D01*
G01X1075154Y1115308D01*
X1075149Y1115303D01*
G02X1074869Y1115304I-139J144D01*
G01X1074868Y1115305D01*
X1074731Y1115442D01*
G02X1074687Y1115509I142J141D01*
G01X1074673Y1115543D01*
Y1122350D01*
G02X1074676Y1122383I200J-2D01*
G02X1074730Y1122490I197J-32D01*
G01X1075137Y1122897D01*
G02X1075261Y1122955I142J-141D01*
G01X1075299D01*
G03X1075419Y1122948I130J1195D01*
G01X1077780D01*
G02X1077892Y1122913I-1J-200D01*
G03X1078570Y1122704I677J993D01*
G01X1081860D01*
X1081862D01*
G03X1081927Y1122705I14J1201D01*
G01X1081974Y1122708D01*
X1082060Y1122671D01*
X1082328Y1122355D01*
X1082350Y1122266D01*
X1082345Y1122240D01*
G03X1082310Y1121948I1216J-294D01*
G03X1083562Y1123200I1252J0D01*
G03X1083371Y1123185I2J-1252D01*
G01X1083331Y1123180D01*
X1083298Y1123194D01*
X1083282Y1123200D01*
G02X1083204Y1123256I74J186D01*
G01X1083062Y1123438D01*
G02X1083026Y1123610I158J123D01*
G03X1083062Y1123887I-1165J292D01*
G01X1083116Y1123941D01*
G03X1083175Y1124083I-141J142D01*
G01Y1127726D01*
G02X1083225Y1127859I200J1D01*
G01X1083432Y1128067D01*
G02X1083497Y1128111I142J-140D01*
G01X1083530Y1128125D01*
X1083572Y1128126D01*
G03X1084864Y1129428I-10J1302D01*
G03X1084650Y1130143I-1301J0D01*
G01X1084633Y1130169D01*
X1084625Y1130195D01*
G02X1084617Y1130252I192J56D01*
G01Y1130621D01*
G03X1084558Y1130763I-200J0D01*
G01X1080910Y1134411D01*
G03X1080768Y1134470I-142J-141D01*
G01X1076817D01*
G02X1076617Y1134670I0J200D01*
G01Y1136060D01*
G02X1076620Y1136093I200J-2D01*
G02X1076674Y1136200I197J-32D01*
G01X1076993Y1136519D01*
G02X1077100Y1136573I139J-143D01*
G02X1077133Y1136576I35J-197D01*
G01X1078471D01*
G02X1078584Y1136541I0J-200D01*
G01X1078608Y1136524D01*
X1078645Y1136478D01*
X1078657Y1136449D01*
G03X1080987I1165J461D01*
G01Y1136450D01*
G02X1081061Y1136542I186J-74D01*
G01X1081085Y1136559D01*
X1081142Y1136576D01*
X1082157D01*
G02X1082326Y1136483I0J-200D01*
G01X1082342Y1136450D01*
X1082345Y1136443D01*
G03X1083562Y1135604I1217J464D01*
G01X1087302D01*
G03Y1138210I0J1303D01*
G01X1084817D01*
G02X1084617Y1138410I0J200D01*
G01Y1139824D01*
G02X1084647Y1139929I200J0D01*
G03Y1141369I-1084J720D01*
G02X1084617Y1141474I170J105D01*
G01Y1143564D01*
G02X1084647Y1143669I200J0D01*
G03X1084650Y1145104I-1084J720D01*
G01X1084633Y1145130D01*
X1084625Y1145156D01*
G02X1084617Y1145213I192J56D01*
G01Y1145307D01*
G02X1084621Y1145345I200J-2D01*
G02X1084674Y1145447I196J-37D01*
G01X1085821Y1146594D01*
G02X1085961Y1146651I140J-143D01*
G01X1086014D01*
G03X1086039Y1146650I61J1200D01*
G01X1088207D01*
G03X1088232Y1146651I-36J1201D01*
G01X1088801D01*
G03X1088943Y1146710I0J200D01*
G01X1089564Y1147331D01*
G03X1089623Y1147473I-141J142D01*
G01Y1167514D01*
G02X1089627Y1167552I200J-2D01*
G02X1089680Y1167654I196J-37D01*
G01X1089766Y1167740D01*
G02X1089868Y1167793I139J-143D01*
G02X1089906Y1167797I40J-196D01*
G01X1091819D01*
G02X1091851Y1167794I-3J-200D01*
G01X1091853D01*
G02X1091959Y1167740I-34J-197D01*
G01X1092470Y1167229D01*
G02X1092518Y1167150I-142J-141D01*
G01X1092520Y1167144D01*
G02X1092528Y1167099I-192J-57D01*
G01Y1147528D01*
G03X1092587Y1147386I200J0D01*
G01X1093514Y1146459D01*
G03X1093656Y1146400I142J141D01*
G01X1098990D01*
G02X1099023Y1146397I-2J-200D01*
G02X1099130Y1146343I-32J-197D01*
G01X1099655Y1145818D01*
G02X1099709Y1145711I-143J-139D01*
G02X1099712Y1145678I-197J-35D01*
G01Y1142042D01*
G02X1099613Y1141870I-200J1D01*
G37*
G36*
G01X1060844Y1348187D02*
G03I-491J0D01*
G37*
G36*
G01X1065204D02*
G03I-491J0D01*
G37*
G36*
G01X1073084D02*
G03I-491J0D01*
G37*
G36*
G01X1060844Y1360099D02*
G03I-491J0D01*
G37*
G36*
G01X1065204D02*
G03I-491J0D01*
G37*
G36*
G01X1073084D02*
G03I-491J0D01*
G37*
G36*
G01X1060844Y1372385D02*
G03I-491J0D01*
G37*
G36*
G01X1065204D02*
G03I-491J0D01*
G37*
G36*
G01X1073084D02*
G03I-491J0D01*
G37*
G36*
G01X1060844Y1384297D02*
G03I-491J0D01*
G37*
G36*
G01X1065204D02*
G03I-491J0D01*
G37*
G36*
G01X1073084D02*
G03I-491J0D01*
G37*
G36*
G01X1065204Y1396583D02*
G03I-491J0D01*
G37*
G36*
G01X1073084D02*
G03I-491J0D01*
G37*
G36*
G01Y1408495D02*
G03I-491J0D01*
G37*
G36*
G01X1065204D02*
G03I-491J0D01*
G37*
G36*
G01X1154193Y54588D02*
X1182695D01*
X1183133Y54150D01*
Y53029D01*
X1182695Y52591D01*
X1154193D01*
G03X1148256Y46654I0J-5937D01*
G01Y7874D01*
G02X1142382Y2000I-5874J0D01*
G01X1095138D01*
G02X1089264Y7874I0J5874D01*
G01Y46558D01*
X1091262D01*
Y7874D01*
G03X1095138Y3998I3876J0D01*
G01X1142382D01*
G03X1146258Y7874I0J3876D01*
G01Y46654D01*
G02X1154193Y54588I7935J-1D01*
G37*
G36*
G01X1077770Y1130999D02*
X1081691D01*
G02X1081833Y1130940I0J-200D01*
G01X1082003Y1130770D01*
G02X1082061Y1130629I-142J-141D01*
G01Y1123905D01*
G02X1081861Y1123705I-200J0D01*
G01X1078571D01*
G02X1078429Y1123764I0J200D01*
G01X1077326Y1124867D01*
X1077297Y1124895D01*
X1077267Y1124969D01*
Y1125147D01*
X1077283Y1125184D01*
G03X1077384Y1125688I-1201J503D01*
G03X1077283Y1126192I-1302J1D01*
G01X1077267Y1126229D01*
Y1128888D01*
X1077283Y1128925D01*
G03X1077384Y1129429I-1201J503D01*
G03X1077283Y1129933I-1302J1D01*
G01X1077267Y1129970D01*
Y1130496D01*
G02X1077326Y1130638I200J0D01*
G01X1077628Y1130940D01*
G02X1077770Y1130999I142J-141D01*
G37*
G36*
G01X1086006Y1167697D02*
X1088240D01*
G02X1088382Y1167638I0J-200D01*
G01X1088563Y1167457D01*
G02X1088621Y1167316I-142J-141D01*
G01Y1148078D01*
G02X1088562Y1147936I-200J0D01*
G01X1088337Y1147711D01*
G02X1088227Y1147654I-143J141D01*
G02X1088195Y1147652I-28J198D01*
G01X1086051D01*
G02X1086019Y1147654I-4J200D01*
G02X1085909Y1147711I33J198D01*
G01X1085382Y1148238D01*
X1085353Y1148266D01*
X1085323Y1148340D01*
Y1155227D01*
X1085327Y1155247D01*
G03X1085364Y1155610I-1765J363D01*
G03X1085327Y1155973I-1802J0D01*
G01X1085323Y1155993D01*
Y1167014D01*
G02X1085382Y1167156I200J0D01*
G01X1085864Y1167638D01*
G02X1086006Y1167697I142J-141D01*
G37*
G36*
G01X1086381Y1182697D02*
X1088280D01*
X1088354Y1182667D01*
X1088382Y1182638D01*
X1088563Y1182457D01*
G02X1088621Y1182316I-142J-141D01*
G01Y1171465D01*
G03X1088672Y1171332I200J0D01*
G01X1088697Y1171304D01*
X1088723Y1171236D01*
Y1170440D01*
X1088693Y1170366D01*
X1088664Y1170338D01*
X1088082Y1169756D01*
G02X1087940Y1169697I-142J141D01*
G01X1086066D01*
X1085992Y1169727D01*
X1085964Y1169756D01*
X1085582Y1170138D01*
G02X1085523Y1170280I141J142D01*
G01Y1182260D01*
X1085613Y1182370D01*
X1085684Y1182384D01*
G03X1086255Y1182652I-251J1277D01*
G02X1086381Y1182697I126J-155D01*
G37*
G36*
G01X1092500Y1172164D02*
X1092016Y1171680D01*
G02X1091763Y1171654I-142J141D01*
G03X1091043Y1171872I-721J-1083D01*
G01X1091042D01*
G03X1090291Y1171634I0J-1302D01*
G01X1090266Y1171615D01*
X1090208Y1171597D01*
X1089906D01*
G02X1089764Y1171656I0J200D01*
G01X1089682Y1171738D01*
X1089653Y1171766D01*
X1089623Y1171840D01*
Y1182814D01*
G02X1089682Y1182956I200J0D01*
G01X1089764Y1183038D01*
G02X1089906Y1183097I142J-141D01*
G01X1092240D01*
G02X1092382Y1183038I0J-200D01*
G01X1092500Y1182920D01*
G02X1092559Y1182778I-141J-142D01*
G01Y1172306D01*
G02X1092500Y1172164I-200J0D01*
G37*
G36*
G01X1077444Y1348187D02*
G03I-491J0D01*
G37*
G36*
G01X1085324D02*
G03I-491J0D01*
G37*
G36*
G01X1089684D02*
G03I-491J0D01*
G37*
G36*
G01X1077444Y1360099D02*
G03I-491J0D01*
G37*
G36*
G01X1085324D02*
G03I-491J0D01*
G37*
G36*
G01X1089684D02*
G03I-491J0D01*
G37*
G36*
G01X1077444Y1372385D02*
G03I-491J0D01*
G37*
G36*
G01X1085324D02*
G03I-491J0D01*
G37*
G36*
G01X1089684D02*
G03I-491J0D01*
G37*
G36*
G01X1077444Y1384297D02*
G03I-491J0D01*
G37*
G36*
G01Y1396583D02*
G03I-491J0D01*
G37*
G36*
G01X1085324Y1384297D02*
G03I-491J0D01*
G37*
G36*
G01X1089684D02*
G03I-491J0D01*
G37*
G36*
G01X1085324Y1396583D02*
G03I-491J0D01*
G37*
G36*
G01X1089684D02*
G03I-491J0D01*
G37*
G36*
G01X1077444Y1408495D02*
G03I-491J0D01*
G37*
G36*
G01X1085324D02*
G03I-491J0D01*
G37*
G36*
G01X1089684D02*
G03I-491J0D01*
G37*
G36*
G01X1104580Y1565888D02*
X1104943Y1565939D01*
G02X1105112Y1565882I27J-198D01*
G01X1105640Y1565355D01*
G02X1105698Y1565213I-142J-141D01*
G01Y1540184D01*
G02X1105498Y1539984I-200J0D01*
G01X1095120D01*
G02X1094978Y1540043I0J200D01*
G01X1091205Y1543816D01*
G02X1091163Y1544035I142J141D01*
G01X1091332Y1544433D01*
X1091433Y1544499D01*
X1091495Y1544498D01*
X1091525D01*
G03X1089723Y1546300I0J1802D01*
G01Y1546270D01*
X1089724Y1546208D01*
X1089658Y1546107D01*
X1089260Y1545938D01*
G02X1089041Y1545980I-78J184D01*
G01X1088084Y1546937D01*
G02X1088026Y1547078I142J141D01*
G01Y1555890D01*
G02X1088084Y1556031I200J0D01*
G01X1091521Y1559468D01*
X1091589Y1559498D01*
X1091628Y1559499D01*
G03X1093371Y1561300I-59J1801D01*
G03X1091569Y1563102I-1802J0D01*
G03X1091435Y1563097I0J-1802D01*
G01X1091372Y1563092D01*
X1091265Y1563156D01*
X1091082Y1563554D01*
G02X1091123Y1563779I182J83D01*
G01X1092692Y1565348D01*
G02X1092833Y1565406I141J-142D01*
G01X1101536D01*
G02X1101672Y1565353I0J-200D01*
G03X1102904Y1564866I1232J1315D01*
G03X1104480Y1565794I0J1802D01*
G01X1104503Y1565835D01*
X1104580Y1565888D01*
G37*
G36*
G01X1095272Y576249D02*
X1099015D01*
X1100456D01*
X1101695D01*
X1102554Y575390D01*
Y549500D01*
X1102054Y549000D01*
X1096694D01*
X1096194Y549500D01*
Y559538D01*
X1095201Y560531D01*
Y576178D01*
X1095272Y576249D01*
G37*
G36*
G01X1099412Y1192000D02*
X1100390D01*
G02X1100532Y1191941I0J-200D01*
G01X1101014Y1191459D01*
G02X1101073Y1191317I-141J-142D01*
G01Y1187283D01*
G02X1101014Y1187141I-200J0D01*
G01X1100932Y1187059D01*
G02X1100790Y1187000I-142J141D01*
G01X1097456D01*
G03X1097314Y1186941I0J-200D01*
G01X1096432Y1186059D01*
G03X1096373Y1185917I141J-142D01*
G01Y1176483D01*
G03X1096432Y1176341I200J0D01*
G01X1097814Y1174959D01*
G02X1097873Y1174817I-141J-142D01*
G01Y1173083D01*
G02X1097814Y1172941I-200J0D01*
G01X1096332Y1171459D01*
G03X1096273Y1171317I141J-142D01*
G01Y1150583D01*
G03X1096332Y1150441I200J0D01*
G01X1097714Y1149059D01*
G02X1097773Y1148917I-141J-142D01*
G01Y1147602D01*
G02X1097573Y1147402I-200J0D01*
G01X1094254D01*
G02X1094113Y1147460I0J200D01*
G01X1093588Y1147985D01*
G02X1093529Y1148126I141J142D01*
G01Y1167089D01*
G03X1093481Y1167426I-1201J1D01*
G01X1093473Y1167453D01*
Y1171854D01*
X1093485Y1171888D01*
G03X1093561Y1172305I-1126J421D01*
G01Y1182779D01*
G03X1093485Y1183196I-1202J-4D01*
G01X1093473Y1183230D01*
Y1186105D01*
G02X1093572Y1186278I200J0D01*
G03Y1188524I-659J1123D01*
G02X1093473Y1188697I101J173D01*
G01Y1189517D01*
G02X1093532Y1189659I200J0D01*
G01X1095814Y1191941D01*
G02X1095956Y1192000I142J-141D01*
G01X1097634D01*
G02X1097753Y1191961I0J-200D01*
G03X1099293I770J1050D01*
G02X1099412Y1192000I119J-161D01*
G37*
G36*
G01X1104054Y1186298D02*
X1107273D01*
G02X1107418Y1186236I0J-200D01*
G01X1107647Y1185994D01*
X1107675Y1185918D01*
X1107672Y1185876D01*
G03X1107671Y1185850I451J-30D01*
G01Y1184350D01*
G03X1108123Y1183898I452J0D01*
G01X1109323D01*
G03X1109461Y1183920I-1J452D01*
G01X1109490Y1183929D01*
X1109521D01*
G02X1109721Y1183729I0J-200D01*
G01Y1182719D01*
G03X1109979Y1181977I1202J2D01*
G02X1110044Y1181792I-236J-187D01*
G01X1110043Y1181791D01*
X1110044Y1181790D01*
G02X1109979Y1181605I-301J2D01*
G03X1109721Y1180863I944J-744D01*
G01Y1179652D01*
G02X1109521Y1179452I-199J-1D01*
G01X1108323D01*
G03X1107871Y1179000I0J-452D01*
G01Y1177500D01*
G03X1108323Y1177048I452J0D01*
G01X1108929D01*
G02X1109041Y1177014I1J-200D01*
G03X1109743Y1176799I702J1037D01*
G03X1110230Y1176898I-1J1252D01*
G01X1110287Y1176921D01*
X1110405Y1176898D01*
X1110855Y1176448D01*
G03X1111399Y1176135I851J849D01*
G01X1111425Y1176128D01*
X1111471Y1176102D01*
X1111714Y1175859D01*
G03X1111856Y1175800I142J141D01*
G01X1112243D01*
G02X1112425Y1175682I0J-200D01*
G01X1112599Y1175297D01*
X1112582Y1175180D01*
X1112543Y1175136D01*
G03X1112232Y1174310I941J-826D01*
G03X1112276Y1173983I1252J2D01*
G01X1112283Y1173957D01*
Y1172890D01*
G03X1112734Y1172438I452J0D01*
G01X1114234D01*
G03X1114685Y1172890I0J451D01*
G01Y1173957D01*
X1114692Y1173983D01*
G03X1114736Y1174310I-1208J329D01*
G03X1114425Y1175136I-1252J0D01*
G01X1114386Y1175180D01*
X1114369Y1175297D01*
X1114543Y1175682D01*
G02X1114725Y1175800I182J-82D01*
G01X1119723D01*
G02X1119905Y1175682I0J-200D01*
G01X1120079Y1175297D01*
X1120062Y1175180D01*
X1120023Y1175136D01*
G03X1119712Y1174310I941J-826D01*
G03X1119756Y1173983I1252J2D01*
G01X1119763Y1173957D01*
Y1172890D01*
G03X1120214Y1172438I452J0D01*
G01X1121714D01*
G03X1122165Y1172890I0J451D01*
G01Y1173957D01*
X1122172Y1173983D01*
G03X1122216Y1174310I-1208J329D01*
G03X1121905Y1175136I-1252J0D01*
G01X1121866Y1175180D01*
X1121849Y1175297D01*
X1122023Y1175682D01*
G02X1122205Y1175800I182J-82D01*
G01X1127203D01*
G02X1127385Y1175682I0J-200D01*
G01X1127559Y1175297D01*
X1127542Y1175180D01*
X1127503Y1175136D01*
G03X1127192Y1174310I941J-826D01*
G03X1127236Y1173983I1252J2D01*
G01X1127243Y1173957D01*
Y1172890D01*
G03X1127694Y1172438I452J0D01*
G01X1129194D01*
G03X1129645Y1172890I0J451D01*
G01Y1173957D01*
X1129652Y1173983D01*
G03X1129696Y1174310I-1208J329D01*
G03X1129385Y1175136I-1252J0D01*
G01X1129346Y1175180D01*
X1129329Y1175297D01*
X1129503Y1175682D01*
G02X1129685Y1175800I182J-82D01*
G01X1134683D01*
G02X1134865Y1175682I0J-200D01*
G01X1135039Y1175297D01*
X1135022Y1175180D01*
X1134983Y1175136D01*
G03X1134672Y1174310I941J-826D01*
G03X1134716Y1173980I1252J-1D01*
G01X1134723Y1173954D01*
Y1172890D01*
G03X1135175Y1172438I452J0D01*
G01X1136675D01*
G03X1137127Y1172890I0J452D01*
G01Y1173960D01*
X1137133Y1173986D01*
G03X1137176Y1174310I-1209J325D01*
G03X1136865Y1175136I-1252J0D01*
G01X1136826Y1175180D01*
X1136809Y1175297D01*
X1136983Y1175682D01*
G02X1137165Y1175800I182J-82D01*
G01X1142164D01*
G02X1142346Y1175682I0J-200D01*
G01X1142520Y1175297D01*
X1142503Y1175180D01*
X1142464Y1175136D01*
G03X1142153Y1174310I941J-826D01*
G03X1142248Y1173831I1252J-1D01*
G01X1142263Y1173794D01*
Y1172890D01*
G03X1142715Y1172438I452J0D01*
G01X1144215D01*
G03X1144667Y1172890I0J452D01*
G01Y1174090D01*
G03X1144658Y1174178I-452J-2D01*
G02X1144654Y1174230I196J41D01*
G03X1144657Y1174310I-1249J87D01*
G03X1144346Y1175136I-1252J0D01*
G01X1144307Y1175180D01*
X1144290Y1175297D01*
X1144464Y1175682D01*
G02X1144646Y1175800I182J-82D01*
G01X1153384D01*
G02X1153566Y1175682I0J-200D01*
G01X1153740Y1175297D01*
X1153723Y1175180D01*
X1153684Y1175136D01*
G03X1153373Y1174310I941J-826D01*
G03X1153417Y1173983I1252J2D01*
G01X1153423Y1173957D01*
Y1172890D01*
G03X1153875Y1172438I452J0D01*
G01X1155375D01*
G03X1155827Y1172890I0J452D01*
G01Y1173957D01*
X1155833Y1173983D01*
G03X1155877Y1174310I-1208J329D01*
G03X1155566Y1175136I-1252J0D01*
G01X1155527Y1175180D01*
X1155510Y1175297D01*
X1155684Y1175682D01*
G02X1155866Y1175800I182J-82D01*
G01X1160865D01*
G02X1161047Y1175682I0J-200D01*
G01X1161221Y1175297D01*
X1161204Y1175180D01*
X1161165Y1175136D01*
G03X1160854Y1174310I941J-826D01*
G03X1160898Y1173983I1252J2D01*
G01X1160905Y1173957D01*
Y1172890D01*
G03X1161356Y1172438I452J0D01*
G01X1162856D01*
G03X1163307Y1172890I0J451D01*
G01Y1173957D01*
X1163314Y1173983D01*
G03X1163358Y1174310I-1208J329D01*
G03X1163047Y1175136I-1252J0D01*
G01X1163008Y1175180D01*
X1162991Y1175297D01*
X1163165Y1175682D01*
G02X1163347Y1175800I182J-82D01*
G01X1168345D01*
G02X1168527Y1175682I0J-200D01*
G01X1168701Y1175297D01*
X1168684Y1175180D01*
X1168645Y1175136D01*
G03X1168334Y1174310I941J-826D01*
G03X1168378Y1173983I1252J2D01*
G01X1168385Y1173957D01*
Y1172890D01*
G03X1168836Y1172438I452J0D01*
G01X1170336D01*
G03X1170787Y1172890I0J451D01*
G01Y1173957D01*
X1170794Y1173983D01*
G03X1170838Y1174310I-1208J329D01*
G03X1170527Y1175136I-1252J0D01*
G01X1170488Y1175180D01*
X1170471Y1175297D01*
X1170645Y1175682D01*
G02X1170827Y1175800I182J-82D01*
G01X1173790D01*
G02X1173932Y1175741I0J-200D01*
G01X1174514Y1175159D01*
G02X1174573Y1175017I-141J-142D01*
G01Y1172836D01*
G02X1174506Y1172687I-200J0D01*
G01X1174251Y1172459D01*
X1174171Y1172434D01*
X1174127Y1172439D01*
G03X1174076Y1172442I-52J-449D01*
G01X1172576D01*
G03X1172125Y1171990I0J-451D01*
G01Y1170923D01*
X1172118Y1170897D01*
G03X1172074Y1170570I1208J-329D01*
G03X1173326Y1169318I1252J0D01*
G03X1173968Y1169495I0J1253D01*
G01X1174015Y1169523D01*
X1174122Y1169524D01*
X1174472Y1169326D01*
G02X1174573Y1169152I-99J-174D01*
G01Y1160768D01*
G02X1174472Y1160594I-200J0D01*
G01X1174122Y1160396D01*
X1174015Y1160397D01*
X1173968Y1160425D01*
G03X1173326Y1160602I-642J-1076D01*
G03X1172074Y1159350I0J-1252D01*
G03X1172118Y1159023I1252J2D01*
G01X1172125Y1158997D01*
Y1157930D01*
G03X1172576Y1157478I452J0D01*
G01X1174076D01*
G03X1174127Y1157481I-1J452D01*
G01X1174171Y1157486D01*
X1174251Y1157461D01*
X1174506Y1157233D01*
G02X1174573Y1157084I-133J-149D01*
G01Y1155683D01*
G02X1174514Y1155541I-200J0D01*
G01X1173733Y1154760D01*
G02X1173592Y1154702I-141J142D01*
G01X1171158D01*
G02X1170996Y1154784I-1J200D01*
G01X1170777Y1155085D01*
X1170762Y1155178D01*
X1170777Y1155225D01*
G03X1170838Y1155610I-1191J386D01*
G03X1170794Y1155937I-1252J-2D01*
G01X1170787Y1155963D01*
Y1157030D01*
G03X1170336Y1157482I-452J0D01*
G01X1168836D01*
G03X1168385Y1157030I0J-451D01*
G01Y1155963D01*
X1168378Y1155937D01*
G03X1168334Y1155610I1208J-329D01*
G03X1168395Y1155225I1252J1D01*
G01X1168410Y1155178D01*
X1168395Y1155085D01*
X1168176Y1154784D01*
G02X1168014Y1154702I-161J118D01*
G01X1163678D01*
G02X1163516Y1154784I-1J200D01*
G01X1163297Y1155085D01*
X1163282Y1155178D01*
X1163297Y1155225D01*
G03X1163358Y1155610I-1191J386D01*
G03X1163314Y1155940I-1252J1D01*
G01X1163307Y1155966D01*
Y1157030D01*
G03X1162855Y1157482I-452J0D01*
G01X1161355D01*
G03X1160903Y1157030I0J-452D01*
G01Y1155960D01*
X1160897Y1155934D01*
G03X1160854Y1155610I1209J-325D01*
G03X1160915Y1155225I1252J1D01*
G01X1160930Y1155178D01*
X1160915Y1155085D01*
X1160696Y1154784D01*
G02X1160534Y1154702I-161J118D01*
G01X1156197D01*
G02X1156035Y1154784I-1J200D01*
G01X1155816Y1155085D01*
X1155801Y1155178D01*
X1155816Y1155225D01*
G03X1155877Y1155610I-1191J386D01*
G03X1155833Y1155937I-1252J-2D01*
G01X1155827Y1155963D01*
Y1157030D01*
G03X1155375Y1157482I-452J0D01*
G01X1153875D01*
G03X1153423Y1157030I0J-452D01*
G01Y1155963D01*
X1153417Y1155937D01*
G03X1153373Y1155610I1208J-329D01*
G03X1153434Y1155225I1252J1D01*
G01X1153449Y1155178D01*
X1153434Y1155085D01*
X1153215Y1154784D01*
G02X1153053Y1154702I-161J118D01*
G01X1144977D01*
G02X1144815Y1154784I-1J200D01*
G01X1144596Y1155085D01*
X1144581Y1155178D01*
X1144596Y1155225D01*
G03X1144657Y1155610I-1191J386D01*
G03X1144613Y1155937I-1252J-2D01*
G01X1144607Y1155963D01*
Y1157030D01*
G03X1144155Y1157482I-452J0D01*
G01X1142655D01*
G03X1142203Y1157030I0J-452D01*
G01Y1155963D01*
X1142197Y1155937D01*
G03X1142153Y1155610I1208J-329D01*
G03X1142214Y1155225I1252J1D01*
G01X1142229Y1155178D01*
X1142214Y1155085D01*
X1141995Y1154784D01*
G02X1141833Y1154702I-161J118D01*
G01X1137496D01*
G02X1137334Y1154784I-1J200D01*
G01X1137115Y1155085D01*
X1137100Y1155178D01*
X1137115Y1155225D01*
G03X1137176Y1155610I-1191J386D01*
G03X1137133Y1155934I-1252J-1D01*
G01X1137127Y1155960D01*
Y1157030D01*
G03X1136675Y1157482I-452J0D01*
G01X1135175D01*
G03X1134723Y1157030I0J-452D01*
G01Y1155966D01*
X1134716Y1155940D01*
G03X1134672Y1155610I1208J-329D01*
G03X1134733Y1155225I1252J1D01*
G01X1134748Y1155178D01*
X1134733Y1155085D01*
X1134514Y1154784D01*
G02X1134352Y1154702I-161J118D01*
G01X1130016D01*
G02X1129854Y1154784I-1J200D01*
G01X1129635Y1155085D01*
X1129620Y1155178D01*
X1129635Y1155225D01*
G03X1129696Y1155610I-1191J386D01*
G03X1129652Y1155937I-1252J-2D01*
G01X1129645Y1155963D01*
Y1157030D01*
G03X1129194Y1157482I-452J0D01*
G01X1127694D01*
G03X1127243Y1157030I0J-451D01*
G01Y1155963D01*
X1127236Y1155937D01*
G03X1127192Y1155610I1208J-329D01*
G03X1127253Y1155225I1252J1D01*
G01X1127268Y1155178D01*
X1127253Y1155085D01*
X1127034Y1154784D01*
G02X1126872Y1154702I-161J118D01*
G01X1122536D01*
G02X1122374Y1154784I-1J200D01*
G01X1122155Y1155085D01*
X1122140Y1155178D01*
X1122155Y1155225D01*
G03X1122216Y1155610I-1191J386D01*
G03X1122172Y1155937I-1252J-2D01*
G01X1122165Y1155963D01*
Y1157030D01*
G03X1121714Y1157482I-452J0D01*
G01X1120214D01*
G03X1119763Y1157030I0J-451D01*
G01Y1155963D01*
X1119756Y1155937D01*
G03X1119712Y1155610I1208J-329D01*
G03X1119773Y1155225I1252J1D01*
G01X1119788Y1155178D01*
X1119773Y1155085D01*
X1119554Y1154784D01*
G02X1119392Y1154702I-161J118D01*
G01X1115056D01*
G02X1114894Y1154784I-1J200D01*
G01X1114675Y1155085D01*
X1114660Y1155178D01*
X1114675Y1155225D01*
G03X1114736Y1155610I-1191J386D01*
G03X1114692Y1155937I-1252J-2D01*
G01X1114685Y1155963D01*
Y1157030D01*
G03X1114234Y1157482I-452J0D01*
G01X1112734D01*
G03X1112283Y1157030I0J-451D01*
G01Y1155963D01*
X1112276Y1155937D01*
G03X1112232Y1155610I1208J-329D01*
G03X1112410Y1154967I1252J0D01*
G01X1112445Y1154908D01*
X1112428Y1154772D01*
X1110581Y1152925D01*
X1110445Y1152908D01*
X1110386Y1152943D01*
G03X1109743Y1153121I-643J-1074D01*
G03X1109416Y1153077I2J-1252D01*
G01X1109390Y1153070D01*
X1108323D01*
G03X1107871Y1152619I0J-452D01*
G01Y1151119D01*
G03X1108323Y1150668I451J0D01*
G01X1109390D01*
X1109416Y1150661D01*
G03X1109743Y1150617I329J1208D01*
G03X1110144Y1150683I0J1251D01*
G01X1110190Y1150698D01*
X1110285Y1150684D01*
X1110535Y1150504D01*
Y1145754D01*
X1110285Y1145574D01*
X1110190Y1145560D01*
X1110144Y1145575D01*
G03X1109743Y1145641I-401J-1185D01*
G03X1109416Y1145597I2J-1252D01*
G01X1109390Y1145590D01*
X1108323D01*
G03X1107871Y1145139I0J-452D01*
G01Y1143639D01*
G03X1108323Y1143188I451J0D01*
G01X1109390D01*
X1109416Y1143181D01*
G03X1109743Y1143137I329J1208D01*
G03X1110371Y1143306I0J1251D01*
G01X1110394Y1143319D01*
X1110445Y1143333D01*
X1110471D01*
G02X1110671Y1143133I0J-200D01*
G01Y1142985D01*
X1110673Y1142984D01*
Y1142683D01*
G02X1110614Y1142541I-200J0D01*
G01X1110003Y1141930D01*
X1109930Y1141900D01*
X1109905D01*
G03X1109743Y1141910I-159J-1251D01*
G03X1109592Y1141901I-1J-1261D01*
G01X1109580Y1141900D01*
X1106166D01*
X1106154Y1141901D01*
G03X1106003Y1141910I-150J-1252D01*
G03X1105852Y1141901I-1J-1261D01*
G01X1105840Y1141900D01*
X1103956D01*
G02X1103814Y1141959I0J200D01*
G01X1103632Y1142141D01*
G02X1103573Y1142283I141J142D01*
G01Y1185817D01*
G02X1103632Y1185959I200J0D01*
G01X1103913Y1186240D01*
G02X1104054Y1186298I141J-142D01*
G37*
G36*
G01X1107892Y1187523D02*
G02X1107879Y1187508I-157J123D01*
G01X1107729Y1187358D01*
G02X1107662Y1187314I-141J142D01*
G01X1107628Y1187300D01*
X1103230D01*
G02X1103104Y1187345I0J200D01*
G02X1103089Y1187358I123J157D01*
G01X1102664Y1187783D01*
G02X1102620Y1187850I142J141D01*
G01X1102606Y1187884D01*
Y1191610D01*
G02X1102641Y1191723I200J0D01*
G01Y1191724D01*
G02X1102733Y1191796I164J-115D01*
G01X1102734Y1191797D01*
G03X1102766Y1191810I-474J1213D01*
G01X1102863D01*
G03X1103310Y1192198I0J451D01*
G02X1103342Y1192282I198J-27D01*
G03X1103565Y1193011I-1080J729D01*
G03X1103342Y1193739I-1301J0D01*
G02X1103310Y1193823I166J111D01*
G03X1103226Y1194029I-447J-62D01*
G01X1103207Y1194055D01*
X1103187Y1194115D01*
Y1194285D01*
X1103191Y1194289D01*
G02X1103301Y1194346I143J-141D01*
G02X1103326Y1194348I28J-198D01*
G01X1108441D01*
G02X1108641Y1194148I0J-200D01*
G01Y1193630D01*
X1108631Y1193586D01*
X1108620Y1193565D01*
G03X1108491Y1193011I1123J-554D01*
G03X1108620Y1192457I1252J0D01*
G01X1108631Y1192436D01*
X1108641Y1192392D01*
Y1192324D01*
G02X1108582Y1192182I-200J0D01*
G01X1107996Y1191596D01*
G03X1107937Y1191454I141J-142D01*
G01Y1187649D01*
G02X1107892Y1187523I-200J0D01*
G37*
G36*
G01X1109288Y1197625D02*
X1109880D01*
G02X1110022Y1197566I0J-200D01*
G01X1110152Y1197435D01*
G03X1110294Y1197376I142J141D01*
G01X1181423D01*
G02X1181623Y1197176I0J-200D01*
G01Y1196462D01*
X1181593Y1196388D01*
X1181564Y1196360D01*
X1180612Y1195408D01*
G02X1180471Y1195350I-141J142D01*
G01X1110955D01*
G03X1110925Y1195349I25J-1201D01*
G01X1103871D01*
X1103797Y1195379D01*
X1103769Y1195408D01*
X1103692Y1195485D01*
G02X1103633Y1195627I141J142D01*
G01Y1196336D01*
X1103708Y1196440D01*
X1103770Y1196461D01*
G03X1104645Y1197002I-707J2122D01*
G01X1105151Y1197507D01*
G02X1105293Y1197566I142J-141D01*
G01X1109066D01*
G03X1109143Y1197581I1J200D01*
G01X1109211Y1197610D01*
G02X1109288Y1197625I76J-185D01*
G37*
G36*
G01X1097564Y1348187D02*
G03I-491J0D01*
G37*
G36*
G01X1101924D02*
G03I-491J0D01*
G37*
G36*
G01X1097564Y1360099D02*
G03I-491J0D01*
G37*
G36*
G01X1101924D02*
G03I-491J0D01*
G37*
G36*
G01X1097564Y1372385D02*
G03I-491J0D01*
G37*
G36*
G01X1101924D02*
G03I-491J0D01*
G37*
G36*
G01X1097564Y1384297D02*
G03I-491J0D01*
G37*
G36*
G01X1101924D02*
G03I-491J0D01*
G37*
G36*
G01X1097564Y1396583D02*
G03I-491J0D01*
G37*
G36*
G01X1101924D02*
G03I-491J0D01*
G37*
G36*
G01X1097564Y1408495D02*
G03I-491J0D01*
G37*
G36*
G01X1101924D02*
G03I-491J0D01*
G37*
G36*
G01X1112906Y1134697D02*
X1181440D01*
G02X1181582Y1134638I0J-200D01*
G01X1181864Y1134356D01*
G02X1181923Y1134214I-141J-142D01*
G01Y1132980D01*
G02X1181864Y1132838I-200J0D01*
G01X1181483Y1132457D01*
G02X1181342Y1132398I-142J141D01*
G01X1113004D01*
G02X1112863Y1132457I1J200D01*
G01X1112582Y1132738D01*
G02X1112523Y1132880I141J142D01*
G01Y1134314D01*
G02X1112582Y1134456I200J0D01*
G01X1112764Y1134638D01*
G02X1112906Y1134697I142J-141D01*
G37*
G36*
G01X1112653Y1141927D02*
X1112663Y1141937D01*
G02X1112804Y1141996I142J-141D01*
G01X1181742D01*
G02X1181883Y1141937I-1J-200D01*
G01X1181893Y1141927D01*
X1181923Y1141854D01*
Y1139998D01*
G02X1181723Y1139798I-200J0D01*
G01X1113104D01*
G02X1112963Y1139857I1J200D01*
G01X1112682Y1140138D01*
G02X1112623Y1140280I141J142D01*
G01Y1141854D01*
X1112653Y1141927D01*
G37*
G36*
G01X1190616Y1127129D02*
X1191772D01*
G02X1191914Y1127070I0J-200D01*
G01X1192232Y1126752D01*
X1192657Y1126326D01*
X1192658D01*
X1192864Y1126120D01*
G02X1192923Y1125978I-141J-142D01*
G01Y1125091D01*
G02X1192864Y1124949I-200J0D01*
G01X1192802Y1124887D01*
X1192722Y1124856D01*
X1192679Y1124859D01*
G03X1192601Y1124862I-87J-1259D01*
G01X1165000D01*
G03X1164277Y1124634I0J-1262D01*
G02X1164197Y1124601I-114J164D01*
G03X1163915Y1124514I221J-1217D01*
G01X1163877Y1124497D01*
X1160182D01*
G02X1160050Y1124547I0J200D01*
G03X1159216Y1124862I-834J-947D01*
G01X1150300D01*
G03X1149408Y1124492I1J-1262D01*
G01X1148408Y1123492D01*
G03X1148038Y1122600I892J-893D01*
G01Y1122492D01*
G02X1147838Y1122292I-200J0D01*
G01X1145533D01*
G02X1145391Y1122351I0J200D01*
G01X1143304Y1124438D01*
G03X1143162Y1124497I-142J-141D01*
G01X1111140D01*
G02X1110998Y1124556I0J200D01*
G01X1110854Y1124700D01*
G02X1110805Y1124900I142J141D01*
G01X1110823Y1124960D01*
X1110838Y1124983D01*
G03X1111045Y1125690I-1095J704D01*
G01Y1125715D01*
G03X1110653Y1126619I-1302J-27D01*
G01X1110624Y1126648D01*
X1110593Y1126721D01*
Y1126806D01*
G02X1110793Y1127006I200J0D01*
G01X1183617D01*
G03X1183754Y1127061I-1J200D01*
G01X1183759Y1127066D01*
X1183779Y1127083D01*
G02X1183907Y1127129I128J-154D01*
G01X1185853D01*
G03X1185863Y1127128I124J1193D01*
G01X1190581D01*
G03X1190613Y1127129I-22J1201D01*
G01X1190616D01*
G37*
G36*
G01X1143742Y1131397D02*
X1182711D01*
G02X1182853Y1131338I0J-200D01*
G01X1183341Y1130850D01*
G02X1183400Y1130708I-141J-142D01*
G01Y1130072D01*
X1183390Y1130028D01*
X1183379Y1130007D01*
G03X1183244Y1129429I1167J-577D01*
G03X1183379Y1128851I1302J-1D01*
G01X1183390Y1128830D01*
X1183400Y1128786D01*
Y1128206D01*
G02X1183341Y1128064I-200J0D01*
G01X1183315Y1128038D01*
X1183242Y1128008D01*
X1110994D01*
G02X1110852Y1128067I0J200D01*
G01X1110836Y1128083D01*
Y1128692D01*
X1110850Y1128743D01*
X1110864Y1128766D01*
G03X1111045Y1129429I-1121J662D01*
G03X1110997Y1129779I-1302J0D01*
G02X1111008Y1129916I193J53D01*
G01X1111059Y1130027D01*
G02X1111155Y1130125I182J-82D01*
G03X1111499Y1130368I-531J1117D01*
G01X1112143Y1131012D01*
G03X1112354Y1131293I-873J875D01*
G01X1112381Y1131342D01*
X1112474Y1131397D01*
X1143264D01*
X1143281Y1131394D01*
G03X1143503Y1131375I222J1283D01*
G03X1143725Y1131394I0J1302D01*
G01X1143742Y1131397D01*
G37*
G36*
G01X1112906Y1138797D02*
X1181640D01*
G02X1181782Y1138738I0J-200D01*
G01X1182064Y1138456D01*
G02X1182123Y1138314I-141J-142D01*
G01Y1135980D01*
G02X1182064Y1135838I-200J0D01*
G01X1181983Y1135757D01*
G02X1181842Y1135698I-142J141D01*
G01X1112623D01*
G02X1112423Y1135898I0J200D01*
G01Y1138314D01*
G02X1112482Y1138456I200J0D01*
G01X1112764Y1138738D01*
G02X1112906Y1138797I142J-141D01*
G37*
G36*
G01X1176256Y1172100D02*
X1185690D01*
G02X1185832Y1172041I0J-200D01*
G01X1186014Y1171859D01*
G02X1186073Y1171717I-141J-142D01*
G01Y1158483D01*
G03X1186132Y1158341I200J0D01*
G01X1187064Y1157409D01*
G02X1187123Y1157267I-141J-142D01*
G01Y1156072D01*
X1187111Y1156039D01*
G03X1187035Y1155610I1176J-430D01*
G03X1187111Y1155181I1252J1D01*
G01X1187123Y1155148D01*
Y1152331D01*
X1187111Y1152298D01*
G03X1187035Y1151869I1176J-430D01*
G03X1187111Y1151440I1252J1D01*
G01X1187123Y1151407D01*
Y1148591D01*
X1187111Y1148558D01*
G03X1187035Y1148129I1176J-430D01*
G03X1187111Y1147700I1252J1D01*
G01X1187123Y1147667D01*
Y1144851D01*
X1187111Y1144818D01*
G03X1187035Y1144389I1176J-430D01*
G03X1187111Y1143960I1252J1D01*
G01X1187123Y1143927D01*
Y1142833D01*
G02X1187064Y1142691I-200J0D01*
G01X1186832Y1142459D01*
G02X1186690Y1142400I-142J141D01*
G01X1182854D01*
X1182754Y1142468D01*
X1182743Y1142493D01*
X1182592Y1142645D01*
G03X1182183Y1142913I-849J-850D01*
G01X1182144Y1142929D01*
X1182132Y1142941D01*
G03X1181990Y1143000I-142J-141D01*
G01X1112156D01*
G02X1112014Y1143059I0J200D01*
G01X1111732Y1143341D01*
X1111703Y1143369D01*
X1111673Y1143443D01*
Y1152517D01*
G02X1111732Y1152659I200J0D01*
G01X1112714Y1153641D01*
G02X1112856Y1153700I142J-141D01*
G01X1175190D01*
G03X1175332Y1153759I0J200D01*
G01X1175915Y1154342D01*
G03X1175958Y1154407I-142J141D01*
G01X1175970Y1154434D01*
X1176019Y1154488D01*
X1176236Y1154594D01*
X1176341Y1154588D01*
X1176385Y1154559D01*
G03X1177066Y1154358I680J1051D01*
G03X1178318Y1155610I0J1252D01*
G03X1178281Y1155912I-1251J0D01*
G01X1178275Y1155936D01*
Y1157030D01*
G03X1177823Y1157482I-452J0D01*
G01X1176323D01*
G03X1176262Y1157477I6J-451D01*
G01X1176261D01*
G03X1176219Y1157469I63J-447D01*
G01X1176049Y1157604D01*
G02X1175973Y1157761I124J157D01*
G01Y1165331D01*
G02X1176066Y1165499I200J-1D01*
G01X1176393Y1165708D01*
X1176495Y1165715D01*
X1176541Y1165693D01*
G03X1177066Y1165578I524J1137D01*
G03X1177392Y1165621I1J1252D01*
G01X1177417Y1165628D01*
X1177953D01*
X1178486D01*
G03X1178937Y1166080I0J451D01*
G01Y1166830D01*
X1178938D01*
Y1167580D01*
G03X1178487Y1168032I-452J0D01*
G01X1177417D01*
X1177392Y1168039D01*
G03X1177066Y1168082I-325J-1209D01*
G03X1176541Y1167967I-1J-1252D01*
G01X1176495Y1167945D01*
X1176393Y1167952D01*
X1176066Y1168161D01*
G02X1175973Y1168329I107J169D01*
G01Y1171817D01*
G02X1176032Y1171959I200J0D01*
G01X1176114Y1172041D01*
G02X1176256Y1172100I142J-141D01*
G37*
G36*
G01X1109142Y1190090D02*
X1110866D01*
X1110871Y1190084D01*
X1181164D01*
G02X1181305Y1190026I0J-200D01*
G01X1181596Y1189735D01*
G02X1181598Y1189733I-140J-142D01*
G02X1181655Y1189593I-143J-140D01*
G01Y1188414D01*
G02X1181596Y1188272I-200J0D01*
G01X1181252Y1187928D01*
G02X1181111Y1187870I-141J142D01*
G01X1110352D01*
Y1187869D01*
X1109236D01*
G02X1109094Y1187928I0J200D01*
G01X1108997Y1188025D01*
G02X1108939Y1188166I142J141D01*
G01Y1189887D01*
G02X1108998Y1190029I200J0D01*
G01X1109004Y1190035D01*
X1109009Y1190039D01*
G02X1109142Y1190090I133J-149D01*
G37*
G36*
G01X1181637Y1186897D02*
X1182240D01*
G02X1182382Y1186838I0J-200D01*
G01X1183258Y1185962D01*
X1183286Y1185864D01*
X1183275Y1185814D01*
G03X1183244Y1185531I1271J-282D01*
G03X1183919Y1184390I1302J0D01*
G01X1183968Y1184363D01*
X1184023Y1184270D01*
Y1183052D01*
X1183968Y1182959D01*
X1183919Y1182932D01*
G03X1183452Y1181086I627J-1141D01*
G01Y1178757D01*
G03X1183244Y1178051I1094J-706D01*
G03X1183290Y1177707I1302J-1D01*
G01X1183305Y1177655D01*
X1183277Y1177551D01*
X1183157Y1177431D01*
G02X1183015Y1177372I-142J141D01*
G01X1181026D01*
G03X1180628Y1177175I1J-502D01*
G01X1180599Y1177138D01*
X1180516Y1177097D01*
X1111706D01*
G02X1111564Y1177156I0J200D01*
G01X1111044Y1177676D01*
X1111015Y1177769D01*
X1111024Y1177818D01*
G03X1111045Y1178051I-1282J233D01*
G03X1110766Y1178857I-1302J1D01*
G02X1110723Y1178980I157J124D01*
G01Y1180862D01*
G02X1110766Y1180985I200J-1D01*
G03X1111045Y1181791I-1023J805D01*
G03X1110766Y1182597I-1302J1D01*
G02X1110723Y1182720I157J124D01*
G01Y1184602D01*
G02X1110766Y1184725I200J-1D01*
G03X1111045Y1185531I-1023J805D01*
G03X1110766Y1186337I-1302J1D01*
G01X1110745Y1186364D01*
X1110723Y1186426D01*
Y1186714D01*
G02X1110782Y1186856I200J0D01*
G01X1110793Y1186868D01*
X1181608D01*
X1181637Y1186897D01*
G37*
G36*
G01X1184944Y1202947D02*
G02X1184753Y1202689I-191J-58D01*
G01X1184570D01*
X1184453Y1202806D01*
Y1202824D01*
X1115243D01*
X1109015D01*
X1108929Y1202910D01*
Y1204954D01*
X1109316Y1205341D01*
X1115192D01*
X1116245D01*
X1143399D01*
G03X1143541Y1205400I0J200D01*
G01X1145649Y1207508D01*
G02X1145791Y1207567I142J-141D01*
G01X1148591D01*
G02X1148733Y1207508I0J-200D01*
G01X1150782Y1205459D01*
G03X1150924Y1205400I142J141D01*
G01X1184965D01*
G02X1185107Y1205341I0J-200D01*
G01X1185476Y1204972D01*
G02X1185535Y1204830I-141J-142D01*
G01Y1204805D01*
G02X1185462Y1204650I-200J0D01*
G03X1184875Y1203412I1015J-1239D01*
G03X1184944Y1202947I1602J0D01*
G37*
G36*
G01X1183421Y1199440D02*
X1183392Y1199412D01*
X1182417Y1198437D01*
X1182389Y1198408D01*
X1182315Y1198378D01*
X1110710D01*
G02X1110568Y1198437I0J200D01*
G01X1110420Y1198585D01*
G02X1110400Y1198608I141J142D01*
G02X1110361Y1198727I161J119D01*
G01Y1199231D01*
G02X1110452Y1199399I200J0D01*
G03X1111045Y1200491I-709J1092D01*
G03X1110832Y1201203I-1302J-2D01*
G01X1110817Y1201226D01*
X1110801Y1201278D01*
X1110800Y1201306D01*
G02X1110824Y1201408I200J7D01*
G01X1110991Y1201718D01*
G02X1111167Y1201823I176J-95D01*
G01X1183251D01*
G02X1183451Y1201623I0J-200D01*
G01Y1201226D01*
X1183437Y1201175D01*
X1183423Y1201152D01*
G03X1183244Y1200492I1123J-659D01*
G01Y1200490D01*
G03X1183423Y1199830I1302J-1D01*
G01X1183437Y1199807D01*
X1183451Y1199756D01*
Y1199514D01*
X1183421Y1199440D01*
G37*
G36*
G01X1181201Y1194497D02*
X1181340D01*
G02X1181480Y1194440I0J-200D01*
G01X1181481Y1194439D01*
X1182364Y1193556D01*
G02X1182366Y1193554I-140J-142D01*
G02X1182423Y1193414I-143J-140D01*
G01Y1191340D01*
X1182393Y1191266D01*
X1182364Y1191238D01*
X1182271Y1191145D01*
G02X1182129Y1191086I-142J141D01*
G01X1111340D01*
X1111335Y1191092D01*
X1111322D01*
G02X1111227Y1191145I46J194D01*
G01X1110782Y1191590D01*
G02X1110723Y1191732I141J142D01*
G01Y1191988D01*
X1110734Y1192034D01*
X1110745Y1192055D01*
G03X1110790Y1192198I-402J205D01*
G02X1110822Y1192282I198J-27D01*
G03X1111045Y1193010I-1079J729D01*
G01Y1193012D01*
G03X1110822Y1193740I-1302J-1D01*
G02X1110790Y1193824I166J111D01*
G03X1110745Y1193967I-447J-62D01*
G01X1110734Y1193988D01*
X1110723Y1194034D01*
Y1194114D01*
G02X1110780Y1194254I200J0D01*
G01X1110781Y1194255D01*
X1110815Y1194289D01*
G02X1110947Y1194347I141J-142D01*
G01X1110959Y1194348D01*
X1180886D01*
G03X1181026Y1194406I-1J200D01*
G01X1181061Y1194440D01*
G02X1181201Y1194497I140J-143D01*
G37*
G36*
G01X1109804Y1348187D02*
G03I-491J0D01*
G37*
G36*
G01X1114164D02*
G03I-491J0D01*
G37*
G36*
G01X1122044D02*
G03I-491J0D01*
G37*
G36*
G01X1109804Y1360099D02*
G03I-491J0D01*
G37*
G36*
G01X1114164D02*
G03I-491J0D01*
G37*
G36*
G01X1122044D02*
G03I-491J0D01*
G37*
G36*
G01X1109804Y1372385D02*
G03I-491J0D01*
G37*
G36*
G01X1114164D02*
G03I-491J0D01*
G37*
G36*
G01X1122044D02*
G03I-491J0D01*
G37*
G36*
G01X1109804Y1384297D02*
G03I-491J0D01*
G37*
G36*
G01Y1396583D02*
G03I-491J0D01*
G37*
G36*
G01X1114164Y1384297D02*
G03I-491J0D01*
G37*
G36*
G01X1122044D02*
G03I-491J0D01*
G37*
G36*
G01X1114164Y1396583D02*
G03I-491J0D01*
G37*
G36*
G01X1122044D02*
G03I-491J0D01*
G37*
G36*
G01X1109804Y1408495D02*
G03I-491J0D01*
G37*
G36*
G01X1122044D02*
G03I-491J0D01*
G37*
G36*
G01X1114164D02*
G03I-491J0D01*
G37*
G36*
G01X1126404Y1348187D02*
G03I-491J0D01*
G37*
G36*
G01X1134284D02*
G03I-491J0D01*
G37*
G36*
G01X1138644D02*
G03I-491J0D01*
G37*
G36*
G01X1126404Y1360099D02*
G03I-491J0D01*
G37*
G36*
G01X1134284D02*
G03I-491J0D01*
G37*
G36*
G01X1138644D02*
G03I-491J0D01*
G37*
G36*
G01X1126404Y1372385D02*
G03I-491J0D01*
G37*
G36*
G01X1134284D02*
G03I-491J0D01*
G37*
G36*
G01X1138644D02*
G03I-491J0D01*
G37*
G36*
G01X1126404Y1384297D02*
G03I-491J0D01*
G37*
G36*
G01Y1396583D02*
G03I-491J0D01*
G37*
G36*
G01X1134284Y1384297D02*
G03I-491J0D01*
G37*
G36*
G01X1138644D02*
G03I-491J0D01*
G37*
G36*
G01X1134284Y1396583D02*
G03I-491J0D01*
G37*
G36*
G01X1138644D02*
G03I-491J0D01*
G37*
G36*
G01X1126404Y1408495D02*
G03I-491J0D01*
G37*
G36*
G01X1134284D02*
G03I-491J0D01*
G37*
G36*
G01X1138644D02*
G03I-491J0D01*
G37*
G36*
G01X1130128Y1461182D02*
G03I-491J0D01*
G37*
G36*
G01Y1456451D02*
G03I-491J0D01*
G37*
G36*
G01X1138789Y1460782D02*
G03I-491J0D01*
G37*
G36*
G01X1130128Y1476536D02*
G03I-491J0D01*
G37*
G36*
G01Y1481267D02*
G03I-491J0D01*
G37*
G36*
G01X1138789Y1476136D02*
G03I-491J0D01*
G37*
G36*
G01Y1470244D02*
G03I-491J0D01*
G37*
G36*
G01Y1480867D02*
G03I-491J0D01*
G37*
G36*
G01X1130128Y1465913D02*
G03I-491J0D01*
G37*
G36*
G01X1138789Y1465513D02*
G03I-491J0D01*
G37*
G36*
G01X1130128Y1471805D02*
G03I-491J0D01*
G37*
G36*
G01X1138789Y1496222D02*
G03I-491J0D01*
G37*
G36*
G01X1130128Y1491891D02*
G03I-491J0D01*
G37*
G36*
G01Y1487160D02*
G03I-491J0D01*
G37*
G36*
G01Y1496622D02*
G03I-491J0D01*
G37*
G36*
G01X1138789Y1491491D02*
G03I-491J0D01*
G37*
G36*
G01Y1485598D02*
G03I-491J0D01*
G37*
G36*
G01X1130128Y1507245D02*
G03I-491J0D01*
G37*
G36*
G01Y1502514D02*
G03I-491J0D01*
G37*
G36*
G01Y1511976D02*
G03I-491J0D01*
G37*
G36*
G01X1138789Y1506845D02*
G03I-491J0D01*
G37*
G36*
G01Y1500953D02*
G03I-491J0D01*
G37*
G36*
G01Y1511576D02*
G03I-491J0D01*
G37*
G36*
G01Y1516307D02*
G03I-491J0D01*
G37*
G36*
G01X1130128Y1558813D02*
G03I-491J0D01*
G37*
G36*
G01Y1563544D02*
G03I-491J0D01*
G37*
G36*
G01X1138789Y1563144D02*
G03I-491J0D01*
G37*
G36*
G01X1130128Y1568275D02*
G03I-491J0D01*
G37*
G36*
G01Y1574167D02*
G03I-491J0D01*
G37*
G36*
G01X1138789Y1567875D02*
G03I-491J0D01*
G37*
G36*
G01Y1578498D02*
G03I-491J0D01*
G37*
G36*
G01Y1572606D02*
G03I-491J0D01*
G37*
G36*
G01X1130128Y1578898D02*
G03I-491J0D01*
G37*
G36*
G01Y1583629D02*
G03I-491J0D01*
G37*
G36*
G01Y1594253D02*
G03I-491J0D01*
G37*
G36*
G01Y1589522D02*
G03I-491J0D01*
G37*
G36*
G01X1138789Y1583229D02*
G03I-491J0D01*
G37*
G36*
G01Y1593853D02*
G03I-491J0D01*
G37*
G36*
G01Y1587960D02*
G03I-491J0D01*
G37*
G36*
G01Y1598584D02*
G03I-491J0D01*
G37*
G36*
G01Y1603315D02*
G03I-491J0D01*
G37*
G36*
G01X1130128Y1609607D02*
G03I-491J0D01*
G37*
G36*
G01Y1598984D02*
G03I-491J0D01*
G37*
G36*
G01Y1604876D02*
G03I-491J0D01*
G37*
G36*
G01X1138789Y1609207D02*
G03I-491J0D01*
G37*
G36*
G01Y1613938D02*
G03I-491J0D01*
G37*
G36*
G01Y1618669D02*
G03I-491J0D01*
G37*
G36*
G01X1130128Y1614338D02*
G03I-491J0D01*
G37*
G36*
G01X1143314Y203641D02*
X1154522D01*
X1155494Y202669D01*
Y195995D01*
X1153940Y194441D01*
X1142795D01*
X1142083Y195153D01*
Y202410D01*
X1143314Y203641D01*
G37*
G36*
G01X1150217Y813323D02*
G03I-590J0D01*
G37*
G36*
G01X1153100Y844642D02*
G03I-590J0D01*
G37*
G36*
G01X1146524Y1348187D02*
G03I-491J0D01*
G37*
G36*
G01X1150884D02*
G03I-491J0D01*
G37*
G36*
G01X1146524Y1360099D02*
G03I-491J0D01*
G37*
G36*
G01X1150884D02*
G03I-491J0D01*
G37*
G36*
G01X1146524Y1372385D02*
G03I-491J0D01*
G37*
G36*
G01X1150884D02*
G03I-491J0D01*
G37*
G36*
G01X1146524Y1384297D02*
G03I-491J0D01*
G37*
G36*
G01X1150884D02*
G03I-491J0D01*
G37*
G36*
G01X1146524Y1396583D02*
G03I-491J0D01*
G37*
G36*
G01X1150884D02*
G03I-491J0D01*
G37*
G36*
G01X1146524Y1408495D02*
G03I-491J0D01*
G37*
G36*
G01X1150884D02*
G03I-491J0D01*
G37*
G36*
G01X1147451Y1461182D02*
G03I-491J0D01*
G37*
G36*
G01X1156112Y1460782D02*
G03I-491J0D01*
G37*
G36*
G01X1147451Y1456451D02*
G03I-491J0D01*
G37*
G36*
G01X1156112Y1465513D02*
G03I-491J0D01*
G37*
G36*
G01X1147451Y1471805D02*
G03I-491J0D01*
G37*
G36*
G01Y1476536D02*
G03I-491J0D01*
G37*
G36*
G01Y1481267D02*
G03I-491J0D01*
G37*
G36*
G01X1156112Y1476136D02*
G03I-491J0D01*
G37*
G36*
G01Y1470244D02*
G03I-491J0D01*
G37*
G36*
G01Y1480867D02*
G03I-491J0D01*
G37*
G36*
G01X1147451Y1465913D02*
G03I-491J0D01*
G37*
G36*
G01Y1491891D02*
G03I-491J0D01*
G37*
G36*
G01Y1496622D02*
G03I-491J0D01*
G37*
G36*
G01X1156112Y1491491D02*
G03I-491J0D01*
G37*
G36*
G01Y1485598D02*
G03I-491J0D01*
G37*
G36*
G01Y1496222D02*
G03I-491J0D01*
G37*
G36*
G01X1147451Y1487160D02*
G03I-491J0D01*
G37*
G36*
G01Y1502514D02*
G03I-491J0D01*
G37*
G36*
G01X1156112Y1506845D02*
G03I-491J0D01*
G37*
G36*
G01Y1500953D02*
G03I-491J0D01*
G37*
G36*
G01Y1511576D02*
G03I-491J0D01*
G37*
G36*
G01X1147451Y1511976D02*
G03I-491J0D01*
G37*
G36*
G01Y1507245D02*
G03I-491J0D01*
G37*
G36*
G01X1156112Y1516307D02*
G03I-491J0D01*
G37*
G36*
G01X1147451Y1558813D02*
G03I-491J0D01*
G37*
G36*
G01X1156112Y1572606D02*
G03I-491J0D01*
G37*
G36*
G01X1147451Y1563544D02*
G03I-491J0D01*
G37*
G36*
G01X1156112Y1563144D02*
G03I-491J0D01*
G37*
G36*
G01X1147451Y1568275D02*
G03I-491J0D01*
G37*
G36*
G01X1156112Y1567875D02*
G03I-491J0D01*
G37*
G36*
G01X1147451Y1574167D02*
G03I-491J0D01*
G37*
G36*
G01X1156112Y1578498D02*
G03I-491J0D01*
G37*
G36*
G01X1147451Y1578898D02*
G03I-491J0D01*
G37*
G36*
G01Y1589522D02*
G03I-491J0D01*
G37*
G36*
G01Y1594253D02*
G03I-491J0D01*
G37*
G36*
G01X1156112Y1593853D02*
G03I-491J0D01*
G37*
G36*
G01Y1587960D02*
G03I-491J0D01*
G37*
G36*
G01X1147451Y1583629D02*
G03I-491J0D01*
G37*
G36*
G01X1156112Y1583229D02*
G03I-491J0D01*
G37*
G36*
G01X1147451Y1609607D02*
G03I-491J0D01*
G37*
G36*
G01Y1604876D02*
G03I-491J0D01*
G37*
G36*
G01Y1598984D02*
G03I-491J0D01*
G37*
G36*
G01X1156112Y1609207D02*
G03I-491J0D01*
G37*
G36*
G01Y1598584D02*
G03I-491J0D01*
G37*
G36*
G01Y1603315D02*
G03I-491J0D01*
G37*
G36*
G01X1147451Y1614338D02*
G03I-491J0D01*
G37*
G36*
G01X1156112Y1613938D02*
G03I-491J0D01*
G37*
G36*
G01Y1618669D02*
G03I-491J0D01*
G37*
G36*
G01X1201477Y174205D02*
X1205029D01*
G02X1205169Y174148I0J-200D01*
G01X1205170Y174147D01*
X1207372Y171945D01*
G02X1207374Y171943I-140J-142D01*
G02X1207431Y171803I-143J-140D01*
G01Y147990D01*
G02X1207321Y147811I-200J0D01*
G01X1207003Y147650D01*
G02X1206793Y147668I-90J178D01*
G03X1205899Y147963I-894J-1207D01*
G03Y144959I0J-1502D01*
G03X1206793Y145254I0J1502D01*
G02X1207003Y145272I120J-160D01*
G01X1207321Y145111D01*
G02X1207431Y144932I-90J-179D01*
G01Y138227D01*
X1207358Y138124D01*
X1207298Y138103D01*
G03X1206597Y137587I502J-1416D01*
G01X1206576Y137559D01*
X1206489Y137501D01*
G02X1206422Y137473I-109J168D01*
G01X1206303Y137446D01*
X1206229Y137457D01*
X1206196Y137475D01*
G03X1205895Y137612I-894J-1565D01*
G03X1205304Y137712I-592J-1703D01*
G03X1204713Y137612I1J-1803D01*
G03X1204412Y137475I593J-1702D01*
G01X1204379Y137457D01*
X1204305Y137446D01*
X1204186Y137473D01*
G02X1204119Y137501I42J196D01*
G01X1204031Y137560D01*
X1204011Y137588D01*
G03X1202808Y138189I-1202J-901D01*
G01X1202765D01*
X1202764Y138188D01*
G03X1201306Y136687I44J-1501D01*
G03X1202808Y135185I1502J0D01*
G03X1203040Y135203I0J1502D01*
G01X1203083Y135210D01*
X1203167Y135186D01*
X1203431Y134961D01*
G02X1203502Y134808I-129J-153D01*
G01Y133610D01*
G02X1203431Y133457I-200J0D01*
G01X1203167Y133232D01*
X1203083Y133208D01*
X1203040Y133215D01*
G03X1202805Y133233I-232J-1484D01*
G01X1202804D01*
G03X1201306Y131731I4J-1502D01*
G03X1202808Y130229I1502J0D01*
G01X1202809D01*
G03X1204011Y130830I0J1502D01*
G01X1204031Y130858D01*
X1204119Y130917D01*
G02X1204186Y130945I109J-168D01*
G01X1204305Y130972D01*
X1204379Y130961D01*
X1204412Y130943D01*
G03X1204713Y130806I894J1565D01*
G03X1205304Y130706I592J1703D01*
G03X1205895Y130806I-1J1803D01*
G03X1206196Y130943I-593J1702D01*
G01X1206229Y130961D01*
X1206303Y130972D01*
X1206422Y130945D01*
G02X1206489Y130917I-42J-196D01*
G01X1206576Y130859D01*
X1206597Y130831D01*
G03X1207298Y130315I1203J900D01*
G01X1207358Y130294D01*
X1207431Y130191D01*
Y124053D01*
X1207358Y123950D01*
X1207298Y123929D01*
G03X1206597Y123413I502J-1416D01*
G01X1206576Y123385D01*
X1206489Y123327D01*
G02X1206422Y123299I-109J168D01*
G01X1206303Y123272D01*
X1206229Y123283D01*
X1206196Y123301D01*
G03X1205895Y123438I-894J-1565D01*
G03X1205304Y123538I-592J-1703D01*
G03X1204713Y123438I1J-1803D01*
G03X1204412Y123301I593J-1702D01*
G01X1204379Y123283D01*
X1204305Y123272D01*
X1204186Y123299D01*
G02X1204119Y123327I42J196D01*
G01X1204031Y123386D01*
X1204011Y123414D01*
G03X1202808Y124015I-1202J-901D01*
G01X1202765D01*
X1202764Y124014D01*
G03X1201306Y122513I44J-1501D01*
G03X1202808Y121011I1502J0D01*
G03X1203040Y121029I0J1502D01*
G01X1203083Y121036D01*
X1203167Y121012D01*
X1203431Y120787D01*
G02X1203502Y120634I-129J-153D01*
G01Y119436D01*
G02X1203431Y119283I-200J0D01*
G01X1203167Y119058D01*
X1203083Y119034D01*
X1203040Y119041D01*
G03X1202805Y119059I-232J-1484D01*
G01X1202804D01*
G03X1201306Y117557I4J-1502D01*
G03X1202808Y116055I1502J0D01*
G01X1202809D01*
G03X1204011Y116656I0J1502D01*
G01X1204031Y116684D01*
X1204119Y116743D01*
G02X1204186Y116771I109J-168D01*
G01X1204305Y116798D01*
X1204379Y116787D01*
X1204412Y116769D01*
G03X1204713Y116632I894J1565D01*
G03X1205304Y116532I592J1703D01*
G03X1205895Y116632I-1J1803D01*
G03X1206196Y116769I-593J1702D01*
G01X1206229Y116787D01*
X1206303Y116798D01*
X1206422Y116771D01*
G02X1206489Y116743I-42J-196D01*
G01X1206576Y116685D01*
X1206597Y116657D01*
G03X1207298Y116141I1203J900D01*
G01X1207358Y116120D01*
X1207431Y116017D01*
Y78102D01*
G02X1207405Y78003I-200J0D01*
G01X1207345Y77899D01*
X1207313Y77865D01*
X1207292Y77851D01*
G03X1206854Y77421I811J-1264D01*
G01X1206853Y77420D01*
Y77419D01*
G02X1206719Y77334I-165J113D01*
G01X1206430Y77288D01*
G02X1206276Y77327I-32J197D01*
G03X1205355Y77642I-920J-1187D01*
G01X1205325D01*
G03X1203853Y76140I30J-1502D01*
G03X1205355Y74638I1502J0D01*
G01X1205371D01*
X1205431Y74639D01*
X1205534Y74572D01*
X1205701Y74174D01*
G02X1205658Y73955I-184J-78D01*
G01X1204204Y72501D01*
X1204176Y72472D01*
X1204102Y72442D01*
X1157989D01*
G02X1157847Y72501I0J200D01*
G01X1156531Y73817D01*
X1156502Y73845D01*
X1156472Y73919D01*
Y100421D01*
G02X1156531Y100563I200J0D01*
G01X1156733Y100763D01*
G02X1156874Y100821I141J-142D01*
G01X1156885D01*
G03Y103825I0J1502D01*
G01X1156874D01*
G02X1156733Y103883I0J200D01*
G01X1156531Y104083D01*
G02X1156472Y104225I141J142D01*
G01Y107508D01*
G02X1156531Y107650I200J0D01*
G01X1156733Y107850D01*
G02X1156874Y107908I141J-142D01*
G01X1156885D01*
G03Y110912I0J1502D01*
G01X1156874D01*
G02X1156733Y110970I0J200D01*
G01X1156531Y111170D01*
G02X1156472Y111312I141J142D01*
G01Y114594D01*
G02X1156531Y114736I200J0D01*
G01X1156733Y114936D01*
G02X1156874Y114994I141J-142D01*
G01X1156885D01*
G03Y117998I0J1502D01*
G01X1156874D01*
G02X1156733Y118056I0J200D01*
G01X1156531Y118256D01*
G02X1156472Y118398I141J142D01*
G01Y121681D01*
G02X1156531Y121823I200J0D01*
G01X1156733Y122023D01*
G02X1156874Y122081I141J-142D01*
G01X1156885D01*
G03Y125085I0J1502D01*
G01X1156874D01*
G02X1156733Y125143I0J200D01*
G01X1156531Y125343D01*
G02X1156472Y125485I141J142D01*
G01Y128768D01*
G02X1156531Y128910I200J0D01*
G01X1156733Y129110D01*
G02X1156874Y129168I141J-142D01*
G01X1156885D01*
G03Y132172I0J1502D01*
G01X1156874D01*
G02X1156733Y132230I0J200D01*
G01X1156531Y132430D01*
G02X1156472Y132572I141J142D01*
G01Y135854D01*
G02X1156531Y135996I200J0D01*
G01X1156733Y136196D01*
G02X1156874Y136254I141J-142D01*
G01X1156885D01*
G03Y139258I0J1502D01*
G01X1156874D01*
G02X1156733Y139316I0J200D01*
G01X1156531Y139516D01*
G02X1156472Y139658I141J142D01*
G01Y172123D01*
G02X1156529Y172263I200J0D01*
G01X1156530Y172264D01*
X1158412Y174146D01*
G02X1158414Y174148I142J-140D01*
G02X1158554Y174205I140J-143D01*
G01X1198483D01*
G02X1198669Y174078I0J-200D01*
G01X1198828Y173673D01*
X1198801Y173554D01*
X1198755Y173512D01*
G03X1198178Y172190I1226J-1322D01*
G03X1201782I1802J0D01*
G03X1201771Y172390I-1802J1D01*
G01X1201772D01*
G03X1201205Y173512I-1792J-201D01*
G01X1201160Y173555D01*
X1201132Y173674D01*
X1201291Y174078D01*
G02X1201477Y174205I186J-73D01*
G37*
G36*
G01X1161106Y800900D02*
G03I-590J0D01*
G37*
G36*
G01X1158764Y1348187D02*
G03I-491J0D01*
G37*
G36*
G01X1163124D02*
G03I-491J0D01*
G37*
G36*
G01X1171004D02*
G03I-491J0D01*
G37*
G36*
G01X1158764Y1360099D02*
G03I-491J0D01*
G37*
G36*
G01X1163124D02*
G03I-491J0D01*
G37*
G36*
G01X1171004D02*
G03I-491J0D01*
G37*
G36*
G01X1158764Y1372385D02*
G03I-491J0D01*
G37*
G36*
G01X1163124D02*
G03I-491J0D01*
G37*
G36*
G01X1171004D02*
G03I-491J0D01*
G37*
G36*
G01X1158764Y1384297D02*
G03I-491J0D01*
G37*
G36*
G01Y1396583D02*
G03I-491J0D01*
G37*
G36*
G01X1163124Y1384297D02*
G03I-491J0D01*
G37*
G36*
G01X1171004D02*
G03I-491J0D01*
G37*
G36*
G01X1163124Y1396583D02*
G03I-491J0D01*
G37*
G36*
G01X1171004D02*
G03I-491J0D01*
G37*
G36*
G01X1158764Y1408495D02*
G03I-491J0D01*
G37*
G36*
G01X1171004D02*
G03I-491J0D01*
G37*
G36*
G01X1163124D02*
G03I-491J0D01*
G37*
G36*
G01X1164774Y1456451D02*
G03I-491J0D01*
G37*
G36*
G01Y1461182D02*
G03I-491J0D01*
G37*
G36*
G01Y1471805D02*
G03I-491J0D01*
G37*
G36*
G01Y1476536D02*
G03I-491J0D01*
G37*
G36*
G01Y1481267D02*
G03I-491J0D01*
G37*
G36*
G01Y1465913D02*
G03I-491J0D01*
G37*
G36*
G01Y1487160D02*
G03I-491J0D01*
G37*
G36*
G01Y1491891D02*
G03I-491J0D01*
G37*
G36*
G01Y1496622D02*
G03I-491J0D01*
G37*
G36*
G01Y1507245D02*
G03I-491J0D01*
G37*
G36*
G01Y1502514D02*
G03I-491J0D01*
G37*
G36*
G01Y1511976D02*
G03I-491J0D01*
G37*
G36*
G01Y1558813D02*
G03I-491J0D01*
G37*
G36*
G01Y1563544D02*
G03I-491J0D01*
G37*
G36*
G01Y1574167D02*
G03I-491J0D01*
G37*
G36*
G01Y1568275D02*
G03I-491J0D01*
G37*
G36*
G01Y1578898D02*
G03I-491J0D01*
G37*
G36*
G01Y1583629D02*
G03I-491J0D01*
G37*
G36*
G01Y1589522D02*
G03I-491J0D01*
G37*
G36*
G01Y1594253D02*
G03I-491J0D01*
G37*
G36*
G01Y1598984D02*
G03I-491J0D01*
G37*
G36*
G01Y1609607D02*
G03I-491J0D01*
G37*
G36*
G01Y1604876D02*
G03I-491J0D01*
G37*
G36*
G01Y1614338D02*
G03I-491J0D01*
G37*
G36*
G01X1188293Y849734D02*
G03I-590J0D01*
G37*
G36*
G01X1187332Y855466D02*
G03I-590J0D01*
G37*
G36*
G01X1178365Y894053D02*
G03I-590J0D01*
G37*
G36*
G01X1245276Y992393D02*
X1319193D01*
G02X1319335Y992334I0J-200D01*
G01X1319687Y991982D01*
G02X1319739Y991788I-141J-142D01*
G01X1319632Y991400D01*
X1319556Y991325D01*
X1319503Y991311D01*
G03X1318372Y989856I370J-1455D01*
G03X1319874Y988354I1502J0D01*
G03X1320149Y988379I2J1502D01*
G01X1320193Y988388D01*
X1320279Y988365D01*
X1320550Y988140D01*
G02X1320622Y987986I-128J-154D01*
G01Y984287D01*
G02X1320563Y984145I-200J0D01*
G01X1317017Y980599D01*
G02X1316875Y980540I-142J141D01*
G01X1309452D01*
X1309355Y980600D01*
X1309330Y980653D01*
G03X1306084I-1623J-783D01*
G01X1306059Y980600D01*
X1305962Y980540D01*
X1294079D01*
G02X1293909Y980635I0J200D01*
G03X1291353I-1278J-791D01*
G02X1291183Y980540I-170J105D01*
G01X1249371D01*
G03X1249229Y980481I0J-200D01*
G01X1223054Y954306D01*
G03X1222995Y954164I141J-142D01*
G01Y913059D01*
G02X1222936Y912917I-200J0D01*
G01X1209155Y899136D01*
G02X1209013Y899077I-142J141D01*
G01X1187087D01*
G02X1186945Y899136I0J200D01*
G01X1186537Y899544D01*
G02X1186478Y899686I141J142D01*
G01Y901110D01*
X1186466Y901123D01*
Y904050D01*
G02X1186666Y904250I200J0D01*
G01X1195714D01*
G03X1197313Y904912I0J2262D01*
G01X1197476Y905074D01*
G02X1197617Y905133I142J-141D01*
G01X1201276D01*
G03X1201418Y905192I0J200D01*
G01X1214746Y918520D01*
G03X1214805Y918662I-141J142D01*
G01Y961922D01*
G02X1214864Y962064I200J0D01*
G01X1245134Y992334D01*
G02X1245276Y992393I142J-141D01*
G37*
G36*
G01X1179070Y915220D02*
G03I-590J0D01*
G37*
G36*
G01X1193084Y1136005D02*
X1194710D01*
G02X1194784Y1135991I0J-200D01*
G01X1194883Y1135952D01*
X1194909Y1135929D01*
G03X1195650Y1135612I858J980D01*
G01X1195686Y1135609D01*
X1195749Y1135579D01*
X1197041Y1134287D01*
G03X1197183Y1134228I142J141D01*
G01X1201075D01*
G02X1201108Y1134225I-2J-200D01*
G02X1201215Y1134171I-32J-197D01*
G01X1201531Y1133855D01*
G02X1201590Y1133713I-141J-142D01*
G01Y1126997D01*
G02X1201390Y1126797I-200J0D01*
G01X1193648D01*
X1193574Y1126827D01*
X1193546Y1126856D01*
X1193075Y1127327D01*
X1193073D01*
X1192677Y1127724D01*
G02X1192620Y1127885I142J141D01*
G01X1192651Y1128193D01*
G02X1192740Y1128340I199J-20D01*
G01X1192741D01*
G03X1193329Y1129429I-714J1089D01*
G03X1190725I-1302J0D01*
G03X1190921Y1128742I1302J0D01*
G01X1190950Y1128695D01*
X1190953Y1128587D01*
X1190756Y1128233D01*
G02X1190581Y1128130I-175J97D01*
G01X1185898D01*
G02X1185698Y1128330I0J200D01*
G01Y1128821D01*
X1185718Y1128863D01*
G03Y1129995I-1171J566D01*
G01X1185698Y1130037D01*
Y1132561D01*
X1185718Y1132603D01*
G03Y1133735I-1171J566D01*
G01X1185698Y1133777D01*
Y1135292D01*
G02X1185757Y1135434I200J0D01*
G01X1186269Y1135946D01*
G02X1186411Y1136005I142J-141D01*
G01X1187230D01*
G02X1187304Y1135991I0J-200D01*
G01X1187404Y1135951D01*
X1187431Y1135929D01*
G03X1188755Y1135694I857J980D01*
G01X1188789Y1135708D01*
X1189707D01*
G03X1189973Y1135794I1J451D01*
G02X1190091Y1135833I119J-161D01*
G01X1190223D01*
G02X1190341Y1135794I-1J-200D01*
G03X1190607Y1135708I265J365D01*
G01X1191525D01*
X1191559Y1135694D01*
G03X1192883Y1135929I467J1215D01*
G01X1192910Y1135951D01*
X1193010Y1135991D01*
G02X1193084Y1136005I74J-186D01*
G37*
G36*
G01X1175364Y1348187D02*
G03I-491J0D01*
G37*
G36*
G01X1183244D02*
G03I-491J0D01*
G37*
G36*
G01X1175364Y1360099D02*
G03I-491J0D01*
G37*
G36*
G01X1183244D02*
G03I-491J0D01*
G37*
G36*
G01X1175364Y1372385D02*
G03I-491J0D01*
G37*
G36*
G01X1183244D02*
G03I-491J0D01*
G37*
G36*
G01X1175364Y1384297D02*
G03I-491J0D01*
G37*
G36*
G01Y1396583D02*
G03I-491J0D01*
G37*
G36*
G01X1183244Y1384297D02*
G03I-491J0D01*
G37*
G36*
G01Y1396583D02*
G03I-491J0D01*
G37*
G36*
G01X1175364Y1408495D02*
G03I-491J0D01*
G37*
G36*
G01X1183244D02*
G03I-491J0D01*
G37*
G36*
G01X1182096Y1456451D02*
G03I-491J0D01*
G37*
G36*
G01Y1461182D02*
G03I-491J0D01*
G37*
G36*
G01X1173435Y1460782D02*
G03I-491J0D01*
G37*
G36*
G01Y1480867D02*
G03I-491J0D01*
G37*
G36*
G01Y1465513D02*
G03I-491J0D01*
G37*
G36*
G01X1182096Y1465913D02*
G03I-491J0D01*
G37*
G36*
G01Y1471805D02*
G03I-491J0D01*
G37*
G36*
G01Y1476536D02*
G03I-491J0D01*
G37*
G36*
G01Y1481267D02*
G03I-491J0D01*
G37*
G36*
G01X1173435Y1476136D02*
G03I-491J0D01*
G37*
G36*
G01Y1470244D02*
G03I-491J0D01*
G37*
G36*
G01Y1485598D02*
G03I-491J0D01*
G37*
G36*
G01Y1496222D02*
G03I-491J0D01*
G37*
G36*
G01X1182096Y1487160D02*
G03I-491J0D01*
G37*
G36*
G01Y1491891D02*
G03I-491J0D01*
G37*
G36*
G01Y1496622D02*
G03I-491J0D01*
G37*
G36*
G01X1173435Y1491491D02*
G03I-491J0D01*
G37*
G36*
G01X1182096Y1507245D02*
G03I-491J0D01*
G37*
G36*
G01Y1502514D02*
G03I-491J0D01*
G37*
G36*
G01Y1511976D02*
G03I-491J0D01*
G37*
G36*
G01X1173435Y1506845D02*
G03I-491J0D01*
G37*
G36*
G01Y1500953D02*
G03I-491J0D01*
G37*
G36*
G01Y1511576D02*
G03I-491J0D01*
G37*
G36*
G01Y1516307D02*
G03I-491J0D01*
G37*
G36*
G01X1182096Y1558813D02*
G03I-491J0D01*
G37*
G36*
G01Y1563544D02*
G03I-491J0D01*
G37*
G36*
G01Y1568275D02*
G03I-491J0D01*
G37*
G36*
G01Y1574167D02*
G03I-491J0D01*
G37*
G36*
G01X1173435Y1563144D02*
G03I-491J0D01*
G37*
G36*
G01Y1567875D02*
G03I-491J0D01*
G37*
G36*
G01Y1578498D02*
G03I-491J0D01*
G37*
G36*
G01Y1572606D02*
G03I-491J0D01*
G37*
G36*
G01X1182096Y1578898D02*
G03I-491J0D01*
G37*
G36*
G01Y1594253D02*
G03I-491J0D01*
G37*
G36*
G01X1173435Y1583229D02*
G03I-491J0D01*
G37*
G36*
G01Y1593853D02*
G03I-491J0D01*
G37*
G36*
G01Y1587960D02*
G03I-491J0D01*
G37*
G36*
G01X1182096Y1583629D02*
G03I-491J0D01*
G37*
G36*
G01Y1589522D02*
G03I-491J0D01*
G37*
G36*
G01Y1609607D02*
G03I-491J0D01*
G37*
G36*
G01Y1604876D02*
G03I-491J0D01*
G37*
G36*
G01Y1598984D02*
G03I-491J0D01*
G37*
G36*
G01X1173435Y1609207D02*
G03I-491J0D01*
G37*
G36*
G01Y1598584D02*
G03I-491J0D01*
G37*
G36*
G01Y1603315D02*
G03I-491J0D01*
G37*
G36*
G01X1182096Y1614338D02*
G03I-491J0D01*
G37*
G36*
G01X1173435Y1613938D02*
G03I-491J0D01*
G37*
G36*
G01Y1618669D02*
G03I-491J0D01*
G37*
G36*
G01X1256555Y54588D02*
X1285191D01*
X1285226D01*
X1285275Y54539D01*
Y52675D01*
X1285191Y52591D01*
X1256555D01*
G03X1250618Y46654I0J-5937D01*
G01Y7874D01*
G02X1244744Y2000I-5874J0D01*
G01X1197500D01*
G02X1191626Y7874I0J5874D01*
G01Y46654D01*
G03X1190170Y50549I-5938J0D01*
G01Y50728D01*
X1190174Y50732D01*
X1192419D01*
X1192602Y50549D01*
G02X1193624Y46654I-6911J-3895D01*
G01Y7874D01*
G03X1197500Y3998I3876J0D01*
G01X1244744D01*
G03X1248620Y7874I0J3876D01*
G01Y46654D01*
G02X1256555Y54588I7935J-1D01*
G37*
G36*
G01X1202811Y429263D02*
X1199016D01*
X1197575D01*
X1196336D01*
X1195477Y430122D01*
Y456169D01*
X1195986Y456678D01*
X1201410D01*
X1201837Y456251D01*
Y445974D01*
X1202811Y445000D01*
Y429263D01*
G37*
G36*
G01X1218292Y444701D02*
X1267374D01*
G02X1267516Y444642I0J-200D01*
G01X1269465Y442693D01*
G02X1269524Y442551I-141J-142D01*
G01Y411754D01*
G02X1269465Y411612I-200J0D01*
G01X1268817Y410964D01*
G02X1268675Y410905I-142J141D01*
G01X1249526D01*
Y410906D01*
X1230141D01*
G02X1229999Y410965I0J200D01*
G01X1211719Y429245D01*
G03X1211577Y429304I-142J-141D01*
G01X1204012D01*
G02X1203812Y429504I0J200D01*
G01Y444223D01*
G02X1203871Y444364I200J-1D01*
G01X1204149Y444642D01*
G02X1204291Y444701I142J-141D01*
G01X1211119D01*
G02X1211268Y444635I0J-200D01*
G03X1212680Y444006I1413J1273D01*
G03X1214092Y444635I-1J1902D01*
G02X1214241Y444701I149J-134D01*
G01X1214968D01*
G02X1215126Y444623I0J-200D01*
G03X1216630Y443886I1503J1164D01*
G03X1218134Y444623I1J1901D01*
G02X1218292Y444701I158J-122D01*
G37*
G36*
G01X1309724Y482893D02*
X1316267D01*
G02X1316409Y482834I0J-200D01*
G01X1322886Y476357D01*
G02X1322945Y476215I-141J-142D01*
G01Y463970D01*
G02X1322886Y463828I-200J0D01*
G01X1321348Y462290D01*
G03X1321290Y462149I142J-141D01*
G01Y451370D01*
G02X1321231Y451229I-200J1D01*
G01X1320757Y450755D01*
G02X1320615Y450696I-142J141D01*
G01X1311222D01*
G02X1311049Y450796I0J200D01*
G03X1310767Y451147I-1299J-755D01*
G02X1310702Y451294I135J148D01*
G01Y451588D01*
G02X1310767Y451735I200J-1D01*
G03X1311252Y452841I-1017J1105D01*
G03X1310767Y453947I-1502J1D01*
G02X1310702Y454094I135J148D01*
G01Y454388D01*
G02X1310767Y454535I200J-1D01*
G03X1311252Y455641I-1017J1105D01*
G03X1308248I-1502J0D01*
G03X1308733Y454535I1502J-1D01*
G02X1308798Y454388I-135J-148D01*
G01Y454094D01*
G02X1308733Y453947I-200J1D01*
G03X1308248Y452841I1017J-1105D01*
G03X1308733Y451735I1502J-1D01*
G02X1308798Y451588I-135J-148D01*
G01Y451294D01*
G02X1308733Y451147I-200J1D01*
G03X1308451Y450796I1017J-1106D01*
G02X1308278Y450696I-173J100D01*
G01X1301229D01*
G02X1301056Y450796I0J200D01*
G03X1300774Y451147I-1299J-755D01*
G02X1300709Y451294I135J148D01*
G01Y451588D01*
G02X1300774Y451735I200J-1D01*
G03X1301259Y452841I-1017J1105D01*
G03X1300774Y453947I-1502J1D01*
G02X1300709Y454094I135J148D01*
G01Y454388D01*
G02X1300774Y454535I200J-1D01*
G03X1301259Y455641I-1017J1105D01*
G03X1298255I-1502J0D01*
G03X1298740Y454535I1502J-1D01*
G02X1298805Y454388I-135J-148D01*
G01Y454094D01*
G02X1298740Y453947I-200J1D01*
G03X1298255Y452841I1017J-1105D01*
G03X1298740Y451735I1502J-1D01*
G02X1298805Y451588I-135J-148D01*
G01Y451294D01*
G02X1298740Y451147I-200J1D01*
G03X1298458Y450796I1017J-1106D01*
G02X1298285Y450696I-173J100D01*
G01X1280627D01*
G02X1280450Y450801I-1J200D01*
G03X1277804I-1323J-709D01*
G02X1277627Y450696I-176J95D01*
G01X1277427D01*
G02X1277250Y450801I-1J200D01*
G03X1274604I-1323J-709D01*
G01X1274577Y450752D01*
X1274483Y450696D01*
X1274371D01*
X1274277Y450752D01*
X1274250Y450801D01*
G03X1271604I-1323J-709D01*
G02X1271427Y450696I-176J95D01*
G01X1268559D01*
X1268523Y450711D01*
G03X1267149I-687J-1667D01*
G01X1267113Y450696D01*
X1212747D01*
G03X1212605Y450637I0J-200D01*
G01X1212515Y450547D01*
X1212458Y450519D01*
X1212424Y450514D01*
G03X1211676Y450245I255J-1884D01*
G01X1211652Y450230D01*
X1211598Y450214D01*
X1211548D01*
X1211430Y450098D01*
Y450066D01*
X1211368Y450007D01*
G03X1210796Y448886I1312J-1376D01*
G01X1210791Y448852D01*
X1210763Y448795D01*
X1207771Y445803D01*
G02X1207629Y445744I-142J141D01*
G01X1203773D01*
G02X1203631Y445803I0J200D01*
G01X1203363Y446071D01*
G02X1203304Y446213I141J142D01*
G01Y447901D01*
G03X1203245Y448043I-200J0D01*
G01X1203033Y448255D01*
G02X1202974Y448397I141J142D01*
G01Y456313D01*
G02X1203033Y456455I200J0D01*
G01X1203205Y456627D01*
G02X1203347Y456686I142J-141D01*
G01X1210194D01*
G03X1210336Y456745I0J200D01*
G01X1216819Y463228D01*
G02X1216961Y463287I142J-141D01*
G01X1240600D01*
G03X1240742Y463346I0J200D01*
G01X1260230Y482834D01*
G02X1260372Y482893I142J-141D01*
G01X1305926D01*
G02X1306072Y482830I0J-200D01*
G01X1306300Y482588D01*
X1306328Y482512D01*
X1306326Y482470D01*
G03X1306323Y482382I1499J-95D01*
G03X1309327I1502J0D01*
G03X1309324Y482470I-1502J-7D01*
G01X1309322Y482512D01*
X1309350Y482588D01*
X1309578Y482830D01*
G02X1309724Y482893I146J-137D01*
G37*
G36*
G01X1194331Y1124859D02*
X1201260D01*
G02X1201402Y1124800I0J-200D01*
G01X1201891Y1124311D01*
G02X1201950Y1124169I-141J-142D01*
G01Y1122074D01*
G02X1201949Y1122058I-200J4D01*
G03X1201945Y1121949I1298J-102D01*
G01Y1121947D01*
G03X1201949Y1121838I1302J-7D01*
G02X1201950Y1121822I-199J-20D01*
G01Y1118334D01*
G02X1201949Y1118318I-200J4D01*
G03X1201945Y1118209I1298J-102D01*
G01Y1118207D01*
G03X1201949Y1118098I1302J-7D01*
G02X1201950Y1118082I-199J-20D01*
G01Y1117749D01*
G02X1201891Y1117607I-200J0D01*
G01X1200440Y1116156D01*
X1200412Y1116127D01*
X1200338Y1116097D01*
X1195085D01*
G02X1194885Y1116297I0J200D01*
G01Y1122420D01*
G03X1194523Y1123294I-1236J0D01*
G01X1193745Y1124073D01*
G02Y1124356I141J142D01*
G01X1194189Y1124800D01*
G02X1194331Y1124859I142J-141D01*
G37*
G36*
G01X1204210Y1178374D02*
Y1177829D01*
G02X1204163Y1177700I-200J0D01*
G03X1203715Y1176475I1454J-1226D01*
G01Y1175680D01*
G03X1204163Y1174455I1902J1D01*
G02X1204210Y1174326I-153J-129D01*
G01Y1151404D01*
G02X1204151Y1151262I-200J0D01*
G01X1203997Y1151108D01*
G02X1203855Y1151049I-142J141D01*
G01X1202958D01*
G02X1202816Y1151108I0J200D01*
G01X1202674Y1151250D01*
G02X1202672Y1151252I140J142D01*
G03X1202629Y1151295I-1296J-1253D01*
G02X1202627Y1151297I140J142D01*
G01X1201767Y1152157D01*
G02X1201708Y1152299I141J142D01*
G01Y1166032D01*
G03X1201649Y1166174I-200J0D01*
G01X1201535Y1166288D01*
G02X1201476Y1166430I141J142D01*
G01Y1177687D01*
G02X1201535Y1177829I200J0D01*
G01X1202413Y1178707D01*
G02X1202555Y1178766I142J-141D01*
G01X1203895D01*
G02X1204037Y1178707I0J-200D01*
G01X1204090Y1178654D01*
G02X1204139Y1178574I-141J-142D01*
G01Y1178573D01*
G03X1204183Y1178474I478J153D01*
G01Y1178473D01*
G02X1204210Y1178374I-173J-100D01*
G37*
G36*
G01X1194655Y1178697D02*
X1196296D01*
G02X1196438Y1178638I0J-200D01*
G01X1196737Y1178339D01*
G02X1196796Y1178197I-141J-142D01*
G01Y1177415D01*
G02X1196737Y1177274I-200J1D01*
G01X1196520Y1177056D01*
G03X1196461Y1176915I141J-142D01*
G01Y1152859D01*
G03X1196520Y1152718I200J1D01*
G01X1196737Y1152500D01*
G02X1196796Y1152359I-141J-142D01*
G01Y1151046D01*
G02X1196737Y1150904I-200J0D01*
G01X1196733Y1150900D01*
X1196660Y1150870D01*
X1194864D01*
G02X1194722Y1150929I0J200D01*
G01X1194283Y1151368D01*
G02X1194224Y1151510I141J142D01*
G01Y1152310D01*
G02X1194283Y1152451I200J-1D01*
G01X1194453Y1152622D01*
G03X1194511Y1152763I-142J141D01*
G01Y1177028D01*
G03X1194453Y1177169I-200J0D01*
G01X1194283Y1177340D01*
G02X1194224Y1177481I141J142D01*
G01Y1178266D01*
G02X1194283Y1178408I200J0D01*
G01X1194513Y1178638D01*
G02X1194655Y1178697I142J-141D01*
G37*
G36*
G01X1200164Y1176912D02*
X1200275D01*
G02X1200475Y1176712I0J-200D01*
G01Y1166015D01*
G03X1200533Y1165874I200J0D01*
G01X1200648Y1165759D01*
G02X1200707Y1165617I-141J-142D01*
G01Y1153371D01*
G02X1200609Y1153200I-200J1D01*
G01X1200270Y1152996D01*
X1200166Y1152993D01*
X1200119Y1153018D01*
G03X1199507Y1153171I-612J-1149D01*
G03X1198632Y1152833I0J-1302D01*
G02X1198497Y1152781I-135J148D01*
G01X1197956D01*
G02X1197814Y1152840I0J200D01*
G01X1197522Y1153132D01*
G02X1197463Y1153274I141J142D01*
G01Y1176500D01*
G02X1197522Y1176642I200J0D01*
G01X1197733Y1176853D01*
G02X1197875Y1176912I142J-141D01*
G01X1198850D01*
X1198896Y1176901D01*
X1198917Y1176890D01*
G03X1199507Y1176749I589J1161D01*
G03X1200097Y1176890I1J1302D01*
G01X1200118Y1176901D01*
X1200164Y1176912D01*
G37*
G36*
G01X1192796Y1176978D02*
X1193145D01*
G02X1193287Y1176919I0J-200D01*
G01X1193451Y1176755D01*
G02X1193510Y1176613I-141J-142D01*
G01Y1153178D01*
G02X1193451Y1153036I-200J0D01*
G01X1193254Y1152839D01*
G02X1193112Y1152780I-142J141D01*
G01X1193001D01*
X1192932Y1152807D01*
X1192904Y1152832D01*
G03X1191150I-877J-961D01*
G02X1191015Y1152780I-135J148D01*
G01X1190444D01*
G02X1190302Y1152839I0J200D01*
G01X1189790Y1153351D01*
G02X1189731Y1153493I141J142D01*
G01Y1176443D01*
G02X1189790Y1176585I200J0D01*
G01X1190124Y1176919D01*
G02X1190266Y1176978I142J-141D01*
G01X1191230D01*
G02X1191336Y1176948I1J-200D01*
G03X1192027Y1176749I692J1103D01*
G03X1192718Y1176948I-1J1302D01*
G01X1192742Y1176963D01*
X1192796Y1176978D01*
G37*
G36*
G01X1190758Y1460782D02*
G03I-491J0D01*
G37*
G36*
G01X1199419Y1456452D02*
G03I-491J0D01*
G37*
G36*
G01Y1461183D02*
G03I-491J0D01*
G37*
G36*
G01X1190758Y1465513D02*
G03I-491J0D01*
G37*
G36*
G01X1199419Y1465914D02*
G03I-491J0D01*
G37*
G36*
G01X1190758Y1476136D02*
G03I-491J0D01*
G37*
G36*
G01Y1470244D02*
G03I-491J0D01*
G37*
G36*
G01Y1480867D02*
G03I-491J0D01*
G37*
G36*
G01X1199419Y1476537D02*
G03I-491J0D01*
G37*
G36*
G01Y1471806D02*
G03I-491J0D01*
G37*
G36*
G01Y1481268D02*
G03I-491J0D01*
G37*
G36*
G01Y1491892D02*
G03I-491J0D01*
G37*
G36*
G01Y1487161D02*
G03I-491J0D01*
G37*
G36*
G01Y1496623D02*
G03I-491J0D01*
G37*
G36*
G01X1190758Y1491491D02*
G03I-491J0D01*
G37*
G36*
G01Y1485598D02*
G03I-491J0D01*
G37*
G36*
G01Y1496222D02*
G03I-491J0D01*
G37*
G36*
G01Y1506845D02*
G03I-491J0D01*
G37*
G36*
G01Y1500953D02*
G03I-491J0D01*
G37*
G36*
G01Y1511576D02*
G03I-491J0D01*
G37*
G36*
G01X1199419Y1507246D02*
G03I-491J0D01*
G37*
G36*
G01Y1502515D02*
G03I-491J0D01*
G37*
G36*
G01Y1511977D02*
G03I-491J0D01*
G37*
G36*
G01X1190758Y1516307D02*
G03I-491J0D01*
G37*
G36*
G01X1199419Y1558813D02*
G03I-491J0D01*
G37*
G36*
G01Y1563544D02*
G03I-491J0D01*
G37*
G36*
G01Y1578898D02*
G03I-491J0D01*
G37*
G36*
G01X1190758Y1567875D02*
G03I-491J0D01*
G37*
G36*
G01X1199419Y1568275D02*
G03I-491J0D01*
G37*
G36*
G01X1190758Y1578498D02*
G03I-491J0D01*
G37*
G36*
G01Y1572606D02*
G03I-491J0D01*
G37*
G36*
G01X1199419Y1574167D02*
G03I-491J0D01*
G37*
G36*
G01X1190758Y1563144D02*
G03I-491J0D01*
G37*
G36*
G01X1199419Y1583629D02*
G03I-491J0D01*
G37*
G36*
G01X1190758Y1593853D02*
G03I-491J0D01*
G37*
G36*
G01Y1587960D02*
G03I-491J0D01*
G37*
G36*
G01X1199419Y1594253D02*
G03I-491J0D01*
G37*
G36*
G01Y1589522D02*
G03I-491J0D01*
G37*
G36*
G01X1190758Y1583229D02*
G03I-491J0D01*
G37*
G36*
G01Y1609207D02*
G03I-491J0D01*
G37*
G36*
G01Y1598584D02*
G03I-491J0D01*
G37*
G36*
G01Y1603315D02*
G03I-491J0D01*
G37*
G36*
G01X1199419Y1609607D02*
G03I-491J0D01*
G37*
G36*
G01Y1598984D02*
G03I-491J0D01*
G37*
G36*
G01Y1604876D02*
G03I-491J0D01*
G37*
G36*
G01Y1614338D02*
G03I-491J0D01*
G37*
G36*
G01X1190758Y1613938D02*
G03I-491J0D01*
G37*
G36*
G01Y1618669D02*
G03I-491J0D01*
G37*
G36*
G01X1206105Y1167578D02*
X1206300Y1167773D01*
G02X1206442Y1167832I142J-141D01*
G01X1211342D01*
G02X1211484Y1167773I0J-200D01*
G01X1211710Y1167547D01*
G02X1211769Y1167405I-141J-142D01*
G01Y1158972D01*
G02X1211710Y1158830I-200J0D01*
G01X1211327Y1158447D01*
G02X1211185Y1158388I-142J141D01*
G01X1206535D01*
G02X1206393Y1158447I0J200D01*
G01X1206105Y1158735D01*
G02X1206046Y1158877I141J142D01*
G01Y1167436D01*
G02X1206105Y1167578I200J0D01*
G37*
G36*
G01X1216030Y1167906D02*
X1222937D01*
G02X1222970Y1167903I-2J-200D01*
G02X1223077Y1167849I-32J-197D01*
G01X1223430Y1167496D01*
G02X1223489Y1167354I-141J-142D01*
G01Y1160474D01*
Y1160471D01*
G02X1223381Y1160297I-200J4D01*
G02X1223365Y1160289I-97J174D01*
G01X1222966Y1160126D01*
X1222924Y1160135D01*
G03X1221948Y1160602I-976J-786D01*
G03X1220696Y1159350I0J-1252D01*
G03X1220769Y1158930I1252J1D01*
G01X1220785Y1158883D01*
X1220772Y1158786D01*
X1220588Y1158533D01*
G02X1220426Y1158450I-162J117D01*
G01X1216095D01*
G02X1215934Y1158531I0J200D01*
G01X1215743Y1158789D01*
G02X1215713Y1158966I161J118D01*
G03X1215770Y1159350I-1245J381D01*
G03X1214468Y1160652I-1302J0D01*
G01X1214467D01*
G03X1213475Y1160193I0J-1302D01*
G01X1213474Y1160192D01*
G02X1213253Y1160134I-152J130D01*
G01X1212902Y1160264D01*
X1212842Y1160286D01*
X1212771Y1160388D01*
Y1165792D01*
X1212842Y1165894D01*
X1212902Y1165916D01*
X1213253Y1166046D01*
G02X1213474Y1165988I69J-188D01*
G01X1213475Y1165987D01*
G03X1214467Y1165528I992J843D01*
G01X1214468D01*
G03X1215770Y1166830I0J1302D01*
G03X1215667Y1167338I-1303J0D01*
G03X1215664Y1167344I-180J-86D01*
G02X1215672Y1167526I182J83D01*
G02X1215679Y1167537I172J-102D01*
G01X1215863Y1167816D01*
G02X1216030Y1167906I167J-110D01*
G37*
G36*
G01X1224555Y1167234D02*
X1225000Y1167679D01*
G02X1225142Y1167738I142J-141D01*
G01X1230104D01*
G02X1230246Y1167679I0J-200D01*
G01X1230441Y1167484D01*
G02X1230500Y1167342I-141J-142D01*
G01Y1158940D01*
G02X1230441Y1158798I-200J0D01*
G01X1230184Y1158541D01*
G02X1230042Y1158482I-142J141D01*
G01X1225236D01*
G02X1225094Y1158541I0J200D01*
G01X1224555Y1159080D01*
G02X1224496Y1159222I141J142D01*
G01Y1167092D01*
G02X1224555Y1167234I200J0D01*
G37*
G36*
G01X1228577Y1348187D02*
G03I-491J0D01*
G37*
G36*
G01X1236457D02*
G03I-491J0D01*
G37*
G36*
G01X1228577Y1360099D02*
G03I-491J0D01*
G37*
G36*
G01X1236457D02*
G03I-491J0D01*
G37*
G36*
G01X1228577Y1372385D02*
G03I-491J0D01*
G37*
G36*
G01X1236457D02*
G03I-491J0D01*
G37*
G36*
G01X1228577Y1384297D02*
G03I-491J0D01*
G37*
G36*
G01X1236457D02*
G03I-491J0D01*
G37*
G36*
G01X1250806Y140296D02*
G03I-499J0D01*
G37*
G36*
G01X1245676Y203641D02*
X1256884D01*
X1257856Y202669D01*
Y195995D01*
X1256302Y194441D01*
X1245157D01*
X1244445Y195153D01*
Y202410D01*
X1245676Y203641D01*
G37*
G36*
G01X1249330Y1025864D02*
G03I-609J0D01*
G37*
G36*
G01X1284825Y1066535D02*
G02I-17700J0D01*
G37*
G36*
G01X1282078Y1163908D02*
X1282784D01*
G02X1282926Y1163849I0J-200D01*
G01X1284323Y1162452D01*
G02X1284382Y1162310I-141J-142D01*
G01Y1148450D01*
G02X1284271Y1148271I-200J0D01*
G01X1283899Y1148087D01*
X1283785Y1148098D01*
X1283740Y1148132D01*
G03X1282830Y1148439I-910J-1195D01*
G03Y1145435I0J-1502D01*
G03X1283740Y1145742I0J1502D01*
G01X1283785Y1145776D01*
X1283899Y1145787D01*
X1284271Y1145603D01*
G02X1284382Y1145424I-89J-179D01*
G01Y1122110D01*
G02X1284323Y1121968I-200J0D01*
G01X1283624Y1121269D01*
G02X1283482Y1121210I-142J141D01*
G01X1275287D01*
G02X1275145Y1121269I0J200D01*
G01X1274797Y1121617D01*
G02X1274738Y1121759I141J142D01*
G01Y1128359D01*
G02X1274797Y1128501I200J0D01*
G01X1277713Y1131417D01*
G03X1277772Y1131559I-141J142D01*
G01Y1133582D01*
G02X1277795Y1133675I200J0D01*
G03X1278056Y1134729I-2001J1055D01*
G03X1277393Y1136328I-2262J-1D01*
G01X1274729Y1138992D01*
G03X1273763Y1139564I-1599J-1599D01*
G01X1273738Y1139571D01*
X1273695Y1139597D01*
X1273631Y1139661D01*
G03X1273489Y1139720I-142J-141D01*
G01X1265411D01*
G03X1265269Y1139661I0J-200D01*
G01X1261731Y1136123D01*
G03X1261672Y1135981I141J-142D01*
G01Y1134967D01*
X1261671Y1134957D01*
G03X1261660Y1134729I2250J-223D01*
G01Y1133490D01*
G02X1261601Y1133349I-200J1D01*
G01X1261109Y1132857D01*
G02X1260967Y1132798I-142J141D01*
G01X1258020D01*
G02X1257820Y1132998I0J200D01*
G01Y1139015D01*
G03X1257158Y1140614I-2262J0D01*
G01X1256566Y1141206D01*
G02X1256508Y1141348I142J141D01*
G01Y1146554D01*
G03X1256107Y1147838I-2261J-2D01*
G02X1256072Y1147952I165J113D01*
G01Y1153092D01*
G03X1256013Y1153234I-200J0D01*
G01X1255120Y1154127D01*
G03X1254978Y1154186I-142J-141D01*
G01X1253433D01*
G03X1253291Y1154127I0J-200D01*
G01X1252165Y1153001D01*
G03X1252106Y1152859I141J-142D01*
G01Y1147455D01*
X1252092Y1147420D01*
G03X1251938Y1146600I2108J-820D01*
G03X1251981Y1146165I2262J4D01*
G01X1251984Y1146146D01*
Y1144613D01*
G02X1251899Y1144449I-200J0D01*
G01X1251589Y1144233D01*
X1251493Y1144221D01*
X1251446Y1144238D01*
G03X1250928Y1144330I-518J-1410D01*
G03Y1141326I0J-1502D01*
G03X1251592Y1141481I0J1502D01*
G02X1251780Y1141475I88J-180D01*
G01X1251884Y1141415D01*
G02X1251984Y1141242I-100J-173D01*
G01Y1141232D01*
X1250454Y1139701D01*
G02X1250312Y1139642I-142J141D01*
G01X1247601D01*
G02X1247459Y1139701I0J200D01*
G01X1246254Y1140906D01*
G02X1246195Y1141048I141J142D01*
G01Y1162193D01*
G02X1246254Y1162335I200J0D01*
G01X1247768Y1163849D01*
G02X1247910Y1163908I142J-141D01*
G01X1278534D01*
G02X1278699Y1163821I0J-200D01*
G01X1278913Y1163507D01*
X1278925Y1163409D01*
X1278907Y1163363D01*
G03X1278804Y1162817I1399J-547D01*
G03X1281808I1502J0D01*
G03X1281705Y1163363I-1502J-1D01*
G01X1281687Y1163409D01*
X1281699Y1163507D01*
X1281913Y1163821D01*
G02X1282078Y1163908I165J-113D01*
G37*
G36*
G01X1284825Y1263386D02*
G02I-17700J0D01*
G37*
G36*
G01X1253057Y1348187D02*
G03I-491J0D01*
G37*
G36*
G01X1248697D02*
G03I-491J0D01*
G37*
G36*
G01X1240817D02*
G03I-491J0D01*
G37*
G36*
G01X1253057Y1360099D02*
G03I-491J0D01*
G37*
G36*
G01X1248697D02*
G03I-491J0D01*
G37*
G36*
G01X1240817D02*
G03I-491J0D01*
G37*
G36*
G01X1253057Y1372385D02*
G03I-491J0D01*
G37*
G36*
G01X1248697D02*
G03I-491J0D01*
G37*
G36*
G01X1240817D02*
G03I-491J0D01*
G37*
G36*
G01X1253057Y1396583D02*
G03I-491J0D01*
G37*
G36*
G01X1248697D02*
G03I-491J0D01*
G37*
G36*
G01X1240817D02*
G03I-491J0D01*
G37*
G36*
G01X1253057Y1384297D02*
G03I-491J0D01*
G37*
G36*
G01X1248697D02*
G03I-491J0D01*
G37*
G36*
G01X1240817D02*
G03I-491J0D01*
G37*
G36*
G01X1253057Y1408495D02*
G03I-491J0D01*
G37*
G36*
G01X1240817D02*
G03I-491J0D01*
G37*
G36*
G01X1248697D02*
G03I-491J0D01*
G37*
G36*
G01X1260916Y174551D02*
X1307391D01*
G02X1307531Y174494I0J-200D01*
G01X1307532Y174493D01*
X1309734Y172291D01*
G02X1309736Y172289I-140J-142D01*
G02X1309793Y172149I-143J-140D01*
G01Y138227D01*
X1309720Y138124D01*
X1309660Y138103D01*
G03X1308959Y137587I502J-1416D01*
G01X1308938Y137559D01*
X1308851Y137501D01*
G02X1308784Y137473I-109J168D01*
G01X1308665Y137446D01*
X1308591Y137457D01*
X1308558Y137475D01*
G03X1308257Y137612I-894J-1565D01*
G03X1307666Y137712I-592J-1703D01*
G03X1307075Y137612I1J-1803D01*
G03X1306774Y137475I593J-1702D01*
G01X1306741Y137457D01*
X1306667Y137446D01*
X1306548Y137473D01*
G02X1306481Y137501I42J196D01*
G01X1306393Y137560D01*
X1306373Y137588D01*
G03X1305170Y138189I-1202J-901D01*
G01X1305127D01*
X1305126Y138188D01*
G03X1303668Y136687I44J-1501D01*
G03X1305170Y135185I1502J0D01*
G03X1305402Y135203I0J1502D01*
G01X1305445Y135210D01*
X1305529Y135186D01*
X1305793Y134961D01*
G02X1305864Y134808I-129J-153D01*
G01Y133610D01*
G02X1305793Y133457I-200J0D01*
G01X1305529Y133232D01*
X1305445Y133208D01*
X1305402Y133215D01*
G03X1305167Y133233I-232J-1484D01*
G01X1305166D01*
G03X1303668Y131731I4J-1502D01*
G03X1305170Y130229I1502J0D01*
G01X1305171D01*
G03X1306373Y130830I0J1502D01*
G01X1306393Y130858D01*
X1306481Y130917D01*
G02X1306548Y130945I109J-168D01*
G01X1306667Y130972D01*
X1306741Y130961D01*
X1306774Y130943D01*
G03X1307075Y130806I894J1565D01*
G03X1307666Y130706I592J1703D01*
G03X1308257Y130806I-1J1803D01*
G03X1308558Y130943I-593J1702D01*
G01X1308591Y130961D01*
X1308665Y130972D01*
X1308784Y130945D01*
G02X1308851Y130917I-42J-196D01*
G01X1308938Y130859D01*
X1308959Y130831D01*
G03X1309660Y130315I1203J900D01*
G01X1309720Y130294D01*
X1309793Y130191D01*
Y124053D01*
X1309720Y123950D01*
X1309660Y123929D01*
G03X1308959Y123413I502J-1416D01*
G01X1308938Y123385D01*
X1308851Y123327D01*
G02X1308784Y123299I-109J168D01*
G01X1308665Y123272D01*
X1308591Y123283D01*
X1308558Y123301D01*
G03X1308257Y123438I-894J-1565D01*
G03X1307666Y123538I-592J-1703D01*
G03X1307075Y123438I1J-1803D01*
G03X1306774Y123301I593J-1702D01*
G01X1306741Y123283D01*
X1306667Y123272D01*
X1306548Y123299D01*
G02X1306481Y123327I42J196D01*
G01X1306393Y123386D01*
X1306373Y123414D01*
G03X1305170Y124015I-1202J-901D01*
G01X1305127D01*
X1305126Y124014D01*
G03X1303668Y122513I44J-1501D01*
G03X1305170Y121011I1502J0D01*
G03X1305402Y121029I0J1502D01*
G01X1305445Y121036D01*
X1305529Y121012D01*
X1305793Y120787D01*
G02X1305864Y120634I-129J-153D01*
G01Y119436D01*
G02X1305793Y119283I-200J0D01*
G01X1305529Y119058D01*
X1305445Y119034D01*
X1305402Y119041D01*
G03X1305167Y119059I-232J-1484D01*
G01X1305166D01*
G03X1303668Y117557I4J-1502D01*
G03X1305170Y116055I1502J0D01*
G01X1305171D01*
G03X1306373Y116656I0J1502D01*
G01X1306393Y116684D01*
X1306481Y116743D01*
G02X1306548Y116771I109J-168D01*
G01X1306667Y116798D01*
X1306741Y116787D01*
X1306774Y116769D01*
G03X1307075Y116632I894J1565D01*
G03X1307666Y116532I592J1703D01*
G03X1308257Y116632I-1J1803D01*
G03X1308558Y116769I-593J1702D01*
G01X1308591Y116787D01*
X1308665Y116798D01*
X1308784Y116771D01*
G02X1308851Y116743I-42J-196D01*
G01X1308938Y116685D01*
X1308959Y116657D01*
G03X1309660Y116141I1203J900D01*
G01X1309720Y116120D01*
X1309793Y116017D01*
Y76157D01*
G02X1309734Y76015I-200J0D01*
G01X1309552Y75833D01*
G02X1309270I-141J142D01*
G01X1309237Y75866D01*
X1309208Y75949D01*
X1309212Y75994D01*
G03X1309219Y76131I-1495J145D01*
G01Y76144D01*
G03X1307717Y77642I-1502J-4D01*
G03X1306215Y76140I0J-1502D01*
G03X1307479Y74657I1502J0D01*
G01X1307535Y74648D01*
X1307620Y74575D01*
X1307747Y74182D01*
G02X1307698Y73979I-190J-61D01*
G01X1306566Y72847D01*
X1306538Y72818D01*
X1306464Y72788D01*
X1260351D01*
G02X1260209Y72847I0J200D01*
G01X1258893Y74163D01*
X1258864Y74191D01*
X1258834Y74265D01*
Y100421D01*
G02X1258893Y100563I200J0D01*
G01X1259095Y100763D01*
G02X1259236Y100821I141J-142D01*
G01X1259247D01*
G03Y103825I0J1502D01*
G01X1259236D01*
G02X1259095Y103883I0J200D01*
G01X1258893Y104083D01*
G02X1258834Y104225I141J142D01*
G01Y107508D01*
G02X1258893Y107650I200J0D01*
G01X1259095Y107850D01*
G02X1259236Y107908I141J-142D01*
G01X1259247D01*
G03Y110912I0J1502D01*
G01X1259236D01*
G02X1259095Y110970I0J200D01*
G01X1258893Y111170D01*
G02X1258834Y111312I141J142D01*
G01Y114594D01*
G02X1258893Y114736I200J0D01*
G01X1259095Y114936D01*
G02X1259236Y114994I141J-142D01*
G01X1259247D01*
G03Y117998I0J1502D01*
G01X1259236D01*
G02X1259095Y118056I0J200D01*
G01X1258893Y118256D01*
G02X1258834Y118398I141J142D01*
G01Y121681D01*
G02X1258893Y121823I200J0D01*
G01X1259095Y122023D01*
G02X1259236Y122081I141J-142D01*
G01X1259247D01*
G03Y125085I0J1502D01*
G01X1259236D01*
G02X1259095Y125143I0J200D01*
G01X1258893Y125343D01*
G02X1258834Y125485I141J142D01*
G01Y128768D01*
G02X1258893Y128910I200J0D01*
G01X1259095Y129110D01*
G02X1259236Y129168I141J-142D01*
G01X1259247D01*
G03Y132172I0J1502D01*
G01X1259236D01*
G02X1259095Y132230I0J200D01*
G01X1258893Y132430D01*
G02X1258834Y132572I141J142D01*
G01Y135854D01*
G02X1258893Y135996I200J0D01*
G01X1259095Y136196D01*
G02X1259236Y136254I141J-142D01*
G01X1259247D01*
G03Y139258I0J1502D01*
G01X1259236D01*
G02X1259095Y139316I0J200D01*
G01X1258893Y139516D01*
G02X1258834Y139658I141J142D01*
G01Y172469D01*
G02X1258891Y172609I200J0D01*
G01X1258892Y172610D01*
X1260774Y174492D01*
G02X1260776Y174494I142J-140D01*
G02X1260916Y174551I140J-143D01*
G37*
G36*
G01X1310406Y448689D02*
X1321948D01*
G02X1322090Y448630I0J-200D01*
G01X1324400Y446320D01*
G03X1324541Y446262I141J142D01*
G01X1331066D01*
G02X1331266Y446062I0J-201D01*
G01Y431715D01*
G02X1331207Y431574I-200J1D01*
G01X1331068Y431435D01*
G02X1330926Y431376I-142J141D01*
G01X1321888D01*
G03X1321746Y431317I0J-200D01*
G01X1321079Y430650D01*
G03X1321020Y430508I141J-142D01*
G01Y426996D01*
G02X1320961Y426854I-200J0D01*
G01X1320536Y426429D01*
G02X1320394Y426370I-142J141D01*
G01X1302693D01*
G03X1302551Y426311I0J-200D01*
G01X1302069Y425829D01*
G03X1302010Y425687I141J-142D01*
G01Y415233D01*
X1302006Y415229D01*
Y400761D01*
G03X1302065Y400619I200J0D01*
G01X1304072Y398612D01*
G02X1304131Y398470I-141J-142D01*
G01Y397832D01*
G02X1303931Y397632I-200J0D01*
G01X1301967D01*
G03X1301826Y397574I0J-200D01*
G01X1296189Y391937D01*
G03X1296130Y391796I141J-142D01*
G01Y390227D01*
G02X1295930Y390027I-200J0D01*
G01X1286216D01*
G02X1286041Y390129I-1J200D01*
G01X1285843Y390480D01*
X1285845Y390587D01*
X1285874Y390634D01*
G03X1286135Y391569I-1541J934D01*
G03X1282531I-1802J0D01*
G03X1282792Y390634I1802J-1D01*
G01X1282821Y390587D01*
X1282823Y390480D01*
X1282625Y390129D01*
G02X1282450Y390027I-174J98D01*
G01X1257644D01*
G02X1257502Y390086I0J200D01*
G01X1256005Y391583D01*
G02X1255946Y391725I141J142D01*
G01Y404332D01*
G02X1256005Y404474I200J0D01*
G01X1259851Y408320D01*
G02X1259993Y408379I142J-141D01*
G01X1269416D01*
G03X1269558Y408438I0J200D01*
G01X1270467Y409347D01*
G03X1270526Y409489I-141J142D01*
G01Y438319D01*
G02X1270646Y438503I200J1D01*
G01X1271036Y438674D01*
X1271153Y438654D01*
X1271197Y438614D01*
G03X1272215Y438216I1018J1103D01*
G03X1273717Y439718I0J1502D01*
G03X1273232Y440824I-1502J1D01*
G02X1273167Y440971I135J148D01*
G01Y441265D01*
G02X1273232Y441412I200J-1D01*
G03X1273717Y442518I-1017J1105D01*
G03X1272215Y444020I-1502J0D01*
G03X1270901Y443246I0J-1502D01*
G01X1270874Y443198D01*
X1270781Y443142D01*
X1270726D01*
G02X1270526Y443342I0J200D01*
G01Y443764D01*
G02X1270585Y443906I200J0D01*
G01X1272467Y445788D01*
X1272600Y445806D01*
X1272659Y445773D01*
G03X1273397Y445579I738J1307D01*
G03X1274899Y447081I0J1502D01*
G03X1274705Y447819I-1501J0D01*
G01X1274672Y447878D01*
X1274690Y448011D01*
X1275325Y448646D01*
X1275431Y448672D01*
X1275485Y448655D01*
G03X1275927Y448589I440J1436D01*
G03X1276434Y448677I0J1502D01*
G01X1276467Y448689D01*
X1278587D01*
X1278620Y448677D01*
G03X1279127Y448589I507J1414D01*
G03X1279634Y448677I0J1502D01*
G01X1279667Y448689D01*
X1280572D01*
X1280674Y448620D01*
X1280696Y448563D01*
G03X1281075Y448012I1396J555D01*
G02X1281140Y447865I-135J-148D01*
G01Y447571D01*
G02X1281075Y447424I-200J1D01*
G03X1280590Y446318I1017J-1105D01*
G03X1283594I1502J0D01*
G03X1283109Y447424I-1502J1D01*
G02X1283044Y447571I135J148D01*
G01Y447865D01*
G02X1283109Y448012I200J-1D01*
G03X1283488Y448563I-1017J1106D01*
G01X1283510Y448620D01*
X1283612Y448689D01*
X1288572D01*
X1288674Y448620D01*
X1288696Y448563D01*
G03X1289075Y448012I1396J555D01*
G02X1289140Y447865I-135J-148D01*
G01Y447571D01*
G02X1289075Y447424I-200J1D01*
G03X1288590Y446318I1017J-1105D01*
G03X1291594I1502J0D01*
G03X1291109Y447424I-1502J1D01*
G02X1291044Y447571I135J148D01*
G01Y447865D01*
G02X1291109Y448012I200J-1D01*
G03X1291488Y448563I-1017J1106D01*
G01X1291510Y448620D01*
X1291612Y448689D01*
X1299101D01*
X1299140Y448671D01*
G03X1299757Y448539I616J1370D01*
G03X1300374Y448671I1J1502D01*
G01X1300413Y448689D01*
X1309094D01*
X1309133Y448671D01*
G03X1309750Y448539I616J1370D01*
G03X1310367Y448671I1J1502D01*
G01X1310406Y448689D01*
G37*
G36*
G01X1287889Y887552D02*
G03X1286568Y887019I-1J-1901D01*
G02X1286442Y886963I-139J144D01*
G01X1286322Y886956D01*
G02X1286191Y886994I-13J200D01*
G03X1285303Y887285I-889J-1211D01*
G01X1285302D01*
G03Y884281I0J-1502D01*
G03X1285527Y884298I0J1502D01*
G02X1285688Y884252I31J-198D01*
G01X1285918Y884054D01*
G02X1285988Y883902I-130J-152D01*
G01Y883664D01*
G02X1285918Y883512I-200J0D01*
G01X1285654Y883285D01*
X1285571Y883261D01*
X1285543Y883265D01*
G03X1283815Y881996I-241J-1483D01*
G01X1283814Y881988D01*
G02X1283625Y881824I-197J36D01*
G01X1278497D01*
G03X1278355Y881765I0J-200D01*
G01X1277934Y881344D01*
G03X1277875Y881202I141J-142D01*
G01Y880419D01*
G02X1277869Y880370I-200J0D01*
G01X1277853Y880306D01*
X1277845Y880288D01*
X1277843Y880284D01*
X1277842Y880283D01*
G03X1277658Y879520I1618J-794D01*
G01X1277656Y879467D01*
X1276382Y878193D01*
G03X1276012Y877301I892J-893D01*
G01Y873549D01*
G03X1276382Y872657I1262J1D01*
G01X1277660Y871379D01*
G03X1278132Y871082I891J893D01*
G01X1278178Y871065D01*
X1278245Y870994D01*
X1278345Y870629D01*
G02X1278307Y870449I-193J-53D01*
G01X1278306Y870448D01*
G03X1277958Y869487I1153J-961D01*
G03X1280962I1502J0D01*
G03X1280673Y870373I-1503J0D01*
G01X1280672Y870374D01*
G02X1280656Y870582I162J117D01*
G01X1280817Y870901D01*
G02X1280996Y871010I178J-91D01*
G01X1281709D01*
G02X1281851Y870951I0J-200D01*
G01X1284222Y868580D01*
G02X1284224Y868578I-140J-142D01*
G01X1284248Y868554D01*
X1284276Y868492D01*
X1284279Y868458D01*
G02X1284247Y868329I-199J-19D01*
G03X1283998Y867500I1253J-828D01*
G01Y867473D01*
G03X1285500Y865998I1502J27D01*
G01X1285502D01*
G03X1286306Y866232I-1J1502D01*
G01X1286314Y866237D01*
G03X1286329Y866247I-826J1255D01*
G01X1286440Y866280D01*
G02X1286576Y866226I-1J-200D01*
G01X1286947Y865855D01*
G03X1287089Y865796I142J141D01*
G01X1287582D01*
G02X1287782Y865596I0J-200D01*
G01Y865550D01*
G03X1287982Y865350I200J0D01*
G01X1290165D01*
X1290282Y865467D01*
Y865474D01*
X1292801D01*
G02X1292991Y865335I0J-200D01*
G01X1293038Y865189D01*
G02X1293035Y865072I-193J-54D01*
G01X1293031Y865061D01*
G02X1292962Y864973I-186J74D01*
G01X1292961Y864972D01*
G03X1292198Y863500I1038J-1472D01*
G03X1295802I1802J0D01*
G03X1295039Y864973I-1803J0D01*
G01X1295027Y864981D01*
G02X1294965Y865071I128J154D01*
G01Y865072D01*
G02X1294964Y865197I190J64D01*
G01X1294968Y865210D01*
X1295008Y865335D01*
G02X1295199Y865474I191J-61D01*
G01X1300901D01*
X1300924Y865451D01*
G02X1300926Y865449I-140J-142D01*
G02X1300980Y865342I-143J-139D01*
G02X1300983Y865309I-197J-35D01*
G01Y862419D01*
G02X1300969Y862344I-200J-1D01*
G01X1300954Y862308D01*
X1300519Y861873D01*
G02X1300378Y861815I-141J142D01*
G01X1300366D01*
X1300259Y861771D01*
G02X1300248Y861767I-74J186D01*
G02X1300184Y861756I-65J189D01*
G01X1296683D01*
G03X1296541Y861697I0J-200D01*
G01X1295851Y861007D01*
G03X1295792Y860865I141J-142D01*
G01Y849447D01*
G03X1295851Y849305I200J0D01*
G01X1296865Y848291D01*
G03X1297007Y848232I142J141D01*
G01X1302488D01*
G02X1302688Y848032I0J-200D01*
G01Y843845D01*
G02X1302666Y843754I-200J0D01*
G02X1302630Y843704I-178J90D01*
G01X1299593Y840667D01*
G03X1299534Y840525I141J-142D01*
G01Y837782D01*
G02X1299529Y837738I-200J0D01*
G02X1299511Y837689I-195J44D01*
G01X1299502Y837672D01*
X1299467Y837606D01*
G02X1299441Y837569I-176J96D01*
G01X1299428Y837554D01*
X1299407Y837539D01*
G03Y834431I1097J-1554D01*
G01X1299428Y834416D01*
X1299441Y834402D01*
G02X1299467Y834363I-152J-130D01*
G01X1299515Y834272D01*
G02X1299534Y834189I-181J-85D01*
G01Y834032D01*
G02X1299531Y833995I-200J-2D01*
G02X1299510Y833937I-197J38D01*
G01X1299479Y833881D01*
X1299478Y833880D01*
G02X1299454Y833845I-176J95D01*
G01X1299453Y833844D01*
X1299410Y833795D01*
X1299405Y833791D01*
X1299392Y833782D01*
G03X1299192Y833613I1124J-1534D01*
G01X1299167Y833589D01*
X1299040Y833530D01*
X1299001Y833528D01*
X1298943Y833525D01*
G02X1298876Y833534I-7J200D01*
G01X1298783Y833566D01*
X1298758Y833585D01*
G03X1297668Y833952I-1090J-1437D01*
G01X1297667D01*
G03X1295865Y832150I0J-1802D01*
G03X1296414Y830855I1802J0D01*
G01X1296432Y830837D01*
X1296459Y830794D01*
X1296466Y830770D01*
G02X1296470Y830669I-191J-58D01*
G01X1296449Y830573D01*
Y830571D01*
X1296396Y830334D01*
G02X1296352Y830247I-195J44D01*
G01X1296334Y830226D01*
G03X1295287Y829084I436J-1451D01*
G02X1295240Y828990I-196J39D01*
G01X1295223Y828972D01*
X1294838Y828843D01*
G02X1294663Y828877I-53J193D01*
G01X1294657Y828882D01*
G03X1294618Y828913I-1141J-1395D01*
G01X1294587Y828939D01*
X1294562Y828956D01*
G03X1293501Y829302I-1062J-1456D01*
G01X1293465D01*
G03X1291698Y827500I35J-1802D01*
G03X1293500Y825698I1802J0D01*
G01X1293502D01*
G03X1293700Y825709I-1J1802D01*
G03X1295287Y827265I-200J1791D01*
G01Y827266D01*
X1295294Y827318D01*
X1295326Y827360D01*
G02X1295405Y827423I160J-120D01*
G01X1295717Y827561D01*
G02X1295724Y827564I82J-182D01*
G02X1295850Y827571I74J-186D01*
G03X1296770Y827260I920J1205D01*
G03X1298285Y828775I0J1515D01*
G03X1297904Y829780I-1516J0D01*
G02X1297858Y829872I150J132D01*
G01X1297853Y829894D01*
X1297955Y830221D01*
G02X1298009Y830306I191J-61D01*
G01X1298093Y830386D01*
X1298135Y830410D01*
X1298158Y830416D01*
G03X1298716Y830685I-492J1734D01*
G03X1298849Y830790I-1049J1465D01*
G01X1298850Y830791D01*
X1298877Y830814D01*
X1298981Y830854D01*
G02X1299034Y830865I67J-188D01*
G01X1299068Y830866D01*
X1299094D01*
G02X1299138Y830862I4J-200D01*
G02X1299168Y830853I-42J-196D01*
G01X1299263Y830816D01*
X1299290Y830794D01*
G03X1299409Y830700I1237J1444D01*
G01X1299429Y830686D01*
X1299458Y830653D01*
X1299464Y830642D01*
X1299510Y830555D01*
X1299516Y830544D01*
G02X1299534Y830472I-182J-84D01*
G01Y830185D01*
G03X1299593Y830043I200J0D01*
G01X1302432Y827204D01*
G02X1302481Y827001I-141J-142D01*
G01X1302372Y826662D01*
G02X1302366Y826645I-192J58D01*
G02X1302213Y826526I-184J79D01*
G03X1300699Y824747I288J-1779D01*
G03X1302501Y822945I1802J0D01*
G01X1302503D01*
G03X1302701Y822956I-1J1802D01*
G03X1304272Y824411I-200J1791D01*
G02X1304318Y824505I196J-38D01*
G01X1304379Y824576D01*
G02X1304469Y824635I151J-132D01*
G01X1304755Y824727D01*
G02X1304958Y824678I61J-190D01*
G01X1305483Y824153D01*
G03X1305625Y824094I142J141D01*
G01X1311655D01*
G02X1311693Y824090I-2J-200D01*
G02X1311795Y824037I-37J-196D01*
G01X1312273Y823559D01*
G02X1312327Y823452I-143J-139D01*
G02X1312330Y823419I-197J-35D01*
G01Y817066D01*
G02X1312308Y816975I-200J0D01*
G02X1312272Y816925I-178J90D01*
G01X1311687Y816340D01*
G02X1311620Y816296I-141J142D01*
G01X1311586Y816282D01*
X1295944D01*
G03X1295802Y816223I0J-200D01*
G01X1291649Y812070D01*
G03X1291590Y811928I141J-142D01*
G01Y805780D01*
G02X1291589Y805764I-200J4D01*
G02X1291567Y805687I-199J15D01*
G02X1291486Y805605I-177J94D01*
G01X1291137Y805427D01*
X1291112Y805415D01*
X1291057Y805419D01*
G02X1290954Y805458I17J199D01*
G03X1290110Y805747I-887J-1213D01*
G01X1290108D01*
G03X1290075Y805748I-62J-1500D01*
G01X1290048D01*
G03Y802744I18J-1502D01*
G01X1290068D01*
G03X1290954Y803034I-1J1502D01*
G02X1291057Y803073I120J-160D01*
G01X1291112Y803077D01*
X1291137Y803065D01*
X1291486Y802887D01*
G02X1291567Y802805I-96J-176D01*
G02X1291590Y802712I-177J-93D01*
G01Y802431D01*
G03X1291649Y802289I200J0D01*
G01X1293579Y800359D01*
G03X1293721Y800300I142J141D01*
G01X1295769D01*
G02X1295903Y800248I0J-200D01*
G01X1296298Y799853D01*
G02X1296350Y799719I-148J-134D01*
G01Y773411D01*
G02X1296336Y773336I-200J-1D01*
G01X1296321Y773300D01*
X1294087Y771066D01*
G02X1294039Y771031I-140J142D01*
G01Y771030D01*
G02X1294003Y771015I-95J177D01*
G02X1293865Y771024I-57J192D01*
G01X1293516Y771178D01*
G02X1293433Y771255I89J179D01*
G01X1293424Y771271D01*
G02X1293405Y771364I181J85D01*
G03X1293406Y771434I-1801J61D01*
G01Y771436D01*
G03X1291604Y773237I-1802J-1D01*
G03X1289802Y771435I0J-1802D01*
G03X1291603Y769633I1802J0D01*
G01X1291605D01*
G03X1291675Y769634I9J1802D01*
G02X1291861Y769523I7J-200D01*
G01X1292015Y769174D01*
G02X1292024Y769036I-183J-81D01*
G02X1292009Y769000I-192J59D01*
G01X1291994Y768973D01*
X1290484Y767463D01*
G02X1290434Y767427I-140J142D01*
G02X1290343Y767405I-91J178D01*
G01X1283286D01*
X1283264Y767410D01*
X1283205Y767423D01*
X1283183Y767433D01*
G03X1282539Y767578I-644J-1358D01*
G03X1281917Y767443I0J-1502D01*
G01X1281877Y767425D01*
X1281678D01*
Y767405D01*
X1271907D01*
G02X1271832Y767419I-1J200D01*
G01X1271796Y767434D01*
X1269156Y770074D01*
G02X1269120Y770124I142J140D01*
G02X1269098Y770215I178J91D01*
G01Y822686D01*
G03X1269069Y822791I-200J1D01*
G01X1269060Y822806D01*
X1269054Y822815D01*
X1269047Y822840D01*
G02X1269039Y822895I192J56D01*
G01Y846231D01*
G02X1269105Y846380I200J0D01*
G01X1269326Y846579D01*
G02X1269478Y846630I134J-148D01*
G01X1269479D01*
G03X1269629Y846622I155J1494D01*
G03Y849626I0J1502D01*
G03X1269480Y849618I6J-1502D01*
G01X1269478D01*
X1269436Y849614D01*
X1269358Y849640D01*
X1269105Y849868D01*
G02X1269039Y850017I134J149D01*
G01Y855116D01*
G02X1269170Y855304I200J0D01*
G01X1269523Y855433D01*
G02X1269744Y855375I69J-188D01*
G01X1269745Y855374D01*
G03X1270892Y854841I1147J968D01*
G03Y857845I0J1502D01*
G03X1269433Y856701I0J-1502D01*
G02X1269239Y856548I-194J47D01*
G01X1269156D01*
X1269039Y856665D01*
Y857273D01*
G02X1269042Y857306I200J-2D01*
G02X1269096Y857413I197J-32D01*
G01X1269883Y858200D01*
G02X1269990Y858254I139J-143D01*
G02X1270023Y858257I35J-197D01*
G01X1273813D01*
G03X1273955Y858316I0J200D01*
G01X1276045Y860406D01*
G03X1276104Y860548I-141J142D01*
G01Y866058D01*
X1276122Y866098D01*
G03X1276298Y866896I-1726J799D01*
G03X1274619Y868785I-1902J0D01*
G01X1274585Y868789D01*
X1274525Y868818D01*
X1269097Y874246D01*
G02X1269053Y874313I142J141D01*
G01X1269039Y874347D01*
Y892976D01*
G02X1269097Y893116I200J-1D01*
G01X1269181Y893202D01*
G02X1269311Y893261I142J-141D01*
G03X1270723Y894760I-90J1499D01*
G03X1270656Y895201I-1502J-3D01*
G01Y895203D01*
X1270645Y895238D01*
X1270650Y895310D01*
X1270793Y895621D01*
X1270845Y895672D01*
X1270878Y895686D01*
G03X1271778Y897062I-602J1376D01*
G03X1270276Y898564I-1502J0D01*
G01X1270275D01*
G03X1269506Y898352I0J-1502D01*
G01X1269483Y898338D01*
X1269431Y898324D01*
X1269239D01*
G02X1269039Y898524I0J200D01*
G01Y901204D01*
G02X1269239Y901404I200J0D01*
G01X1283803D01*
G02X1283841Y901400I-2J-200D01*
G02X1283943Y901347I-37J-196D01*
G01X1285306Y899985D01*
G03X1285448Y899926I142J141D01*
G01X1286483D01*
G02X1286529Y899920I-3J-200D01*
G01X1286539Y899917D01*
G02X1286661Y899821I-53J-193D01*
G01X1286700Y899750D01*
X1286699Y899748D01*
G03X1288000Y898998I1301J753D01*
G01X1288003D01*
G03X1288180Y899009I-4J1502D01*
G02X1288228I24J-199D01*
G03X1288500Y898992I277J2245D01*
G03X1289232Y899115I-4J2261D01*
G02X1289344Y899120I65J-189D01*
G01X1289351Y899118D01*
X1289617Y898852D01*
G02X1289671Y898745I-143J-139D01*
G02X1289674Y898712I-197J-35D01*
G01Y893424D01*
G02X1289664Y893363I-200J1D01*
G01X1289638Y893281D01*
X1289632Y893271D01*
X1289623Y893257D01*
G03X1289327Y892267I1506J-990D01*
G03X1289623Y891277I1802J0D01*
G01X1289632Y891263D01*
X1289638Y891253D01*
X1289664Y891171D01*
G02X1289674Y891110I-190J-62D01*
G01Y887100D01*
G02X1289474Y886900I-200J0D01*
G01X1289370D01*
X1289294Y886933D01*
X1289266Y886963D01*
G03X1287889Y887552I-1376J-1312D01*
G37*
G36*
G01X1265297Y1348187D02*
G03I-491J0D01*
G37*
G36*
G01X1260937D02*
G03I-491J0D01*
G37*
G36*
G01X1265297Y1360099D02*
G03I-491J0D01*
G37*
G36*
G01X1260937D02*
G03I-491J0D01*
G37*
G36*
G01X1265297Y1372385D02*
G03I-491J0D01*
G37*
G36*
G01X1260937D02*
G03I-491J0D01*
G37*
G36*
G01X1265297Y1396583D02*
G03I-491J0D01*
G37*
G36*
G01X1260937D02*
G03I-491J0D01*
G37*
G36*
G01X1265297Y1384297D02*
G03I-491J0D01*
G37*
G36*
G01X1260937D02*
G03I-491J0D01*
G37*
G36*
G01X1265297Y1408495D02*
G03I-491J0D01*
G37*
G36*
G01X1260937D02*
G03I-491J0D01*
G37*
G36*
G01X1277537Y1348187D02*
G03I-491J0D01*
G37*
G36*
G01X1285417D02*
G03I-491J0D01*
G37*
G36*
G01X1273177D02*
G03I-491J0D01*
G37*
G36*
G01X1277537Y1360099D02*
G03I-491J0D01*
G37*
G36*
G01X1285417D02*
G03I-491J0D01*
G37*
G36*
G01X1273177D02*
G03I-491J0D01*
G37*
G36*
G01X1277537Y1372385D02*
G03I-491J0D01*
G37*
G36*
G01X1285417D02*
G03I-491J0D01*
G37*
G36*
G01X1273177D02*
G03I-491J0D01*
G37*
G36*
G01X1277537Y1396583D02*
G03I-491J0D01*
G37*
G36*
G01X1285417D02*
G03I-491J0D01*
G37*
G36*
G01X1273177D02*
G03I-491J0D01*
G37*
G36*
G01X1277537Y1384297D02*
G03I-491J0D01*
G37*
G36*
G01X1285417D02*
G03I-491J0D01*
G37*
G36*
G01X1273177D02*
G03I-491J0D01*
G37*
G36*
G01X1285417Y1408495D02*
G03I-491J0D01*
G37*
G36*
G01X1277537D02*
G03I-491J0D01*
G37*
G36*
G01X1273177D02*
G03I-491J0D01*
G37*
G36*
G01X1406555Y54588D02*
X1435515D01*
X1435890Y54213D01*
Y52966D01*
X1435515Y52591D01*
X1406555D01*
G03X1400618Y46654I0J-5937D01*
G01Y7874D01*
G02X1394744Y2000I-5874J0D01*
G01X1299862D01*
G02X1293988Y7874I0J5874D01*
G01Y46654D01*
G03X1292425Y50669I-5938J0D01*
G01Y50696D01*
X1292470Y50741D01*
X1294823D01*
X1294895Y50669D01*
G02X1295986Y46654I-6842J-4015D01*
G01Y7874D01*
G03X1299862Y3998I3876J0D01*
G01X1394744D01*
G03X1398620Y7874I0J3876D01*
G01Y46654D01*
G02X1406555Y54588I7935J-1D01*
G37*
G36*
G01X1310022Y323536D02*
Y316998D01*
G02X1309963Y316856I-200J0D01*
G01X1309918Y316811D01*
G02X1309776Y316752I-142J141D01*
G01X1302432D01*
G02X1302290Y316811I0J200D01*
G01X1300871Y318230D01*
G02X1300812Y318372I141J142D01*
G01Y323585D01*
G02X1300871Y323727I200J0D01*
G01X1301135Y323991D01*
G02X1301277Y324050I142J-141D01*
G01X1309508D01*
G02X1309650Y323991I0J-200D01*
G01X1309963Y323678D01*
G02X1310022Y323536I-141J-142D01*
G37*
G36*
G01X1302077Y329000D02*
G03I-577J0D01*
G37*
G36*
G01X1345641Y462636D02*
X1346051D01*
G02X1346214Y462552I0J-200D01*
G01X1346431Y462245D01*
X1346445Y462150D01*
X1346429Y462104D01*
G03X1346344Y461607I1417J-498D01*
G03X1347846Y460105I1502J0D01*
G03X1349176Y460909I0J1502D01*
G01X1349198Y460951D01*
X1349275Y461006D01*
X1349641Y461062D01*
G02X1349813Y461005I30J-198D01*
G01X1351919Y458899D01*
G02X1351978Y458757I-141J-142D01*
G01Y454475D01*
X1351894Y454367D01*
X1351826Y454350D01*
G03Y450852I433J-1749D01*
G01X1351894Y450835D01*
X1351978Y450727D01*
Y448997D01*
X1351892Y448888D01*
X1351825Y448872D01*
G03Y445370I426J-1751D01*
G01X1351892Y445354D01*
X1351978Y445245D01*
Y443985D01*
X1351895Y443878D01*
X1351827Y443861D01*
G03Y440367I445J-1747D01*
G01X1351895Y440350D01*
X1351978Y440243D01*
Y437014D01*
X1351877Y436900D01*
X1351801Y436891D01*
G03Y433311I207J-1790D01*
G01X1351877Y433302D01*
X1351978Y433188D01*
Y381895D01*
G02X1351919Y381753I-200J0D01*
G01X1347386Y377220D01*
G02X1347245Y377162I-141J142D01*
G01X1331337D01*
G03X1330445Y376792I1J-1262D01*
G01X1329836Y376183D01*
G02X1329695Y376124I-142J141D01*
G01X1307492D01*
G02X1307315Y376230I0J200D01*
G01X1307123Y376591D01*
X1307128Y376700D01*
X1307159Y376747D01*
G03X1307410Y377495I-1249J835D01*
G01X1307412Y377541D01*
X1307456Y377620D01*
X1307785Y377855D01*
X1307874Y377870D01*
X1307918Y377857D01*
G03X1308410Y377789I490J1734D01*
G03X1306608Y379591I0J1802D01*
G03X1306611Y379483I1802J-4D01*
G01X1306614Y379437D01*
X1306580Y379353D01*
X1306280Y379082D01*
X1306194Y379057D01*
X1306148Y379064D01*
G03X1305910Y379083I-238J-1483D01*
G03X1304408Y377581I0J-1502D01*
G03X1304661Y376747I1501J0D01*
G01X1304692Y376700D01*
X1304697Y376591D01*
X1304505Y376230D01*
G02X1304328Y376124I-177J94D01*
G01X1300332D01*
G02X1300132Y376324I0J200D01*
G01Y378788D01*
X1300134Y378801D01*
G03X1300148Y379028I-1788J224D01*
G03X1300134Y379255I-1802J3D01*
G01X1300132Y379268D01*
Y390138D01*
G02X1300191Y390280I200J0D01*
G01X1303483Y393572D01*
G02X1303625Y393631I142J-141D01*
G01X1304784D01*
G02X1304925Y393572I-1J-200D01*
G01X1305438Y393059D01*
G03X1305580Y393000I142J141D01*
G01X1334083D01*
G03X1334225Y393059I0J200D01*
G01X1336106Y394940D01*
G03X1336164Y395082I-142J141D01*
G01Y406278D01*
G03X1336106Y406420I-200J1D01*
G01X1332743Y409782D01*
G02X1332684Y409924I141J142D01*
G01Y427310D01*
G02X1332743Y427451I200J-1D01*
G01X1335141Y429849D01*
X1335208Y429915D01*
G03X1335267Y430057I-141J142D01*
G01Y446784D01*
G02X1335326Y446926I200J0D01*
G01X1335352Y446952D01*
Y449605D01*
G03X1335293Y449747I-200J0D01*
G01X1334836Y450204D01*
G03X1334694Y450263I-142J-141D01*
G01X1330372D01*
G02X1330243Y450310I0J200D01*
G03X1327923I-1160J-1379D01*
G02X1327794Y450263I-129J153D01*
G01X1326199D01*
G02X1326057Y450322I0J200D01*
G01X1325350Y451029D01*
G02X1325291Y451171I141J142D01*
G01Y460491D01*
G02X1325350Y460633I200J0D01*
G01X1327294Y462577D01*
G02X1327436Y462636I142J-141D01*
G01X1338051D01*
G02X1338214Y462552I0J-200D01*
G01X1338431Y462245D01*
X1338445Y462150D01*
X1338429Y462104D01*
G03X1338344Y461607I1417J-498D01*
G03X1341348I1502J0D01*
G03X1341263Y462104I-1502J-1D01*
G01X1341247Y462150D01*
X1341261Y462245D01*
X1341478Y462552D01*
G02X1341641Y462636I163J-116D01*
G01X1342051D01*
G02X1342214Y462552I0J-200D01*
G01X1342431Y462245D01*
X1342445Y462150D01*
X1342429Y462104D01*
G03X1342344Y461607I1417J-498D01*
G03X1345348I1502J0D01*
G03X1345263Y462104I-1502J-1D01*
G01X1345247Y462150D01*
X1345261Y462245D01*
X1345478Y462552D01*
G02X1345641Y462636I163J-116D01*
G37*
G36*
G01X1304269Y813589D02*
X1306241D01*
G02X1306383Y813530I0J-200D01*
G01X1309033Y810880D01*
G02X1309092Y810738I-141J-142D01*
G01Y800331D01*
G02X1309033Y800189I-200J0D01*
G01X1306881Y798037D01*
G02X1306739Y797978I-142J141D01*
G01X1300839D01*
G02X1300680Y798057I0J200D01*
G01X1300459Y798349D01*
X1300442Y798441D01*
X1300454Y798486D01*
G03X1300522Y798975I-1734J490D01*
G03X1298720Y800777I-1802J0D01*
G03X1297518Y800318I0J-1803D01*
G01X1297458Y800264D01*
X1297300Y800268D01*
X1296325Y801243D01*
G03X1296184Y801302I-142J-141D01*
G01X1295942D01*
G02X1295801Y801360I0J200D01*
G01X1295367Y801794D01*
G02X1295308Y801936I141J142D01*
G01Y812066D01*
G02X1295367Y812208I200J0D01*
G01X1296689Y813530D01*
G02X1296831Y813589I142J-141D01*
G01X1300011D01*
G02X1300170Y813511I1J-200D01*
G01X1300392Y813222D01*
X1300410Y813132D01*
X1300398Y813087D01*
G03X1300338Y812625I1742J-461D01*
G03X1303942I1802J0D01*
G03X1303882Y813087I-1802J1D01*
G01X1303870Y813132D01*
X1303888Y813222D01*
X1304110Y813511D01*
G02X1304269Y813589I158J-122D01*
G37*
G36*
G01X1294657Y901373D02*
X1298918D01*
G02X1299060Y901314I0J-200D01*
G01X1299827Y900547D01*
G02X1299886Y900405I-141J-142D01*
G01Y898262D01*
G03X1299945Y898120I200J0D01*
G01X1300629Y897436D01*
G03X1300771Y897377I142J141D01*
G01X1302642D01*
G02X1302784Y897318I0J-200D01*
G01X1305808Y894294D01*
G03X1305950Y894235I142J141D01*
G01X1314343D01*
G02X1314485Y894176I0J-200D01*
G01X1315491Y893170D01*
X1315521Y893083D01*
X1315515Y893037D01*
G03X1315504Y892863I1391J-175D01*
G01Y892862D01*
G03X1316906Y891460I1402J0D01*
G03X1318131Y892180I0J1402D01*
G02X1318306Y892283I175J-97D01*
G01X1318655D01*
G02X1318830Y892180I0J-200D01*
G03X1319374Y891637I1224J683D01*
G02X1319477Y891462I-97J-175D01*
G01Y891112D01*
G02X1319374Y890937I-200J0D01*
G03Y888487I681J-1225D01*
G02X1319477Y888312I-97J-175D01*
G01Y887962D01*
G02X1319374Y887787I-200J0D01*
G03X1318653Y886562I680J-1225D01*
G03X1319373Y885337I1402J0D01*
G02X1319476Y885162I-97J-175D01*
G01Y884813D01*
G02X1319373Y884638I-200J0D01*
G03X1318874Y884168I683J-1225D01*
G02X1318706Y884076I-168J108D01*
G01X1318256D01*
G02X1318088Y884168I0J200D01*
G03X1317739Y884541I-1181J-756D01*
G02X1317658Y884688I119J161D01*
G01Y885336D01*
X1317296Y885566D01*
X1316685D01*
G02X1316563Y885625I21J199D01*
G01X1315937Y886251D01*
G03X1315795Y886310I-142J-141D01*
G01X1314864D01*
G03X1314722Y886251I0J-200D01*
G01X1314673Y886202D01*
G02X1314390I-141J141D01*
G01X1312328Y888264D01*
G02X1312304Y888518I141J141D01*
G03X1312563Y889361I-1242J843D01*
G03X1311061Y890863I-1502J0D01*
G03X1309957Y890380I0J-1503D01*
G01X1309930Y890350D01*
X1309820Y890301D01*
G02X1309738Y890283I-83J182D01*
G01X1309396D01*
G02X1309258Y890338I0J200D01*
G03X1308220Y890755I-1039J-1085D01*
G01X1308218D01*
G03X1307422Y890526I1J-1502D01*
G01X1307390Y890505D01*
X1307319Y890491D01*
X1307199Y890512D01*
G02X1307128Y890539I34J197D01*
G01X1307093Y890561D01*
X1307070Y890592D01*
G03X1305250Y891512I-1821J-1342D01*
G03X1303651Y890849I1J-2262D01*
G01X1303172Y890371D01*
G02X1303031Y890312I-142J141D01*
G01X1302233D01*
G02X1302088Y890374I0J200D01*
G01X1301859Y890616D01*
X1301831Y890691D01*
X1301833Y890733D01*
G03X1301836Y890854I-2258J117D01*
G01Y891800D01*
G03X1299575Y894062I-2262J0D01*
G03X1299535Y894061I37J-2261D01*
G01X1299494Y894060D01*
X1299420Y894090D01*
X1299187Y894318D01*
G02X1299128Y894461I141J142D01*
G01Y894993D01*
G03X1296868Y897254I-2261J0D01*
G01X1296866D01*
G03X1295662Y896907I0J-2262D01*
G02X1295627Y896890I-104J171D01*
G03X1294188Y894800I798J-2090D01*
G01Y893735D01*
G02X1294065Y893551I-200J1D01*
G01X1294008Y893527D01*
X1293890Y893551D01*
X1291183Y896258D01*
X1291154Y896286D01*
X1291124Y896360D01*
Y897840D01*
G02X1291183Y897982I200J0D01*
G01X1294515Y901314D01*
G02X1294657Y901373I142J-141D01*
G37*
G36*
G01X1310517Y1254968D02*
X1359077D01*
G02X1359219Y1254909I0J-200D01*
G01X1360227Y1253901D01*
G02X1360286Y1253759I-141J-142D01*
G01Y1215829D01*
G02X1360227Y1215687I-200J0D01*
G01X1359773Y1215233D01*
G02X1359631Y1215174I-142J141D01*
G01X1342913D01*
X1342086Y1216001D01*
X1342036Y1216051D01*
X1331944D01*
X1331893Y1216000D01*
X1331067Y1215174D01*
X1312177D01*
G03X1312035Y1215115I0J-200D01*
G01X1310344Y1213424D01*
G03X1310285Y1213282I141J-142D01*
G01Y1195532D01*
G03X1310344Y1195390I200J0D01*
G01X1311181Y1194553D01*
G03X1311323Y1194494I142J141D01*
G01X1370119D01*
G02X1370261Y1194435I0J-200D01*
G01X1370810Y1193886D01*
Y1191653D01*
X1371195Y1191268D01*
X1373428D01*
X1378660Y1186036D01*
G02X1378719Y1185894I-141J-142D01*
G01Y1157818D01*
G02X1378660Y1157676I-200J0D01*
G01X1378299Y1157315D01*
G02X1378157Y1157256I-142J141D01*
G01X1292870D01*
G02X1292728Y1157315I0J200D01*
G01X1291075Y1158968D01*
X1291046Y1158996D01*
X1291016Y1159070D01*
Y1234623D01*
X1297876Y1241483D01*
X1313056D01*
X1314298Y1242725D01*
Y1248397D01*
X1313920Y1248775D01*
X1309274D01*
X1308896Y1249153D01*
Y1253347D01*
X1310517Y1254968D01*
G37*
G36*
G01X1302017Y1348187D02*
G03I-491J0D01*
G37*
G36*
G01X1297657D02*
G03I-491J0D01*
G37*
G36*
G01X1289777D02*
G03I-491J0D01*
G37*
G36*
G01X1302017Y1360099D02*
G03I-491J0D01*
G37*
G36*
G01X1297657D02*
G03I-491J0D01*
G37*
G36*
G01X1289777D02*
G03I-491J0D01*
G37*
G36*
G01X1302017Y1372385D02*
G03I-491J0D01*
G37*
G36*
G01X1297657D02*
G03I-491J0D01*
G37*
G36*
G01X1289777D02*
G03I-491J0D01*
G37*
G36*
G01X1302017Y1396583D02*
G03I-491J0D01*
G37*
G36*
G01X1297657D02*
G03I-491J0D01*
G37*
G36*
G01X1289777D02*
G03I-491J0D01*
G37*
G36*
G01X1302017Y1384297D02*
G03I-491J0D01*
G37*
G36*
G01X1297657D02*
G03I-491J0D01*
G37*
G36*
G01X1289777D02*
G03I-491J0D01*
G37*
G36*
G01X1302017Y1408495D02*
G03I-491J0D01*
G37*
G36*
G01X1289777D02*
G03I-491J0D01*
G37*
G36*
G01X1297657D02*
G03I-491J0D01*
G37*
G36*
G01X1311223Y323946D02*
X1316615D01*
G02X1316757Y323887I0J-200D01*
G01X1316995Y323649D01*
G02X1317054Y323507I-141J-142D01*
G01Y316555D01*
G02X1316995Y316413I-200J0D01*
G01X1316727Y316145D01*
G02X1316585Y316086I-142J141D01*
G01X1311424D01*
G02X1311282Y316145I0J200D01*
G01X1311023Y316404D01*
Y323746D01*
G02X1311223Y323946I200J0D01*
G37*
G36*
G01X1330812Y358415D02*
X1330857Y358382D01*
G03X1331922Y358034I1065J1454D01*
G03X1333177Y358543I0J1802D01*
G02X1333316Y358600I140J-143D01*
G01X1345487D01*
G02X1345628Y358541I-1J-200D01*
G01X1348486Y355683D01*
G02X1348545Y355541I-141J-142D01*
G01Y349025D01*
G02X1348486Y348883I-200J0D01*
G01X1347101Y347498D01*
G03X1347042Y347356I141J-142D01*
G01Y342626D01*
G02X1346961Y342465I-200J0D01*
G01X1346665Y342246D01*
X1346572Y342229D01*
X1346527Y342243D01*
G03X1346093Y342307I-434J-1438D01*
G03Y339303I0J-1502D01*
G03X1346527Y339367I0J1502D01*
G01X1346572Y339381D01*
X1346665Y339364D01*
X1346961Y339145D01*
G02X1347042Y338984I-119J-161D01*
G01Y338684D01*
G03X1347057Y338607I200J-1D01*
G01X1347086Y338539D01*
G02X1347101Y338462I-185J-76D01*
G01Y326470D01*
G03X1347160Y326328I200J0D01*
G01X1347760Y325728D01*
G02X1347819Y325586I-141J-142D01*
G01Y324561D01*
G02X1347760Y324419I-200J0D01*
G01X1347671Y324330D01*
X1347622Y324303D01*
X1347594Y324297D01*
G03X1346232Y322935I396J-1758D01*
G01X1346226Y322907D01*
X1346199Y322858D01*
X1345524Y322183D01*
G02X1345382Y322124I-142J141D01*
G01X1334555D01*
G02X1334409Y322188I1J200D01*
G01X1334180Y322433D01*
X1334153Y322511D01*
X1334156Y322553D01*
G03X1334161Y322685I-1797J134D01*
G03X1330557I-1802J0D01*
G03X1330562Y322553I1802J2D01*
G01X1330565Y322511D01*
X1330538Y322433D01*
X1330309Y322188D01*
G02X1330163Y322124I-147J136D01*
G01X1320214D01*
G02X1320072Y322183I0J200D01*
G01X1317582Y324673D01*
G03X1317440Y324732I-142J-141D01*
G01X1317412D01*
G02X1317271Y324790I0J200D01*
G01X1317171Y324889D01*
G03X1317030Y324948I-142J-141D01*
G01X1310684D01*
G03X1310543Y324889I1J-200D01*
G01X1310497Y324843D01*
G02X1310214I-141J141D01*
G01X1310064Y324993D01*
G03X1309923Y325052I-142J-141D01*
G01X1306215D01*
G02X1306074Y325110I0J200D01*
G01X1306005Y325179D01*
G02X1305947Y325320I142J141D01*
G01Y331356D01*
G03X1305888Y331497I-200J-1D01*
G01X1305788Y331598D01*
G02X1305730Y331739I142J141D01*
G01Y331837D01*
G02X1305789Y331979I200J0D01*
G01X1306255Y332445D01*
G02X1306397Y332504I142J-141D01*
G01X1313439D01*
G03X1313581Y332563I0J200D01*
G01X1313718Y332700D01*
G02X1313816Y332754I142J-141D01*
G02X1313864Y332759I45J-195D01*
G01X1314193Y332752D01*
X1314267Y332719D01*
X1314295Y332689D01*
G03X1315397Y332207I1102J1019D01*
G03Y335211I0J1502D01*
G03X1314470Y334891I0J-1503D01*
G01X1314444Y334871D01*
X1314368Y334844D01*
G02X1314235Y334843I-68J188D01*
G01X1314088Y334895D01*
X1314019Y334975D01*
X1314008Y335027D01*
G03X1313974Y335170I-1768J-345D01*
G01X1313967Y335196D01*
Y337910D01*
G02X1314061Y338080I200J0D01*
G03X1314892Y339391I-958J1526D01*
G01X1314896Y339425D01*
X1314925Y339484D01*
X1314964Y339523D01*
G02X1315106Y339582I142J-141D01*
G01X1320694D01*
G02X1320836Y339523I0J-200D01*
G01X1321460Y338899D01*
G02X1321519Y338757I-141J-142D01*
G01Y333584D01*
G03X1321578Y333442I200J0D01*
G01X1321855Y333165D01*
X1321856Y333164D01*
G03X1321870Y333150I856J842D01*
G01X1322325Y332695D01*
G03X1322339Y332681I856J842D01*
G01X1322340Y332680D01*
X1322617Y332403D01*
G03X1322759Y332344I142J141D01*
G01X1340124D01*
G03X1340266Y332403I0J200D01*
G01X1340653Y332790D01*
G03X1340712Y332932I-141J142D01*
G01Y350241D01*
G03X1340653Y350383I-200J0D01*
G01X1340606Y350430D01*
X1340578Y350487D01*
X1340573Y350520D01*
G03X1340232Y351207I-1190J-163D01*
G01X1339940Y351498D01*
G02X1339882Y351640I142J141D01*
G01Y353034D01*
G03X1339529Y353884I-1202J-1D01*
G01X1339528D01*
X1338736Y354676D01*
Y354677D01*
G03X1337886Y355030I-851J-849D01*
G01X1333104D01*
G03X1332254Y354677I1J-1202D01*
G01X1332053Y354476D01*
G03X1331700Y353626I849J-851D01*
G01Y352570D01*
G02X1331500Y352370I-200J0D01*
G01X1329627D01*
G02X1329486Y352429I1J200D01*
G01X1329345Y352570D01*
G03X1328495Y352922I-850J-849D01*
G01X1328174D01*
G02X1327974Y353122I1J201D01*
G01Y353432D01*
X1327976Y353446D01*
G03X1327990Y353651I-1487J205D01*
G01Y355232D01*
G02X1328049Y355374I200J0D01*
G01X1329785Y357109D01*
G03X1330222Y358083I-1062J1062D01*
G01X1330225Y358139D01*
X1330286Y358228D01*
X1330705Y358425D01*
X1330812Y358415D01*
G37*
G36*
G01X1318978Y359986D02*
X1327063D01*
G02X1327205Y359927I0J-200D01*
G01X1327807Y359325D01*
G02X1327866Y359183I-141J-142D01*
G01Y356690D01*
G02X1327807Y356548I-200J0D01*
G01X1327341Y356083D01*
G03X1326988Y355232I849J-851D01*
G01Y353650D01*
G02X1326984Y353586I-499J-1D01*
G01Y353583D01*
X1326975Y353517D01*
G03X1326972Y353489I197J-35D01*
G01Y353122D01*
G02X1326772Y352922I-200J0D01*
G01X1323024D01*
G03X1322174Y352570I0J-1201D01*
G01X1321552Y351948D01*
G03X1321293Y351561I850J-849D01*
G01X1321277Y351524D01*
X1321252Y351499D01*
G03X1321193Y351357I141J-142D01*
G01Y345596D01*
G02X1321134Y345454I-200J0D01*
G01X1320099Y344419D01*
G02X1319957Y344360I-142J141D01*
G01X1307108D01*
G02X1306966Y344419I0J200D01*
G01X1306406Y344979D01*
G02X1306347Y345121I141J142D01*
G01Y347355D01*
G02X1306406Y347496I200J-1D01*
G01X1318837Y359927D01*
G02X1318978Y359986I142J-141D01*
G37*
G36*
G01X1305801Y395610D02*
Y398285D01*
G03X1305742Y398427I-200J0D01*
G01X1303087Y401082D01*
G02X1303028Y401224I141J142D01*
G01Y424378D01*
G02X1303087Y424520I200J0D01*
G01X1303835Y425268D01*
G02X1303977Y425327I142J-141D01*
G01X1321305D01*
G03X1321447Y425386I0J200D01*
G01X1322145Y426084D01*
G03X1322204Y426226I-141J142D01*
G01Y429273D01*
G02X1322263Y429415I200J0D01*
G01X1322750Y429902D01*
G02X1322892Y429961I142J-141D01*
G01X1329715D01*
G02X1329857Y429902I0J-200D01*
G01X1330624Y429135D01*
G02X1330683Y428993I-141J-142D01*
G01Y409095D01*
G03X1330742Y408953I200J0D01*
G01X1334104Y405591D01*
G02X1334163Y405449I-141J-142D01*
G01Y395911D01*
G02X1334104Y395769I-200J0D01*
G01X1333396Y395061D01*
G02X1333254Y395002I-142J141D01*
G01X1306409D01*
G02X1306267Y395061I0J200D01*
G01X1305860Y395468D01*
G02X1305801Y395610I141J142D01*
G37*
G36*
G01X1306052Y838748D02*
X1307674D01*
G02X1307815Y838690I0J-200D01*
G01X1307905Y838601D01*
G03X1308046Y838542I142J141D01*
G01X1312376D01*
G02X1312517Y838484I0J-200D01*
G01X1312858Y838143D01*
G02X1312917Y838001I-141J-142D01*
G01Y837255D01*
X1312901Y837217D01*
G03Y835123I854J-1047D01*
G01X1312917Y835085D01*
Y834106D01*
X1312901Y834068D01*
G03Y831974I854J-1047D01*
G01X1312917Y831936D01*
Y830956D01*
X1312901Y830918D01*
G03Y828824I854J-1047D01*
G01X1312917Y828786D01*
Y827571D01*
G02X1312858Y827429I-200J0D01*
G01X1311890Y826461D01*
X1311862Y826432D01*
X1311788Y826402D01*
X1306228D01*
G02X1306086Y826461I0J200D01*
G01X1305609Y826938D01*
X1305580Y826966D01*
X1305550Y827040D01*
Y838246D01*
G02X1305609Y838388I200J0D01*
G01X1305910Y838689D01*
G02X1306052Y838748I142J-141D01*
G37*
G36*
G01X1312089Y859303D02*
G02X1312149Y859294I1J-200D01*
G01X1312208Y859275D01*
X1312209D01*
G03X1312269Y859265I62J190D01*
G01X1312395D01*
G02X1312572Y859158I0J-200D01*
G01X1312624Y859060D01*
X1312621Y858955D01*
X1312595Y858910D01*
G03X1312404Y858218I1161J-693D01*
G03X1315108I1352J0D01*
G03X1314995Y858758I-1352J-1D01*
G01X1314975Y858806D01*
X1314984Y858907D01*
X1315164Y859176D01*
G02X1315330Y859265I166J-111D01*
G01X1315332D01*
G02X1315498Y859176I0J-200D01*
G01X1315678Y858907D01*
X1315687Y858806D01*
X1315667Y858758D01*
G03X1315554Y858218I1239J-541D01*
G03X1318258I1352J0D01*
G03X1318145Y858758I-1352J-1D01*
G01X1318125Y858806D01*
X1318134Y858907D01*
X1318314Y859176D01*
G02X1318480Y859265I166J-111D01*
G01X1318481D01*
G02X1318647Y859176I0J-200D01*
G01X1318827Y858907D01*
X1318836Y858806D01*
X1318816Y858758D01*
G03X1318703Y858218I1239J-541D01*
G03X1321407I1352J0D01*
G03X1321294Y858758I-1352J-1D01*
G01X1321274Y858806D01*
X1321283Y858907D01*
X1321463Y859176D01*
G02X1321629Y859265I166J-111D01*
G01X1321631D01*
G02X1321797Y859176I0J-200D01*
G01X1321977Y858907D01*
X1321986Y858806D01*
X1321966Y858758D01*
G03X1321853Y858218I1239J-541D01*
G03X1324557I1352J0D01*
G03X1324444Y858758I-1352J-1D01*
G01X1324424Y858806D01*
X1324433Y858907D01*
X1324613Y859176D01*
G02X1324779Y859265I166J-111D01*
G01X1324781D01*
G02X1324947Y859176I0J-200D01*
G01X1325127Y858907D01*
X1325136Y858806D01*
X1325116Y858758D01*
G03X1325003Y858218I1239J-541D01*
G03X1327707I1352J0D01*
G03X1327594Y858758I-1352J-1D01*
G01X1327574Y858806D01*
X1327583Y858907D01*
X1327763Y859176D01*
G02X1327929Y859265I166J-111D01*
G01X1327930D01*
G02X1328096Y859176I0J-200D01*
G01X1328276Y858907D01*
X1328285Y858806D01*
X1328265Y858758D01*
G03X1328152Y858218I1239J-541D01*
G03X1330856I1352J0D01*
G03X1330743Y858758I-1352J-1D01*
G01X1330723Y858806D01*
X1330732Y858907D01*
X1330912Y859176D01*
G02X1331078Y859265I166J-111D01*
G01X1331080D01*
G02X1331246Y859176I0J-200D01*
G01X1331426Y858907D01*
X1331435Y858806D01*
X1331415Y858758D01*
G03X1331302Y858218I1239J-541D01*
G03X1334006I1352J0D01*
G03X1333893Y858758I-1352J-1D01*
G01X1333873Y858806D01*
X1333882Y858907D01*
X1334062Y859176D01*
G02X1334228Y859265I166J-111D01*
G01X1336056D01*
Y859243D01*
X1336829Y858470D01*
X1336865D01*
X1337766Y857569D01*
X1337780Y857546D01*
G03X1338171Y857115I1173J672D01*
G01X1338255Y856952D01*
Y856337D01*
G02X1338196Y856195I-200J0D01*
G01X1338173Y856172D01*
X1338160Y856163D01*
G03X1337885Y855897I793J-1095D01*
G02X1337728Y855820I-158J123D01*
G01X1337725D01*
X1337030D01*
X1336800Y855458D01*
Y854868D01*
G02X1336741Y854740I-200J14D01*
G01X1335036Y853035D01*
X1335011Y853014D01*
G03X1334735Y852747I793J-1095D01*
G02X1334578Y852670I-158J123D01*
G01X1333860D01*
G02X1333774Y852689I-1J200D01*
G01X1333760Y852696D01*
G03X1332654Y853270I-1106J-779D01*
G03Y850566I0J-1352D01*
G03X1332737Y850569I-7J1352D01*
G01X1332758Y850560D01*
X1332833Y850487D01*
G02X1332894Y850344I-139J-144D01*
G01Y850303D01*
X1332863Y850228D01*
X1332758Y850127D01*
X1332737Y850118D01*
G03X1332654Y850121I-90J-1349D01*
G03Y847417I0J-1352D01*
G03X1333738Y847961I0J1352D01*
G01X1333782Y847971D01*
X1334189Y847815D01*
G02X1334317Y847629I-72J-187D01*
G01Y846759D01*
G02X1334189Y846573I-200J1D01*
G01X1333782Y846417D01*
X1333738Y846427D01*
G03X1332654Y846971I-1084J-808D01*
G03Y844267I0J-1352D01*
G03X1333738Y844811I0J1352D01*
G01X1333782Y844821D01*
X1334189Y844665D01*
G02X1334317Y844479I-72J-187D01*
G01Y844392D01*
G02X1334258Y844250I-200J0D01*
G01X1333589Y843581D01*
X1333448Y843566D01*
X1333389Y843605D01*
G03X1332654Y843822I-735J-1136D01*
G03X1331302Y842470I0J-1352D01*
G03X1331519Y841735I1353J0D01*
G01X1331558Y841676D01*
X1331543Y841535D01*
X1330428Y840420D01*
X1330367Y840391D01*
X1330334Y840388D01*
G03X1329506Y840672I-829J-1068D01*
G01X1329504D01*
G03X1328257Y839843I0J-1352D01*
G01X1328242Y839806D01*
X1328037Y839602D01*
G02X1327896Y839544I-141J142D01*
G01X1327781D01*
X1327674Y839625D01*
X1327656Y839689D01*
G03X1325054I-1301J-369D01*
G01X1325036Y839625D01*
X1324929Y839544D01*
X1324629D01*
X1324523Y839624D01*
X1324504Y839689D01*
G03X1321904I-1300J-369D01*
G01X1321885Y839624D01*
X1321779Y839544D01*
X1321481D01*
X1321374Y839625D01*
X1321356Y839689D01*
G03X1318754I-1301J-369D01*
G01X1318736Y839625D01*
X1318629Y839544D01*
X1318332D01*
X1318225Y839625D01*
X1318207Y839689D01*
G03X1317718Y840401I-1301J-369D01*
G01X1317680Y840430D01*
X1317638Y840513D01*
Y841229D01*
G02X1317718Y841389I200J0D01*
G03X1318258Y842470I-812J1081D01*
G03X1316906Y843822I-1352J0D01*
G03X1315625Y842902I0J-1352D01*
G01X1315610Y842857D01*
X1315413Y842661D01*
G02X1315131I-141J142D01*
G01X1315110Y842682D01*
X1315083Y842731D01*
X1315077Y842760D01*
G03X1313756Y843822I-1321J-291D01*
G01X1313755D01*
G03X1312635Y843227I0J-1352D01*
G01X1312608Y843187D01*
X1312524Y843140D01*
X1312233Y843131D01*
X1312148Y843171D01*
X1312118Y843210D01*
G03X1310971Y843771I-1147J-892D01*
G03Y840867I0J-1452D01*
G03X1312207Y841558I0J1451D01*
G01X1312233Y841599D01*
X1312314Y841649D01*
X1312605Y841670D01*
X1312692Y841634D01*
X1312724Y841597D01*
G03X1313671Y841121I1032J873D01*
G01X1313710Y841118D01*
X1313781Y841084D01*
X1313938Y840911D01*
G02X1313989Y840792I-149J-134D01*
G02X1313990Y840776I-199J-20D01*
G01Y840455D01*
G03X1314048Y840315I200J1D01*
G01X1314477Y839885D01*
G02X1314520Y839667I-142J-141D01*
G01X1314497Y839611D01*
X1314397Y839544D01*
X1308461D01*
G02X1308319Y839603I0J200D01*
G01X1305093Y842829D01*
X1305064Y842857D01*
X1305034Y842931D01*
Y845314D01*
G03X1305004Y845419I-200J0D01*
G01X1304990Y845443D01*
X1304975Y845495D01*
Y850245D01*
G02X1305034Y850387I200J0D01*
G01X1305045Y850398D01*
G03X1305104Y850540I-141J142D01*
G01Y850846D01*
Y851541D01*
X1304975Y851623D01*
Y851912D01*
G02X1305034Y852054I200J0D01*
G01X1305039Y852059D01*
G03X1305098Y852201I-141J142D01*
G01Y855033D01*
G02X1305157Y855175I200J0D01*
G01X1309226Y859244D01*
G02X1309368Y859303I142J-141D01*
G01X1312089D01*
G37*
G36*
G01X1313895Y869606D02*
X1316884D01*
G02X1316891Y869601I-112J-164D01*
G01X1316918Y869579D01*
X1316942Y869559D01*
G03X1317071Y869512I129J153D01*
G01X1319690D01*
X1319715Y869506D01*
G03X1319983Y869464I342J1308D01*
G01X1320020Y869462D01*
X1320053Y869447D01*
G02X1320113Y869406I-81J-183D01*
G01X1320136Y869295D01*
X1320071Y869133D01*
G02X1319907Y869009I-186J75D01*
G03X1318703Y867665I148J-1344D01*
G03X1320055Y866313I1352J0D01*
G01Y866312D01*
G03X1321126Y866839I0J1352D01*
G01X1321139Y866856D01*
X1321157Y866871D01*
G02X1321192Y866894I127J-155D01*
G01X1321275Y866937D01*
G02X1321361Y866956I85J-181D01*
G01X1321714D01*
G02X1321811Y866931I0J-200D01*
G01X1321892Y866886D01*
X1321961Y866823D01*
G03X1323029Y866173I1244J842D01*
G01X1323071Y866168D01*
G03X1323205Y866162I134J1497D01*
G03X1324289Y866625I-1J1503D01*
G01X1324317Y866653D01*
X1324423Y866700D01*
G02X1324502Y866717I81J-183D01*
G01X1325273D01*
G02X1325346Y866703I0J-200D01*
G01X1325444Y866665D01*
X1325463Y866649D01*
G03X1325469Y866643I959J953D01*
G01X1325471Y866642D01*
G03X1326355Y866313I884J1023D01*
G03X1327707Y867665I0J1352D01*
G03X1327242Y868686I-1353J0D01*
G01X1327153Y868764D01*
X1327145Y868793D01*
X1327164Y868850D01*
G02X1327167Y868858I189J-66D01*
G01X1327179Y868891D01*
X1327303Y869214D01*
X1327311Y869231D01*
G02X1327487Y869336I176J-95D01*
G01X1328372D01*
G02X1328548Y869231I0J-200D01*
G01X1328556Y869214D01*
X1328680Y868891D01*
X1328692Y868858D01*
G02X1328695Y868850I-186J-74D01*
G01X1328714Y868793D01*
X1328706Y868764D01*
X1328617Y868686D01*
G03X1328152Y867665I888J-1021D01*
G03X1330856I1352J0D01*
G03X1330391Y868686I-1353J0D01*
G01X1330302Y868764D01*
X1330294Y868793D01*
X1330313Y868850D01*
G02X1330316Y868858I189J-66D01*
G01X1330328Y868891D01*
X1330452Y869214D01*
X1330460Y869231D01*
G02X1330636Y869336I176J-95D01*
G01X1331522D01*
G02X1331698Y869231I0J-200D01*
G01X1331706Y869214D01*
X1331830Y868891D01*
X1331842Y868858D01*
G02X1331845Y868850I-186J-74D01*
G01X1331864Y868793D01*
X1331856Y868764D01*
X1331767Y868686D01*
G03X1331302Y867665I888J-1021D01*
G03X1334006I1352J0D01*
G03X1333541Y868686I-1353J0D01*
G01X1333452Y868764D01*
X1333444Y868793D01*
X1333463Y868850D01*
G02X1333466Y868858I189J-66D01*
G01X1333478Y868891D01*
X1333602Y869214D01*
X1333610Y869231D01*
G02X1333786Y869336I176J-95D01*
G01X1334809D01*
G02X1334826Y869335I-3J-200D01*
G02X1334939Y869283I-23J-199D01*
G01X1334941Y869281D01*
G02X1334943Y869279I-140J-142D01*
G01X1334965Y869257D01*
G03X1335538Y868938I849J850D01*
G03X1335803Y868906I276J1169D01*
G01X1335804D01*
X1335845Y868905D01*
X1335879Y868891D01*
G02X1335941Y868849I-79J-184D01*
G01X1336056Y868734D01*
Y868693D01*
X1336694Y868055D01*
G02X1336730Y868006I-141J-142D01*
G02X1336752Y867927I-178J-92D01*
G01Y867178D01*
G03X1336811Y867036I200J0D01*
G01X1336960Y866887D01*
G03X1337102Y866828I142J141D01*
G01X1337688D01*
G02X1337725Y866824I-3J-200D01*
G01X1337727D01*
G02X1337763Y866813I-40J-196D01*
G01X1337882Y866759D01*
X1337909Y866728D01*
G03X1337960Y866675I1036J946D01*
G02X1337962Y866673I-140J-142D01*
G03X1338036Y866604I993J990D01*
G01X1338067Y866577D01*
X1338111Y866488D01*
G02X1338132Y866399I-179J-89D01*
G01Y863207D01*
G02X1338072Y863075I-200J11D01*
G01X1338042Y863050D01*
G02X1338036Y863047I-92J177D01*
G01X1337871Y862964D01*
X1337832Y862945D01*
X1337810Y862923D01*
G03X1337808Y862921I140J-142D01*
G01X1337753Y862865D01*
G02X1337751Y862863I-142J140D01*
G01X1337714Y862826D01*
G03X1337712Y862824I140J-142D01*
G01X1337661Y862771D01*
X1337648Y862758D01*
G03X1337347Y862240I855J-844D01*
G01X1337334Y862198D01*
X1337283Y862160D01*
G02X1337187Y862120I-122J159D01*
G01X1337030D01*
X1336800Y861758D01*
Y861139D01*
G02X1336775Y861070I-198J33D01*
G01Y861068D01*
G02X1336752Y861036I-173J100D01*
G02X1336743Y861026I-153J129D01*
G01X1336226Y860509D01*
G02X1336129Y860456I-141J142D01*
G01X1336103Y860451D01*
X1336101D01*
X1336092Y860450D01*
X1334276D01*
G02X1334171Y860480I0J200D01*
G02X1334116Y860530I105J170D01*
G01X1334108Y860541D01*
X1333960Y860745D01*
G02X1333933Y860797I162J117D01*
G01Y860926D01*
X1333936Y860936D01*
G03X1334006Y861366I-1282J429D01*
G01Y861391D01*
G03X1332654Y862719I-1352J-24D01*
G03X1331302Y861367I0J-1352D01*
G03X1331376Y860926I1351J0D01*
G01X1331403Y860848D01*
X1331406Y860838D01*
X1331408Y860834D01*
G02X1331385Y860794I-184J79D01*
G01X1331195Y860533D01*
G02X1331178Y860511I-166J111D01*
G02X1331053Y860451I-144J139D01*
G02X1331033Y860450I-20J199D01*
G01X1330937D01*
G02X1330903Y860453I1J200D01*
G02X1330766Y860548I35J197D01*
G01X1330705Y860649D01*
G02X1330685Y860701I175J97D01*
G01X1330726Y860788D01*
G03X1330856Y861362I-1222J579D01*
G01Y861388D01*
G03X1329504Y862719I-1352J-21D01*
G03X1328152Y861367I0J-1352D01*
G03X1328226Y860926I1351J0D01*
G01X1328253Y860848D01*
X1328256Y860838D01*
X1328258Y860834D01*
G02X1328235Y860794I-184J79D01*
G01X1328045Y860533D01*
G02X1328028Y860511I-166J111D01*
G02X1327903Y860451I-144J139D01*
G02X1327883Y860450I-20J199D01*
G01X1327788D01*
G02X1327754Y860453I1J200D01*
G02X1327617Y860548I35J197D01*
G01X1327556Y860649D01*
G02X1327536Y860701I175J97D01*
G01X1327577Y860788D01*
G03X1327707Y861362I-1222J579D01*
G01Y861388D01*
G03X1326355Y862719I-1352J-21D01*
G03X1325003Y861367I0J-1352D01*
G03X1325077Y860926I1351J0D01*
G01X1325104Y860848D01*
X1325107Y860838D01*
X1325109Y860834D01*
G02X1325086Y860794I-184J79D01*
G01X1324896Y860533D01*
G02X1324879Y860511I-166J111D01*
G02X1324754Y860451I-144J139D01*
G02X1324734Y860450I-20J199D01*
G01X1324638D01*
G02X1324604Y860453I1J200D01*
G02X1324467Y860548I35J197D01*
G01X1324406Y860649D01*
G02X1324386Y860701I175J97D01*
G01X1324427Y860788D01*
G03X1324557Y861362I-1222J579D01*
G01Y861388D01*
G03X1324408Y861985I-1352J-20D01*
G03X1324404Y861991I-168J-107D01*
G03X1324398Y862002I-1189J-641D01*
G02X1324396Y862006I178J91D01*
G03X1324340Y862101I-1192J-638D01*
G01X1324341D01*
G03X1323294Y862716I-1135J-734D01*
G01X1323240Y862721D01*
G02X1323216Y862740I111J165D01*
G01X1323145Y862814D01*
G02X1323096Y862938I151J131D01*
G01Y863627D01*
G03X1323037Y863769I-200J0D01*
G01X1322332Y864474D01*
G03X1322191Y864532I-141J-142D01*
G01X1321191D01*
G03X1321050Y864474I0J-200D01*
G01X1320439Y863863D01*
G02X1320372Y863819I-141J142D01*
G01X1320338Y863805D01*
X1319657D01*
G03X1319515Y863746I0J-200D01*
G01X1319401Y863632D01*
G03X1319342Y863490I141J-142D01*
G01Y862858D01*
G03X1319401Y862716I200J0D01*
G01X1319533Y862584D01*
G03X1319675Y862525I142J141D01*
G01X1320224D01*
G02X1320256Y862522I-3J-200D01*
G01X1320258D01*
G02X1320364Y862468I-34J-197D01*
G01X1321050Y861782D01*
G03X1321191Y861724I141J142D01*
G01X1321420D01*
G02X1321511Y861702I0J-200D01*
G02X1321550Y861676I-91J-178D01*
G01X1321801Y861426D01*
G02X1321822Y861400I-145J-138D01*
G01Y861398D01*
G02X1321855Y861304I-166J-111D01*
G01Y861299D01*
G03X1321927Y860927I1350J68D01*
G01X1321959Y860834D01*
G02X1321935Y860793I-184J80D01*
G01X1321747Y860533D01*
G02X1321726Y860509I-161J119D01*
G01X1321725Y860508D01*
G02X1321607Y860451I-141J142D01*
G01X1321604D01*
G02X1321584Y860450I-20J199D01*
G01X1318528D01*
G02X1318423Y860480I0J200D01*
G02X1318368Y860530I105J170D01*
G01X1318176Y860794D01*
G02X1318156Y860827I160J120D01*
G02X1318140Y860879I182J84D01*
G01X1318132Y860925D01*
X1318147Y860972D01*
G03X1318208Y861359I-1241J394D01*
G01Y861384D01*
G03X1316906Y862669I-1302J-17D01*
G03X1315604Y861388I0J-1302D01*
G01Y861365D01*
G03X1315665Y860972I1302J1D01*
G01X1315672Y860949D01*
G02X1315641Y860800I-197J-37D01*
G01X1315584Y860721D01*
X1315447Y860533D01*
G02X1315430Y860511I-166J111D01*
G02X1315305Y860451I-144J139D01*
G02X1315285Y860450I-20J199D01*
G01X1315191D01*
G02X1315019Y860548I0J200D01*
G01X1314957Y860652D01*
G02X1314929Y860755I172J102D01*
G01X1314937Y860793D01*
X1314946Y860835D01*
X1314954Y860853D01*
G03X1315058Y861364I-1199J510D01*
G01Y861393D01*
G03X1313756Y862668I-1302J-27D01*
G03X1312454Y861383I0J-1302D01*
G01Y861364D01*
G03X1312512Y860984I1302J4D01*
G01X1312515Y860971D01*
Y860970D01*
X1312516Y860967D01*
X1312529Y860926D01*
X1312522Y860880D01*
G02X1312486Y860794I-198J32D01*
G01X1312410Y860689D01*
X1312292Y860527D01*
G02X1312281Y860514I-158J122D01*
G01X1312272Y860505D01*
G02X1312155Y860451I-138J145D01*
G02X1312136Y860450I-20J199D01*
G01X1309270D01*
G03X1309128Y860391I0J-200D01*
G01X1308978Y860241D01*
X1308938Y860226D01*
G03X1308518Y859953I431J-1122D01*
G01X1306310Y857745D01*
G02X1306260Y857709I-140J142D01*
G02X1306169Y857687I-91J178D01*
G01X1305663D01*
G02X1305572Y857709I0J200D01*
G02X1305522Y857745I90J178D01*
G01X1305258Y858009D01*
G02X1305222Y858059I142J140D01*
G02X1305200Y858150I178J91D01*
G01Y858735D01*
X1305210Y858742D01*
Y859435D01*
X1305200Y859442D01*
Y860683D01*
G03X1305141Y860825I-200J0D01*
G01X1303064Y862902D01*
G02X1303028Y862952I142J140D01*
G02X1303006Y863043I178J91D01*
G01Y865367D01*
G02X1303007Y865386I200J-1D01*
G01Y865387D01*
G02X1303046Y865485I199J-22D01*
G02X1303064Y865506I160J-119D01*
G01X1303197Y865639D01*
G02X1303317Y865697I142J-141D01*
G01X1303328Y865698D01*
X1305018D01*
G03X1305635Y865863I0J1237D01*
G01X1305639Y865866D01*
X1305644Y865868D01*
X1305680Y865884D01*
G02X1305693Y865889I78J-184D01*
G01X1305704Y865892D01*
X1305745Y865904D01*
G02X1305800Y865912I56J-192D01*
G01X1309821D01*
G02X1309853Y865909I-3J-200D01*
G01X1309904Y865899D01*
G03X1310994Y865407I1090J961D01*
G03X1312446Y866859I0J1452D01*
G03X1312205Y867660I-1452J0D01*
G01X1312185Y867691D01*
X1312177Y867725D01*
G02X1312174Y867800I195J45D01*
G01X1312188Y867899D01*
Y867901D01*
G02X1312207Y867961I198J-30D01*
G01X1312258Y868056D01*
X1312269Y868066D01*
G03X1312295Y868090I-843J939D01*
G03X1312298Y868093I-140J143D01*
G02X1312300Y868095I142J-140D01*
G03X1312304Y868099I-890J894D01*
G02X1312306Y868101I142J-140D01*
G03X1312313Y868108I-889J896D01*
G01X1313754Y869548D01*
G02X1313895Y869606I141J-142D01*
G37*
G36*
G01X1314397Y1096020D02*
Y1058207D01*
Y1056904D01*
X1315782Y1055519D01*
X1334165D01*
X1335036Y1056390D01*
Y1058821D01*
Y1071074D01*
G02X1335095Y1071216I200J0D01*
G01X1335309Y1071430D01*
G02X1335451Y1071489I142J-141D01*
G01X1356143D01*
G03X1356285Y1071548I0J200D01*
G01X1357643Y1072906D01*
G03X1357702Y1073048I-141J142D01*
G01Y1097275D01*
X1354679Y1100298D01*
G02X1354620Y1100440I141J142D01*
G01Y1104783D01*
G02X1354679Y1104925I200J0D01*
G01X1354721Y1104967D01*
G02X1354863Y1105026I142J-141D01*
G01X1360085D01*
G02X1360227Y1104967I0J-200D01*
G01X1361938Y1103256D01*
G03X1362080Y1103197I142J141D01*
G01X1365907D01*
G02X1366049Y1103138I0J-200D01*
G01X1369222Y1099965D01*
G03X1369364Y1099906I142J141D01*
G01X1379035D01*
G02X1379177Y1099847I0J-200D01*
G01X1379951Y1099073D01*
G02X1380010Y1098931I-141J-142D01*
G01Y1072748D01*
G03X1380069Y1072606I200J0D01*
G01X1381611Y1071063D01*
G03X1381753Y1071004I142J141D01*
G01X1402258D01*
G02X1402400Y1070945I0J-200D01*
G01X1402671Y1070674D01*
G02X1402730Y1070532I-141J-142D01*
G01Y1058768D01*
Y1056474D01*
X1403419Y1055785D01*
X1421859D01*
X1423122Y1057048D01*
Y1058999D01*
Y1088246D01*
G02X1423137Y1088322I200J0D01*
G01X1423153Y1088360D01*
Y1092827D01*
X1423127Y1092853D01*
Y1097554D01*
G03X1423068Y1097696I-200J0D01*
G01X1420466Y1100298D01*
G02X1420407Y1100440I141J142D01*
G01Y1104783D01*
G02X1420466Y1104925I200J0D01*
G01X1420508Y1104967D01*
G02X1420650Y1105026I142J-141D01*
G01X1425872D01*
G02X1426014Y1104967I0J-200D01*
G01X1427725Y1103256D01*
G03X1427867Y1103197I142J141D01*
G01X1431694D01*
G02X1431836Y1103138I0J-200D01*
G01X1435018Y1099956D01*
G03X1435160Y1099897I142J141D01*
G01X1437953D01*
G02X1438095Y1099838I0J-200D01*
G01X1438713Y1099220D01*
G02X1438772Y1099078I-141J-142D01*
G01Y1097855D01*
G02X1438713Y1097713I-200J0D01*
G01X1433872Y1092873D01*
G03X1433813Y1092731I141J-142D01*
G01Y1051222D01*
G02X1433754Y1051080I-200J0D01*
G01X1433547Y1050873D01*
X1433519Y1050844D01*
X1433445Y1050814D01*
X1310327D01*
G02X1310185Y1050873I0J200D01*
G01X1308315Y1052743D01*
X1308286Y1052771D01*
X1308256Y1052845D01*
Y1095883D01*
Y1098106D01*
X1308731Y1098581D01*
X1313867D01*
X1314397Y1098051D01*
Y1096020D01*
G37*
G36*
G01X1316421Y1058603D02*
X1315878Y1059146D01*
Y1069654D01*
X1316941Y1070717D01*
X1332856D01*
X1333825Y1069748D01*
Y1059792D01*
Y1058155D01*
X1332763Y1057093D01*
X1317931D01*
X1316421Y1058603D01*
G37*
G36*
G01X1348445Y1120863D02*
X1361684D01*
G02X1361826Y1120804I0J-200D01*
G01X1362153Y1120477D01*
G02X1362212Y1120335I-141J-142D01*
G01Y1107335D01*
G02X1362153Y1107193I-200J0D01*
G01X1361027Y1106067D01*
G02X1360885Y1106008I-142J141D01*
G01X1360602D01*
X1360583Y1106028D01*
X1354448D01*
G03X1354307Y1105969I1J-200D01*
G01X1353677Y1105339D01*
G03X1353618Y1105198I141J-142D01*
G01Y1100025D01*
G03X1353677Y1099884I200J1D01*
G01X1356349Y1097211D01*
G02X1356408Y1097070I-141J-142D01*
G01Y1097016D01*
X1356422Y1097002D01*
X1356452Y1096929D01*
Y1073275D01*
G02X1356393Y1073133I-200J0D01*
G01X1355956Y1072696D01*
G02X1355814Y1072637I-142J141D01*
G01X1316784D01*
G02X1316642Y1072696I0J200D01*
G01X1315928Y1073410D01*
G02X1315869Y1073552I141J142D01*
G01Y1104857D01*
G03X1315871Y1104889I-1497J110D01*
G03Y1104903I-200J7D01*
G03X1315869Y1104935I-1499J-78D01*
G01Y1120414D01*
G02X1315928Y1120556I200J0D01*
G01X1316176Y1120804D01*
G02X1316318Y1120863I142J-141D01*
G01X1329779D01*
G02X1329921Y1120804I0J-200D01*
G01X1330025Y1120700D01*
G02X1330084Y1120558I-141J-142D01*
G01Y1107335D01*
G02X1330025Y1107193I-200J0D01*
G01X1328899Y1106067D01*
G02X1328757Y1106008I-142J141D01*
G01X1328474D01*
X1328455Y1106028D01*
X1322320D01*
G03X1322179Y1105969I1J-200D01*
G01X1321549Y1105339D01*
G03X1321490Y1105198I141J-142D01*
G01Y1100025D01*
G03X1321549Y1099884I200J1D01*
G01X1325002Y1096431D01*
G03X1325143Y1096372I142J141D01*
G01X1340411D01*
G03X1340552Y1096431I-1J200D01*
G01X1340576Y1096455D01*
X1340649Y1096485D01*
X1343481D01*
G03X1343623Y1096544I0J200D01*
G01X1347938Y1100859D01*
G03X1347997Y1101001I-141J142D01*
G01Y1120415D01*
G02X1348056Y1120557I200J0D01*
G01X1348303Y1120804D01*
G02X1348445Y1120863I142J-141D01*
G37*
G36*
G01X1316582Y1156179D02*
X1463290D01*
X1463364Y1156149D01*
X1463392Y1156120D01*
X1464450Y1155062D01*
G02X1464509Y1154920I-141J-142D01*
G01Y1123975D01*
X1464479Y1123901D01*
X1464450Y1123873D01*
X1463946Y1123369D01*
G02X1463804Y1123310I-142J141D01*
G01X1438980D01*
G03X1438838Y1123251I0J-200D01*
G01X1436243Y1120656D01*
G03X1436184Y1120514I141J-142D01*
G01Y1113777D01*
G02X1436150Y1113664I-200J-1D01*
G02X1436125Y1113634I-165J112D01*
G03X1435966Y1113418I630J-630D01*
G01X1435952Y1113391D01*
X1435404Y1112843D01*
G02X1435262Y1112784I-142J141D01*
G01X1429129D01*
X1429106Y1112807D01*
Y1121516D01*
G03X1429047Y1121658I-200J0D01*
G01X1428710Y1121995D01*
G03X1428568Y1122054I-142J-141D01*
G01X1416668D01*
G03X1416526Y1121995I0J-200D01*
G01X1416483Y1121952D01*
X1416455Y1121923D01*
X1416381Y1121893D01*
X1414275D01*
X1413890Y1122278D01*
Y1126918D01*
X1415019Y1128048D01*
G03X1415078Y1128189I-141J142D01*
G01Y1129599D01*
G03X1415019Y1129740I-200J-1D01*
G01X1413679Y1131080D01*
X1410271D01*
G03X1410130Y1131139I-142J-141D01*
G01X1408720D01*
G03X1408579Y1131080I1J-200D01*
G01X1406112Y1128613D01*
G03X1406053Y1128472I141J-142D01*
G01Y1122511D01*
X1405435Y1121893D01*
G03X1405293Y1121834I0J-200D01*
G01X1404115Y1120656D01*
G03X1404056Y1120514I141J-142D01*
G01Y1113825D01*
G02X1404039Y1113745I-200J1D01*
G01X1403992Y1113639D01*
X1403965Y1113612D01*
G03X1403722Y1113169I628J-633D01*
G01X1403716Y1113140D01*
X1403689Y1113091D01*
X1403510Y1112912D01*
X1403482Y1112883D01*
X1403408Y1112853D01*
X1403337D01*
G03X1403226Y1112819I1J-200D01*
G01X1403201Y1112802D01*
X1403144Y1112784D01*
X1397001D01*
X1396978Y1112807D01*
Y1121516D01*
G03X1396919Y1121658I-200J0D01*
G01X1396582Y1121995D01*
G03X1396440Y1122054I-142J-141D01*
G01X1382000D01*
G02X1381858Y1122113I0J200D01*
G01X1381452Y1122519D01*
X1381423Y1122547D01*
X1381422Y1122550D01*
X1372695D01*
X1370656Y1120511D01*
G03X1370597Y1120369I141J-142D01*
G01Y1113761D01*
G02X1370583Y1113688I-200J1D01*
G01X1370544Y1113590D01*
X1370522Y1113564D01*
G03X1370346Y1113249I674J-583D01*
G01X1370343Y1113240D01*
G02X1370292Y1113150I-193J50D01*
G01X1369985Y1112843D01*
X1369957Y1112814D01*
X1369883Y1112784D01*
X1363542D01*
X1363519Y1112807D01*
Y1121516D01*
G03X1363460Y1121658I-200J0D01*
G01X1363123Y1121995D01*
G03X1362981Y1122054I-142J-141D01*
G01X1351081D01*
G03X1350939Y1121995I0J-200D01*
G01X1350896Y1121952D01*
G02X1350754Y1121893I-142J141D01*
G01X1348281D01*
G02X1348139Y1121952I0J200D01*
G01X1347893Y1122198D01*
X1347864Y1122226D01*
X1347834Y1122300D01*
Y1126306D01*
G02X1347891Y1126446I200J0D01*
G01X1348676Y1127231D01*
X1348943Y1127499D01*
X1348992Y1127548D01*
G03X1349051Y1127690I-141J142D01*
G01Y1128974D01*
G03X1348992Y1129116I-200J0D01*
G01X1348084Y1130024D01*
G03X1347942Y1130083I-142J-141D01*
G01X1346575D01*
X1346552Y1130060D01*
X1344963D01*
G02X1344822Y1130118I0J200D01*
G01X1344509Y1130430D01*
G03X1344367Y1130489I-142J-141D01*
G01X1343083D01*
G03X1342941Y1130430I0J-200D01*
G01X1340471Y1127960D01*
G03X1340428Y1127895I142J-141D01*
G01X1340413Y1127859D01*
Y1122157D01*
G02X1340354Y1122015I-200J0D01*
G01X1338528Y1120189D01*
G03X1338469Y1120047I141J-142D01*
G01Y1113737D01*
G02X1338456Y1113667I-200J1D01*
G01X1338420Y1113570D01*
X1338399Y1113544D01*
G03X1338244Y1113262I691J-563D01*
G01X1338243Y1113259D01*
G02X1338195Y1113181I-190J63D01*
G01X1337972Y1112958D01*
X1337944Y1112929D01*
X1337870Y1112899D01*
X1337607D01*
G03X1337468Y1112842I1J-200D01*
G01X1337466Y1112840D01*
G02X1337327Y1112784I-139J144D01*
G01X1331414D01*
X1331391Y1112807D01*
Y1121516D01*
G03X1331332Y1121658I-200J0D01*
G01X1330995Y1121995D01*
G03X1330853Y1122054I-142J-141D01*
G01X1318953D01*
G03X1318811Y1121995I0J-200D01*
G01X1318768Y1121952D01*
G02X1318626Y1121893I-142J141D01*
G01X1316574D01*
G02X1316432Y1121952I0J200D01*
G01X1315865Y1122519D01*
G02X1315806Y1122661I141J142D01*
G01Y1133253D01*
G02X1315826Y1133339I200J-1D01*
G01X1315835Y1133358D01*
X1315843Y1133370D01*
G03X1315840Y1148682I-11316J7654D01*
G01X1315824Y1148706D01*
X1315807Y1148759D01*
X1315806Y1148793D01*
Y1155403D01*
G02X1315863Y1155543I200J0D01*
G01X1316440Y1156120D01*
G02X1316442Y1156122I142J-140D01*
G02X1316582Y1156179I140J-143D01*
G37*
G36*
G01X1311461Y1212949D02*
X1312333Y1213821D01*
G02X1312475Y1213880I142J-141D01*
G01X1331758D01*
X1332879Y1215001D01*
X1340955D01*
X1341225Y1214731D01*
Y1214704D01*
X1342049Y1213880D01*
X1419212D01*
X1420094Y1214762D01*
X1421868D01*
X1422750Y1213880D01*
X1432553D01*
X1433361Y1214688D01*
X1434892D01*
X1435700Y1213880D01*
X1441346D01*
X1442204Y1214738D01*
X1446511D01*
X1446626Y1214623D01*
Y1196717D01*
X1446016Y1196107D01*
X1443360D01*
X1385304D01*
G02X1385162Y1196166I0J200D01*
G01X1384663Y1196665D01*
G02X1384604Y1196807I141J142D01*
G01Y1200622D01*
G03X1384545Y1200764I-200J0D01*
G01X1383702Y1201607D01*
G03X1383560Y1201666I-142J-141D01*
G01X1371359D01*
G03X1371217Y1201607I0J-200D01*
G01X1370585Y1200975D01*
G03X1370526Y1200833I141J-142D01*
G01Y1196307D01*
G02X1370326Y1196107I-200J0D01*
G01X1312102D01*
G02X1311960Y1196166I0J200D01*
G01X1311461Y1196665D01*
G02X1311402Y1196807I141J142D01*
G01Y1212807D01*
G02X1311461Y1212949I200J0D01*
G37*
G36*
G01X1311117Y1256342D02*
X1355772D01*
X1360954D01*
X1362398Y1254898D01*
Y1215558D01*
X1362627Y1215329D01*
X1373519D01*
X1375091D01*
X1376651D01*
X1376847Y1215525D01*
Y1241077D01*
X1373445Y1244479D01*
Y1255959D01*
X1374592Y1257106D01*
Y1259188D01*
X1376847Y1261443D01*
Y1270733D01*
X1375739Y1271841D01*
X1370421D01*
X1313808D01*
X1311488Y1274161D01*
X1307753D01*
X1306739Y1273147D01*
Y1271068D01*
Y1268253D01*
Y1256968D01*
X1307365Y1256342D01*
X1311117D01*
G37*
G36*
G01X1324828Y1299574D02*
X1362268D01*
G02X1362409Y1299515I-1J-200D01*
G01X1364096Y1297828D01*
G02X1364155Y1297686I-141J-142D01*
G01Y1288237D01*
G02X1364096Y1288095I-200J0D01*
G01X1363349Y1287348D01*
G02X1363207Y1287289I-142J141D01*
G01X1324617D01*
G03X1324475Y1287230I0J-200D01*
G01X1321757Y1284512D01*
G02X1321615Y1284453I-142J141D01*
G01X1313543D01*
G02X1313401Y1284512I0J200D01*
G01X1312817Y1285096D01*
G02X1312758Y1285238I141J142D01*
G01Y1287747D01*
G02X1312817Y1287889I200J0D01*
G01X1313239Y1288311D01*
G02X1313381Y1288370I142J-141D01*
G01X1321750D01*
G03X1321892Y1288429I0J200D01*
G01X1323070Y1289607D01*
G03X1323129Y1289749I-141J142D01*
G01Y1297874D01*
G02X1323188Y1298016I200J0D01*
G01X1324687Y1299515D01*
G02X1324828Y1299574I142J-141D01*
G37*
G36*
G01X1314257Y1348187D02*
G03I-491J0D01*
G37*
G36*
G01X1309897D02*
G03I-491J0D01*
G37*
G36*
G01Y1360099D02*
G03I-491J0D01*
G37*
G36*
G01X1314257D02*
G03I-491J0D01*
G37*
G36*
G01Y1372385D02*
G03I-491J0D01*
G37*
G36*
G01X1309897D02*
G03I-491J0D01*
G37*
G36*
G01X1314257Y1396583D02*
G03I-491J0D01*
G37*
G36*
G01X1309897D02*
G03I-491J0D01*
G37*
G36*
G01X1314257Y1384297D02*
G03I-491J0D01*
G37*
G36*
G01X1309897D02*
G03I-491J0D01*
G37*
G36*
G01X1314257Y1408495D02*
G03I-491J0D01*
G37*
G36*
G01X1309897D02*
G03I-491J0D01*
G37*
G36*
G01X1303357Y1461182D02*
G03I-491J0D01*
G37*
G36*
G01Y1456451D02*
G03I-491J0D01*
G37*
G36*
G01X1312018Y1460782D02*
G03I-491J0D01*
G37*
G36*
G01Y1465513D02*
G03I-491J0D01*
G37*
G36*
G01Y1476136D02*
G03I-491J0D01*
G37*
G36*
G01Y1470244D02*
G03I-491J0D01*
G37*
G36*
G01Y1480867D02*
G03I-491J0D01*
G37*
G36*
G01X1303357Y1465913D02*
G03I-491J0D01*
G37*
G36*
G01Y1476536D02*
G03I-491J0D01*
G37*
G36*
G01Y1471805D02*
G03I-491J0D01*
G37*
G36*
G01Y1481267D02*
G03I-491J0D01*
G37*
G36*
G01X1312018Y1496222D02*
G03I-491J0D01*
G37*
G36*
G01X1303357Y1491891D02*
G03I-491J0D01*
G37*
G36*
G01Y1487160D02*
G03I-491J0D01*
G37*
G36*
G01Y1496622D02*
G03I-491J0D01*
G37*
G36*
G01X1312018Y1491491D02*
G03I-491J0D01*
G37*
G36*
G01Y1485598D02*
G03I-491J0D01*
G37*
G36*
G01Y1506845D02*
G03I-491J0D01*
G37*
G36*
G01Y1500953D02*
G03I-491J0D01*
G37*
G36*
G01Y1511576D02*
G03I-491J0D01*
G37*
G36*
G01X1303357Y1507245D02*
G03I-491J0D01*
G37*
G36*
G01Y1502514D02*
G03I-491J0D01*
G37*
G36*
G01Y1511976D02*
G03I-491J0D01*
G37*
G36*
G01X1312018Y1516307D02*
G03I-491J0D01*
G37*
G36*
G01X1303357Y1558813D02*
G03I-491J0D01*
G37*
G36*
G01Y1563544D02*
G03I-491J0D01*
G37*
G36*
G01Y1568275D02*
G03I-491J0D01*
G37*
G36*
G01Y1574167D02*
G03I-491J0D01*
G37*
G36*
G01Y1578898D02*
G03I-491J0D01*
G37*
G36*
G01X1312018Y1563144D02*
G03I-491J0D01*
G37*
G36*
G01Y1567875D02*
G03I-491J0D01*
G37*
G36*
G01Y1578498D02*
G03I-491J0D01*
G37*
G36*
G01Y1572606D02*
G03I-491J0D01*
G37*
G36*
G01Y1583229D02*
G03I-491J0D01*
G37*
G36*
G01Y1593853D02*
G03I-491J0D01*
G37*
G36*
G01Y1587960D02*
G03I-491J0D01*
G37*
G36*
G01X1303357Y1594253D02*
G03I-491J0D01*
G37*
G36*
G01Y1589522D02*
G03I-491J0D01*
G37*
G36*
G01Y1583629D02*
G03I-491J0D01*
G37*
G36*
G01X1312018Y1609207D02*
G03I-491J0D01*
G37*
G36*
G01Y1598584D02*
G03I-491J0D01*
G37*
G36*
G01Y1603315D02*
G03I-491J0D01*
G37*
G36*
G01X1303357Y1609607D02*
G03I-491J0D01*
G37*
G36*
G01Y1598984D02*
G03I-491J0D01*
G37*
G36*
G01Y1604876D02*
G03I-491J0D01*
G37*
G36*
G01X1312018Y1613938D02*
G03I-491J0D01*
G37*
G36*
G01Y1618669D02*
G03I-491J0D01*
G37*
G36*
G01X1303357Y1614338D02*
G03I-491J0D01*
G37*
G36*
G01X1333105Y354028D02*
X1337885D01*
G02X1338027Y353969I0J-200D01*
G01X1338821Y353175D01*
G02X1338880Y353033I-141J-142D01*
G01Y351225D01*
G03X1338939Y351083I200J0D01*
G01X1339524Y350498D01*
G02X1339583Y350356I-141J-142D01*
G01Y334178D01*
G02X1339524Y334036I-200J0D01*
G01X1338892Y333404D01*
G02X1338751Y333346I-141J142D01*
G01X1323174D01*
G02X1323032Y333404I-1J200D01*
G01X1322579Y333857D01*
G02X1322521Y333999I142J141D01*
G01Y339172D01*
G03X1322462Y339313I-200J-1D01*
G01X1322260Y339516D01*
G02X1322201Y339657I141J142D01*
G01Y345566D01*
X1322212Y345597D01*
G03X1322291Y346078I-1423J481D01*
G03X1322212Y346559I-1502J0D01*
G01X1322201Y346590D01*
Y351097D01*
G02X1322260Y351239I200J0D01*
G01X1322883Y351862D01*
G02X1323025Y351921I142J-141D01*
G01X1328494D01*
G02X1328636Y351862I0J-200D01*
G01X1329527Y350971D01*
G03X1329669Y350912I142J141D01*
G01X1331935D01*
G03X1332077Y350971I0J200D01*
G01X1332643Y351537D01*
G03X1332702Y351679I-141J142D01*
G01Y353625D01*
G02X1332761Y353767I200J0D01*
G01X1332963Y353969D01*
G02X1333105Y354028I142J-141D01*
G37*
G36*
G01X1334675Y876281D02*
G03X1335249Y875826I1128J833D01*
G01X1335284Y875811D01*
X1336056Y875040D01*
Y874992D01*
X1336742Y874306D01*
Y873396D01*
X1336992Y873146D01*
X1337813D01*
G02X1337825Y873131I-150J-132D01*
G03X1338090Y872859I1128J833D01*
G02X1338167Y872702I-123J-158D01*
G01Y872215D01*
G02X1338108Y872073I-200J0D01*
G01X1336001Y869966D01*
G02X1335859Y869907I-142J141D01*
G01X1335815D01*
G02X1335673Y869966I0J200D01*
G01X1333621Y872017D01*
G02Y872299I142J141D01*
G01X1334075Y872753D01*
G03X1334134Y872895I-141J142D01*
G01Y874298D01*
G03X1334075Y874440I-200J0D01*
G01X1333892Y874623D01*
X1333878Y874648D01*
G03X1333338Y875188I-1224J-684D01*
G01X1333313Y875202D01*
X1333040Y875475D01*
G02X1332981Y875617I141J142D01*
G01Y875635D01*
X1333147Y875801D01*
X1333184Y875816D01*
G03X1333782Y876281I-530J1298D01*
G02X1333943Y876362I161J-119D01*
G01X1334514D01*
G02X1334675Y876281I0J-200D01*
G37*
G36*
G01X1324065Y967623D02*
G03I-511J0D01*
G37*
G36*
G01X1331793Y1097374D02*
X1325475D01*
X1322492Y1100357D01*
Y1104866D01*
X1322652Y1105026D01*
X1328040D01*
X1329810Y1103256D01*
G03X1329952Y1103197I142J141D01*
G01X1332093D01*
X1333862D01*
X1335039Y1102020D01*
X1337250Y1099809D01*
X1339158D01*
X1339698D01*
X1340236Y1099271D01*
Y1097531D01*
X1340079Y1097374D01*
X1334614D01*
X1331793D01*
G37*
G36*
G01X1326497Y1348187D02*
G03I-491J0D01*
G37*
G36*
G01X1322137D02*
G03I-491J0D01*
G37*
G36*
G01X1334377D02*
G03I-491J0D01*
G37*
G36*
G01X1326497Y1360099D02*
G03I-491J0D01*
G37*
G36*
G01X1322137D02*
G03I-491J0D01*
G37*
G36*
G01X1334377D02*
G03I-491J0D01*
G37*
G36*
G01X1326497Y1372385D02*
G03I-491J0D01*
G37*
G36*
G01X1322137D02*
G03I-491J0D01*
G37*
G36*
G01X1334377D02*
G03I-491J0D01*
G37*
G36*
G01X1326497Y1396583D02*
G03I-491J0D01*
G37*
G36*
G01X1322137D02*
G03I-491J0D01*
G37*
G36*
G01X1334377D02*
G03I-491J0D01*
G37*
G36*
G01X1326497Y1384297D02*
G03I-491J0D01*
G37*
G36*
G01X1322137D02*
G03I-491J0D01*
G37*
G36*
G01X1334377D02*
G03I-491J0D01*
G37*
G36*
G01X1326497Y1408495D02*
G03I-491J0D01*
G37*
G36*
G01X1334377D02*
G03I-491J0D01*
G37*
G36*
G01X1322137D02*
G03I-491J0D01*
G37*
G36*
G01X1320680Y1456451D02*
G03I-491J0D01*
G37*
G36*
G01Y1461182D02*
G03I-491J0D01*
G37*
G36*
G01Y1481267D02*
G03I-491J0D01*
G37*
G36*
G01Y1471805D02*
G03I-491J0D01*
G37*
G36*
G01Y1476536D02*
G03I-491J0D01*
G37*
G36*
G01Y1465913D02*
G03I-491J0D01*
G37*
G36*
G01Y1487160D02*
G03I-491J0D01*
G37*
G36*
G01Y1491891D02*
G03I-491J0D01*
G37*
G36*
G01Y1496622D02*
G03I-491J0D01*
G37*
G36*
G01Y1511976D02*
G03I-491J0D01*
G37*
G36*
G01Y1507245D02*
G03I-491J0D01*
G37*
G36*
G01Y1502514D02*
G03I-491J0D01*
G37*
G36*
G01Y1558813D02*
G03I-491J0D01*
G37*
G36*
G01Y1578898D02*
G03I-491J0D01*
G37*
G36*
G01Y1563544D02*
G03I-491J0D01*
G37*
G36*
G01X1329341Y1563144D02*
G03I-491J0D01*
G37*
G36*
G01X1320680Y1568275D02*
G03I-491J0D01*
G37*
G36*
G01X1329341Y1567875D02*
G03I-491J0D01*
G37*
G36*
G01X1320680Y1574167D02*
G03I-491J0D01*
G37*
G36*
G01X1329341Y1578498D02*
G03I-491J0D01*
G37*
G36*
G01Y1572606D02*
G03I-491J0D01*
G37*
G36*
G01Y1583229D02*
G03I-491J0D01*
G37*
G36*
G01X1320680Y1589522D02*
G03I-491J0D01*
G37*
G36*
G01Y1594253D02*
G03I-491J0D01*
G37*
G36*
G01X1329341Y1593853D02*
G03I-491J0D01*
G37*
G36*
G01Y1587960D02*
G03I-491J0D01*
G37*
G36*
G01X1320680Y1583629D02*
G03I-491J0D01*
G37*
G36*
G01Y1609607D02*
G03I-491J0D01*
G37*
G36*
G01Y1604876D02*
G03I-491J0D01*
G37*
G36*
G01Y1598984D02*
G03I-491J0D01*
G37*
G36*
G01X1329341Y1609207D02*
G03I-491J0D01*
G37*
G36*
G01Y1598584D02*
G03I-491J0D01*
G37*
G36*
G01Y1603315D02*
G03I-491J0D01*
G37*
G36*
G01X1320680Y1614338D02*
G03I-491J0D01*
G37*
G36*
G01X1329341Y1613938D02*
G03I-491J0D01*
G37*
G36*
G01Y1618669D02*
G03I-491J0D01*
G37*
G36*
G01X1355972Y854239D02*
X1356577D01*
G02X1356662Y854220I0J-200D01*
G01X1356774Y854168D01*
X1356801Y854137D01*
G03X1357537Y853700I1050J930D01*
G01X1357605Y853684D01*
X1357692Y853575D01*
Y852638D01*
G03X1357772Y852478I200J0D01*
G01X1358091Y852238D01*
G02X1358200Y852112I-242J-320D01*
G01X1358247Y852027D01*
G02X1358256Y851851I-175J-97D01*
G01X1358218Y851764D01*
X1358217Y851762D01*
G02X1358045Y851568I-370J154D01*
G01X1358044D01*
G03X1357448Y850747I584J-1050D01*
G01Y850139D01*
X1357382Y850039D01*
X1357325Y850016D01*
G03X1356497Y848769I525J-1247D01*
G03X1357016Y847704I1352J0D01*
G01X1357050Y847677D01*
X1357090Y847601D01*
X1357111Y847259D01*
G02X1357053Y847106I-200J-12D01*
G01X1356362Y846415D01*
G02X1356209Y846357I-141J142D01*
G01X1355867Y846378D01*
X1355791Y846418D01*
X1355764Y846452D01*
G03X1354699Y846971I-1065J-833D01*
G03X1353364Y845834I0J-1352D01*
G01X1353352Y845761D01*
X1353241Y845666D01*
X1353008D01*
X1352897Y845761D01*
X1352885Y845834D01*
G03X1350215I-1335J-215D01*
G01X1350203Y845761D01*
X1350092Y845666D01*
X1346710D01*
X1346599Y845761D01*
X1346587Y845834D01*
G03X1343917I-1335J-215D01*
G01X1343905Y845761D01*
X1343794Y845666D01*
X1343561D01*
X1343450Y845761D01*
X1343438Y845834D01*
G03X1340768I-1335J-215D01*
G01X1340756Y845761D01*
X1340645Y845666D01*
X1340411D01*
X1340300Y845761D01*
X1340288Y845834D01*
G03X1338953Y846971I-1335J-215D01*
G03X1338621Y846930I-2J-1352D01*
G01X1338569Y846917D01*
X1338469Y846944D01*
X1338220Y847193D01*
G02Y847475I142J141D01*
G01X1338264Y847519D01*
X1338381Y847542D01*
X1338438Y847519D01*
G03X1338953Y847417I515J1249D01*
G03Y850121I0J1352D01*
G03X1338448Y850023I0J-1352D01*
G01X1338401Y850004D01*
X1338303Y850015D01*
X1337986Y850228D01*
G02X1337898Y850394I112J166D01*
G01Y851491D01*
G02X1338029Y851679I200J0D01*
G01X1338030D01*
G03X1338626Y852149I-408J1130D01*
G02X1338635Y852162I169J-107D01*
G02X1338719Y852242I315J-247D01*
G01X1338746Y852261D01*
X1338790Y852298D01*
G03X1339220Y853219I-772J921D01*
G01Y853463D01*
G02X1339279Y853605I200J0D01*
G01X1339418Y853744D01*
X1339457Y853759D01*
G03X1340001Y854137I-505J1308D01*
G01X1340028Y854168D01*
X1340140Y854220D01*
G02X1340225Y854239I85J-181D01*
G01X1340830D01*
G02X1340915Y854220I0J-200D01*
G01X1341027Y854168D01*
X1341054Y854137D01*
G03X1342102Y853666I1048J931D01*
G01X1342104D01*
G03X1343152Y854137I0J1402D01*
G01X1343179Y854168D01*
X1343291Y854220D01*
G02X1343376Y854239I85J-181D01*
G01X1343979D01*
G02X1344064Y854220I0J-200D01*
G01X1344176Y854168D01*
X1344203Y854137D01*
G03X1345251Y853666I1048J931D01*
G01X1345253D01*
G03X1346301Y854137I0J1402D01*
G01X1346328Y854168D01*
X1346440Y854220D01*
G02X1346525Y854239I85J-181D01*
G01X1350277D01*
G02X1350362Y854220I0J-200D01*
G01X1350474Y854168D01*
X1350501Y854137D01*
G03X1351549Y853666I1048J931D01*
G01X1351551D01*
G03X1352599Y854137I0J1402D01*
G01X1352626Y854168D01*
X1352738Y854220D01*
G02X1352823Y854239I85J-181D01*
G01X1353426D01*
G02X1353511Y854220I0J-200D01*
G01X1353623Y854168D01*
X1353650Y854137D01*
G03X1354698Y853666I1048J931D01*
G01X1354700D01*
G03X1355748Y854137I0J1402D01*
G01X1355775Y854168D01*
X1355887Y854220D01*
G02X1355972Y854239I85J-181D01*
G37*
G36*
G01X1338575Y868222D02*
G02X1338811Y868236I128J-154D01*
G01X1339171Y868002D01*
G02X1339275Y867904I-219J-336D01*
G01X1339388Y867751D01*
G03X1339458Y867692I160J119D01*
G01X1339840Y867498D01*
G02X1339948Y867344I-90J-178D01*
G01Y867269D01*
X1340180Y866912D01*
X1340874D01*
X1341104Y867269D01*
Y867376D01*
X1341163Y867471D01*
X1341598Y867692D01*
G03X1341668Y867751I-90J178D01*
G01X1341781Y867903D01*
G02X1342425I322J-238D01*
G01X1342538Y867751D01*
G03X1342608Y867692I160J119D01*
G01X1342989Y867499D01*
G02X1343098Y867320I-91J-178D01*
G01Y867269D01*
X1343330Y866912D01*
X1343386D01*
G03X1343604Y866615I1066J554D01*
G01X1344032Y866188D01*
G03X1344880Y865836I850J849D01*
G01X1345621D01*
G03X1346469Y866188I-2J1201D01*
G01X1346684Y866402D01*
G02X1346966I141J-141D01*
G01X1347181Y866188D01*
G03X1348029Y865836I850J849D01*
G01X1348770D01*
G03X1349618Y866188I-2J1201D01*
G01X1349833Y866402D01*
G02X1350115I141J-141D01*
G01X1350330Y866188D01*
G03X1351178Y865836I850J849D01*
G01X1351919D01*
G03X1352767Y866188I-2J1201D01*
G01X1353195Y866614D01*
G03X1353413Y866912I-850J850D01*
G01X1353470D01*
X1353700Y867269D01*
Y867375D01*
X1353759Y867470D01*
X1354195Y867693D01*
G03X1354265Y867752I-90J178D01*
G01X1354377Y867903D01*
G02X1355021I322J-238D01*
G01X1355134Y867751D01*
G03X1355204Y867692I160J119D01*
G01X1355586Y867498D01*
G02X1355694Y867344I-90J-178D01*
G01Y867269D01*
X1355926Y866912D01*
X1356620D01*
X1356850Y867269D01*
Y867376D01*
X1356909Y867471D01*
X1357344Y867691D01*
G03X1357414Y867750I-90J178D01*
G01X1357527Y867903D01*
G02X1357623Y867996I323J-238D01*
G01X1357624D01*
X1357687Y868038D01*
G03X1357717Y868063I-112J165D01*
G01X1357768Y868114D01*
X1357921Y868122D01*
X1358100Y867978D01*
G02X1358163Y867914I-252J-311D01*
G01X1358170Y867905D01*
X1358237Y867824D01*
G03X1358262Y867798I156J125D01*
G01X1358422Y867662D01*
G03X1358463Y867635I130J152D01*
G01X1358643Y867546D01*
Y867545D01*
G03X1358722Y867509I537J1075D01*
G02X1358846Y867324I-76J-185D01*
G01Y867269D01*
X1359077Y866912D01*
X1359133D01*
G03X1359337Y866629I1066J554D01*
G01X1359684Y866282D01*
G02X1359742Y866140I-142J-141D01*
G01Y865991D01*
G02X1359712Y865886I-200J0D01*
G01X1359711Y865884D01*
G03X1359522Y865240I1012J-647D01*
G01Y863795D01*
G03X1359713Y863149I1201J4D01*
G01Y863147D01*
X1359728Y863124D01*
X1359744Y863070D01*
Y862891D01*
G02X1359686Y862749I-200J-1D01*
G01X1359355Y862418D01*
G03X1359136Y862120I847J-852D01*
G01X1359078D01*
X1358848Y861763D01*
Y861647D01*
X1358781Y861548D01*
X1358725Y861525D01*
G03X1358638Y861485I458J-1111D01*
G01X1358637Y861484D01*
X1358460Y861395D01*
G03X1358421Y861369I91J-178D01*
G01X1358262Y861234D01*
G03X1358237Y861208I131J-151D01*
G01X1358170Y861127D01*
X1358163Y861119D01*
G02X1358078Y861038I-316J246D01*
G02X1358076Y861037I-89J176D01*
G01X1357938Y860941D01*
G02X1357683Y860964I-114J164D01*
G01X1357382Y861265D01*
G03X1356979Y861530I-848J-851D01*
G02X1356854Y861692I73J186D01*
G01Y861763D01*
X1356622Y862120D01*
X1355928D01*
X1355698Y861763D01*
Y861646D01*
X1355631Y861547D01*
X1355576Y861524D01*
X1355574D01*
G03X1355493Y861487I458J-1111D01*
G01Y861486D01*
X1355313Y861397D01*
G03X1355272Y861370I89J-179D01*
G01X1355112Y861234D01*
G03X1355087Y861208I131J-151D01*
G01X1355020Y861127D01*
X1355014Y861119D01*
G02X1354384I-315J248D01*
G01X1354378Y861127D01*
X1354311Y861208D01*
G03X1354286Y861234I-156J-125D01*
G01X1354126Y861370D01*
G03X1354085Y861397I-130J-152D01*
G01X1353905Y861486D01*
Y861487D01*
G03X1353826Y861523I-537J-1075D01*
G01X1353770Y861546D01*
X1353704Y861645D01*
Y861763D01*
X1353473Y862120D01*
X1353472D01*
X1353439Y862171D01*
G03X1353412Y862204I-167J-109D01*
G01X1352819Y862795D01*
G03X1351971Y863148I-851J-848D01*
G01X1351133D01*
G03X1350339Y862847I1J-1202D01*
G01X1350306Y862818D01*
G03X1350298Y862810I137J-145D01*
G01X1350118Y862630D01*
G02X1349836I-141J142D01*
G01X1349670Y862795D01*
G03X1348822Y863148I-851J-848D01*
G01X1347982D01*
G03X1347188Y862847I1J-1202D01*
G01X1347131Y862796D01*
X1347130D01*
X1346967Y862632D01*
G02X1346684Y862631I-142J140D01*
G01X1346519Y862795D01*
G03X1345671Y863148I-851J-848D01*
G01X1344833D01*
G03X1344039Y862847I1J-1202D01*
G01X1343982Y862796D01*
X1343981D01*
X1343605Y862416D01*
X1343604D01*
G03X1343388Y862120I851J-848D01*
G01X1343330D01*
X1343100Y861763D01*
Y861646D01*
X1343033Y861547D01*
X1342977Y861524D01*
G03X1342892Y861485I458J-1111D01*
G01X1342891Y861484D01*
X1342714Y861395D01*
G03X1342675Y861369I91J-178D01*
G01X1342516Y861234D01*
G03X1342491Y861208I131J-151D01*
G01X1342424Y861127D01*
X1342418Y861119D01*
G02X1341788I-315J248D01*
G01X1341782Y861127D01*
X1341715Y861208D01*
G03X1341690Y861234I-156J-125D01*
G01X1341530Y861370D01*
G03X1341489Y861397I-130J-152D01*
G01X1341309Y861486D01*
Y861487D01*
G03X1341229Y861524I-544J-1071D01*
G01X1341173Y861547D01*
X1341106Y861646D01*
Y861763D01*
X1340875Y862120D01*
X1340181D01*
X1339950Y861763D01*
Y861646D01*
X1339884Y861547D01*
X1339828Y861524D01*
G03X1339747Y861487I458J-1111D01*
G01Y861486D01*
X1339567Y861397D01*
G03X1339526Y861370I89J-179D01*
G01X1339366Y861234D01*
G03X1339341Y861208I131J-151D01*
G01X1339274Y861127D01*
X1339267Y861118D01*
G02X1339191Y861044I-315J248D01*
G02X1339186Y861041I-105J170D01*
G01X1339123Y860997D01*
G03X1339097Y860975I116J-163D01*
G01X1339028Y860907D01*
G03X1338700Y860294I850J-849D01*
G01Y860340D01*
X1338341Y860698D01*
G02X1338285Y860875I141J142D01*
G03X1338304Y861086I-1182J213D01*
G01Y861916D01*
G02X1338362Y862056I200J-1D01*
G01X1338424Y862119D01*
X1338455Y862134D01*
G03X1339134Y863216I-523J1082D01*
G01Y866431D01*
G03X1338698Y867356I-1201J-1D01*
G02X1338552Y867665I255J309D01*
G01Y867867D01*
G03X1338537Y867944I-200J1D01*
G01X1338517Y867992D01*
G02X1338574Y868222I185J76D01*
G01X1338575D01*
G37*
G36*
G01X1351134Y862146D02*
X1351970D01*
G02X1352048Y862130I0J-200D01*
G02X1352103Y862094I-80J-183D01*
G01X1352164Y862034D01*
X1352404Y861795D01*
Y861794D01*
X1352438Y861761D01*
G02X1352497Y861619I-141J-142D01*
G01Y860927D01*
G03X1352556Y860785I200J0D01*
G01X1352717Y860624D01*
G03X1352859Y860565I142J141D01*
G01X1353462D01*
G02X1353550Y860545I1J-200D01*
G01X1353551Y860544D01*
X1353583Y860517D01*
X1353593Y860505D01*
G03X1354645Y859966I1106J862D01*
G03X1355801Y860499I55J1401D01*
G01X1355813Y860514D01*
X1355815Y860517D01*
X1355847Y860544D01*
X1355851Y860546D01*
X1355927Y860583D01*
X1355930Y860586D01*
X1355939Y860590D01*
X1355974Y860605D01*
G02X1356034Y860614I59J-191D01*
G01X1356534D01*
G02X1356675Y860556I0J-200D01*
G01X1356975Y860256D01*
G03X1356992Y860239I858J841D01*
G01X1357010Y860221D01*
G02X1357046Y860171I-142J-140D01*
G02X1357068Y860080I-178J-91D01*
G01Y859484D01*
G02X1357052Y859407I-200J1D01*
G01X1356990Y859326D01*
G03X1356681Y858994I858J-1109D01*
G03X1356493Y858573I1169J-774D01*
G01X1356490Y858559D01*
X1356486Y858546D01*
X1356473Y858524D01*
G02X1356441Y858482I-174J99D01*
G01X1355981Y858022D01*
G02X1355931Y857986I-140J142D01*
G02X1355840Y857964I-91J178D01*
G01X1355811D01*
G03X1355733Y857948I0J-200D01*
G01X1355697Y857933D01*
X1355568Y857804D01*
X1355225Y857462D01*
G02X1355160Y857419I-141J142D01*
G02X1355084Y857404I-76J185D01*
G01X1354317D01*
G02X1354176Y857463I1J200D01*
G01X1353834Y857804D01*
X1353732Y857906D01*
G03X1353669Y857948I-140J-142D01*
G01X1353632Y857964D01*
X1352662D01*
G03X1352584Y857948I0J-200D01*
G01X1352548Y857933D01*
X1352419Y857804D01*
X1352076Y857462D01*
G02X1352011Y857419I-141J142D01*
G02X1351935Y857404I-76J185D01*
G01X1351168D01*
G02X1351027Y857463I1J200D01*
G01X1350685Y857804D01*
X1350583Y857906D01*
G03X1350520Y857948I-140J-142D01*
G01X1350483Y857964D01*
X1346363D01*
G03X1346285Y857948I0J-200D01*
G01X1346249Y857933D01*
X1346120Y857804D01*
X1346052Y857737D01*
G02X1345912Y857679I-141J142D01*
G01X1344594D01*
G02X1344452Y857738I0J200D01*
G01X1344284Y857906D01*
G03X1344221Y857948I-140J-142D01*
G01X1344184Y857964D01*
X1343214D01*
G03X1343136Y857948I0J-200D01*
G01X1343100Y857933D01*
X1342944Y857777D01*
G02X1342802Y857718I-142J141D01*
G01X1341405D01*
G02X1341263Y857777I0J200D01*
G01X1341134Y857906D01*
G03X1341071Y857948I-140J-142D01*
G01X1341034Y857964D01*
X1340748D01*
G02X1340620Y858011I1J200D01*
G01X1340410Y858203D01*
G02X1340351Y858328I140J143D01*
G01Y858335D01*
X1340345Y858381D01*
G03X1340277Y858677I-1392J-164D01*
G03X1339753Y859370I-1325J-457D01*
G01X1339677Y859526D01*
Y860056D01*
G02X1339678Y860077I200J1D01*
G01X1339684Y860105D01*
G02X1339711Y860167I194J-48D01*
G02X1339735Y860197I167J-109D01*
G01X1339752Y860214D01*
X1339765Y860223D01*
G03X1340054Y860498I-812J1143D01*
G01X1340055Y860500D01*
X1340066Y860513D01*
X1340069Y860517D01*
X1340101Y860544D01*
X1340108Y860547D01*
X1340181Y860583D01*
X1340183Y860585D01*
X1340197Y860592D01*
G02X1340207Y860597I94J-176D01*
G02X1340210Y860598I65J-189D01*
G01X1340216Y860600D01*
G02X1340288Y860614I73J-186D01*
G01X1340768D01*
G02X1340840Y860600I-1J-200D01*
G01X1340955Y860544D01*
X1340987Y860517D01*
X1340989Y860514D01*
X1341001Y860499D01*
G03X1342415Y860000I1101J868D01*
G03X1343209Y860505I-312J1367D01*
G01X1343219Y860517D01*
X1343251Y860544D01*
X1343346Y860592D01*
G02X1343354Y860596I93J-177D01*
G02X1343359Y860598I77J-185D01*
G01X1343368Y860602D01*
G02X1343417Y860614I72J-187D01*
G01X1344025D01*
X1344069Y860682D01*
X1344079Y860698D01*
X1344082Y860703D01*
G03X1344084Y860706I-165J112D01*
G01X1344225Y860927D01*
G03X1344230Y860935I-167J110D01*
G01X1344233Y860940D01*
X1344256Y860976D01*
Y861569D01*
G02X1344303Y861697I200J-1D01*
G01X1344347Y861742D01*
X1344351Y861746D01*
X1344704Y862098D01*
G02X1344721Y862111I130J-152D01*
G02X1344834Y862146I113J-165D01*
G01X1345670D01*
G02X1345753Y862128I0J-200D01*
G02X1345802Y862095I-86J-181D01*
G01X1346104Y861795D01*
Y861794D01*
X1346197Y861702D01*
G02X1346248Y861594I-147J-136D01*
G01Y860976D01*
X1346250Y860974D01*
Y860923D01*
G03X1346309Y860781I200J0D01*
G01X1346426Y860664D01*
Y860663D01*
X1346454Y860635D01*
Y860625D01*
X1346477Y860602D01*
X1346524D01*
X1346528Y860606D01*
X1347096D01*
G03X1347150Y860614I-2J200D01*
G01X1347174D01*
X1347181Y860625D01*
G03X1347238Y860665I-85J181D01*
G01X1347360Y860787D01*
G03X1347419Y860929I-141J142D01*
G01Y861643D01*
G02X1347455Y861701I185J-75D01*
G01X1347548Y861795D01*
X1347549D01*
X1347853Y862098D01*
G02X1347870Y862111I130J-152D01*
G02X1347983Y862146I113J-165D01*
G01X1348821D01*
G02X1348904Y862128I0J-200D01*
G02X1348953Y862095I-86J-181D01*
G01X1349255Y861795D01*
Y861794D01*
X1349288Y861762D01*
G02X1349347Y861620I-141J-142D01*
G01Y860912D01*
G03X1349406Y860770I200J0D01*
G01X1349532Y860644D01*
G03X1349674Y860585I142J141D01*
G01X1350270D01*
G03X1350412Y860644I0J200D01*
G01X1350540Y860772D01*
G03X1350599Y860914I-141J142D01*
G01Y861611D01*
G02X1350658Y861753I200J0D01*
G01X1351004Y862098D01*
G02X1351021Y862111I130J-152D01*
G02X1351134Y862146I113J-165D01*
G37*
G36*
G01X1344981Y871743D02*
X1345519D01*
G02X1345660Y871684I-1J-200D01*
G01X1346218Y871127D01*
G03X1346359Y871068I142J141D01*
G01X1347290D01*
G03X1347431Y871127I-1J200D01*
G01X1347738Y871433D01*
G02X1347879Y871492I142J-141D01*
G01X1348919D01*
G02X1349060Y871433I-1J-200D01*
G01X1349367Y871127D01*
G03X1349508Y871068I142J141D01*
G01X1350439D01*
G03X1350580Y871127I-1J200D01*
G01X1351098Y871644D01*
G02X1351239Y871703I142J-141D01*
G01X1351857D01*
G02X1351998Y871644I-1J-200D01*
G01X1352516Y871127D01*
G03X1352657Y871068I142J141D01*
G01X1353588D01*
G03X1353729Y871127I-1J200D01*
G01X1354282Y871679D01*
G02X1354423Y871738I142J-141D01*
G01X1354972D01*
G02X1355113Y871679I-1J-200D01*
G01X1355666Y871127D01*
G03X1355807Y871068I142J141D01*
G01X1356054D01*
G02X1356188Y871016I0J-200D01*
G01X1356416Y870806D01*
X1356448Y870739D01*
X1356452Y870701D01*
G03X1357102Y869627I1398J112D01*
G01Y868865D01*
X1357062Y868825D01*
G03X1356722Y868499I787J-1161D01*
G01X1356562Y868418D01*
X1355986D01*
X1355826Y868499D01*
G03X1353572I-1127J-834D01*
G01X1353413Y868418D01*
X1352775D01*
X1352544Y868056D01*
Y867440D01*
G02X1352487Y867323I-199J24D01*
G01X1352059Y866896D01*
G02X1351918Y866837I-142J141D01*
G01X1351179D01*
G02X1351038Y866896I1J200D01*
G01X1350609Y867324D01*
G02X1350596Y867338I140J143D01*
G01Y868179D01*
X1350313Y868462D01*
X1349543D01*
X1349300Y868219D01*
Y867285D01*
X1348910Y866896D01*
G02X1348769Y866837I-142J141D01*
G01X1348030D01*
G02X1347889Y866896I1J200D01*
G01X1347460Y867324D01*
G02X1347451Y867334I144J139D01*
G01Y868196D01*
X1347228Y868419D01*
X1347061D01*
X1346318D01*
X1346146Y868247D01*
Y867280D01*
X1345761Y866896D01*
G02X1345620Y866837I-142J141D01*
G01X1344881D01*
G02X1344740Y866896I1J200D01*
G01X1344311Y867324D01*
G02X1344252Y867466I141J142D01*
G01Y867998D01*
Y868208D01*
X1344003Y868457D01*
X1343313D01*
X1343230Y868499D01*
G03X1340976I-1127J-834D01*
G01X1340816Y868418D01*
X1340240D01*
X1340080Y868499D01*
G03X1339717Y868841I-1128J-833D01*
G01Y869638D01*
G03X1340350Y870701I-762J1174D01*
G01X1340354Y870739D01*
X1340386Y870806D01*
X1340614Y871016D01*
G02X1340748Y871068I134J-148D01*
G01X1340992D01*
G03X1341133Y871127I-1J200D01*
G01X1341642Y871635D01*
G02X1341783Y871694I142J-141D01*
G01X1342419D01*
G02X1342560Y871635I-1J-200D01*
G01X1343069Y871127D01*
G03X1343210Y871068I142J141D01*
G01X1344141D01*
G03X1344282Y871127I-1J200D01*
G01X1344840Y871684D01*
G02X1344981Y871743I142J-141D01*
G37*
G36*
G01X1346296Y885614D02*
X1350506D01*
X1350640Y885562D01*
G03X1351550Y885210I910J1000D01*
G03X1351997Y885286I0J1353D01*
G01X1352051Y885305D01*
X1352164Y885279D01*
X1353416Y884027D01*
X1353442Y883914D01*
X1353423Y883860D01*
G03X1353347Y883413I1277J-447D01*
G03X1354699Y882061I1352J0D01*
G03X1355146Y882137I0J1353D01*
G01X1355200Y882156D01*
X1355313Y882130D01*
X1356440Y881003D01*
G02X1356499Y880861I-141J-142D01*
G01Y880332D01*
G03X1356497Y880263I1350J-74D01*
G03X1356499Y880194I1352J5D01*
G01Y879756D01*
X1356552Y879664D01*
X1356569Y879654D01*
X1356605Y879616D01*
X1356619Y879591D01*
G03X1356945Y879191I1231J671D01*
G01X1357016Y879038D01*
Y878448D01*
G03X1357075Y878306I200J0D01*
G01X1357269Y878112D01*
G03X1357411Y878053I142J141D01*
G01X1358108D01*
G02X1358251Y877993I0J-200D01*
G01X1358265Y877979D01*
X1358294Y877939D01*
G03X1358315Y877914I163J116D01*
G01X1358529Y877700D01*
G02X1358588Y877558I-141J-142D01*
G01Y877114D01*
G02X1358529Y876972I-200J0D01*
G01X1357570Y876013D01*
G03X1357511Y875871I141J-142D01*
G01Y875662D01*
G02X1357452Y875520I-200J0D01*
G01X1357045Y875113D01*
X1357032Y875104D01*
G03X1356749Y874833I819J-1138D01*
G01X1356735Y874816D01*
X1356702Y874788D01*
X1356606Y874740D01*
G02X1356515Y874718I-91J178D01*
G01X1356033D01*
G02X1355944Y874739I0J200D01*
G01X1355847Y874787D01*
X1355814Y874815D01*
X1355800Y874832D01*
G03X1353598I-1101J-868D01*
G01X1353584Y874815D01*
X1353551Y874787D01*
X1353454Y874739D01*
G02X1353365Y874718I-89J179D01*
G01X1352884D01*
G02X1352795Y874739I0J200D01*
G01X1352698Y874787D01*
X1352665Y874815D01*
X1352651Y874832D01*
G03X1350449I-1101J-868D01*
G01X1350435Y874815D01*
X1350402Y874787D01*
X1350306Y874739D01*
G02X1350231Y874718I-90J179D01*
G01X1349626D01*
X1349572Y874633D01*
G03X1349567Y874626I160J-120D01*
G01X1349551Y874601D01*
X1347356D01*
G02X1347190Y874690I0J200D01*
G01X1347172Y874716D01*
X1347171Y874718D01*
X1346586D01*
G02X1346497Y874739I0J200D01*
G01X1346400Y874787D01*
X1346367Y874815D01*
X1346353Y874832D01*
G03X1344151I-1101J-868D01*
G01X1344137Y874815D01*
X1344104Y874787D01*
X1344007Y874739D01*
G02X1343918Y874718I-89J179D01*
G01X1343437D01*
G02X1343348Y874739I0J200D01*
G01X1343251Y874787D01*
X1343218Y874815D01*
X1343204Y874832D01*
G03X1341002I-1101J-868D01*
G01X1340988Y874815D01*
X1340955Y874787D01*
X1340858Y874739D01*
G02X1340769Y874718I-89J179D01*
G01X1340287D01*
G02X1340196Y874740I0J200D01*
G01X1340100Y874788D01*
X1340067Y874816D01*
X1340053Y874833D01*
G03X1339586Y875215I-1100J-869D01*
G01X1339557Y875230D01*
X1338324Y876463D01*
X1338309Y876497D01*
X1338264Y876598D01*
X1338261Y876606D01*
X1338260Y876608D01*
G03X1338157Y876829I-1135J-394D01*
G01X1338144Y876851D01*
X1338121Y876929D01*
G02X1338113Y876985I192J56D01*
G01Y877472D01*
G02X1338171Y877613I200J0D01*
G01X1338552Y877995D01*
G02X1338694Y878054I142J-141D01*
G01X1339408D01*
G03X1339550Y878113I0J200D01*
G01X1339674Y878237D01*
X1339704Y878310D01*
Y878974D01*
G02X1339786Y879135I200J-1D01*
G03X1340183Y879591I-834J1127D01*
G01Y879592D01*
G02X1340358Y879695I175J-97D01*
G01X1340553D01*
G03X1340753Y879895I0J200D01*
G01Y880865D01*
G02X1340812Y881007I200J0D01*
G01X1341846Y882041D01*
X1341930Y882071D01*
X1341975Y882067D01*
G03X1342101Y882061I127J1346D01*
G01X1342103D01*
G03X1343455Y883413I0J1352D01*
G01Y883415D01*
G03X1343449Y883541I-1352J-1D01*
G01X1343445Y883586D01*
X1343475Y883670D01*
X1343573Y883768D01*
G02X1343856I142J-141D01*
G01X1343890Y883735D01*
X1343919Y883647D01*
X1343913Y883599D01*
G03X1343900Y883413I1339J-187D01*
G03X1345252Y884765I1352J0D01*
G03X1345066Y884752I1J-1352D01*
G01X1345018Y884746D01*
X1344930Y884775D01*
X1344897Y884809D01*
G02Y885092I141J141D01*
G01X1344995Y885190D01*
X1345079Y885220D01*
X1345124Y885216D01*
G03X1345250Y885210I127J1346D01*
G01X1345252D01*
G03X1346162Y885562I0J1352D01*
G01X1346296Y885614D01*
G37*
G36*
G01X1342322Y947407D02*
G03I-502J0D01*
G37*
G36*
G01X1338737Y1348187D02*
G03I-491J0D01*
G37*
G36*
G01X1350977D02*
G03I-491J0D01*
G37*
G36*
G01X1346617D02*
G03I-491J0D01*
G37*
G36*
G01X1338737Y1360099D02*
G03I-491J0D01*
G37*
G36*
G01X1350977D02*
G03I-491J0D01*
G37*
G36*
G01X1346617D02*
G03I-491J0D01*
G37*
G36*
G01X1338737Y1372385D02*
G03I-491J0D01*
G37*
G36*
G01X1350977D02*
G03I-491J0D01*
G37*
G36*
G01X1346617D02*
G03I-491J0D01*
G37*
G36*
G01X1338737Y1396583D02*
G03I-491J0D01*
G37*
G36*
G01X1346617D02*
G03I-491J0D01*
G37*
G36*
G01X1350977D02*
G03I-491J0D01*
G37*
G36*
G01X1338737Y1384297D02*
G03I-491J0D01*
G37*
G36*
G01X1350977D02*
G03I-491J0D01*
G37*
G36*
G01X1346617D02*
G03I-491J0D01*
G37*
G36*
G01X1350977Y1408495D02*
G03I-491J0D01*
G37*
G36*
G01X1338737D02*
G03I-491J0D01*
G37*
G36*
G01X1346617D02*
G03I-491J0D01*
G37*
G36*
G01X1338003Y1558813D02*
G03I-491J0D01*
G37*
G36*
G01Y1578898D02*
G03I-491J0D01*
G37*
G36*
G01Y1574167D02*
G03I-491J0D01*
G37*
G36*
G01X1346664Y1578498D02*
G03I-491J0D01*
G37*
G36*
G01Y1572606D02*
G03I-491J0D01*
G37*
G36*
G01X1338003Y1563544D02*
G03I-491J0D01*
G37*
G36*
G01X1346664Y1563144D02*
G03I-491J0D01*
G37*
G36*
G01X1338003Y1568275D02*
G03I-491J0D01*
G37*
G36*
G01X1346664Y1567875D02*
G03I-491J0D01*
G37*
G36*
G01X1338003Y1583629D02*
G03I-491J0D01*
G37*
G36*
G01X1346664Y1583229D02*
G03I-491J0D01*
G37*
G36*
G01X1338003Y1589522D02*
G03I-491J0D01*
G37*
G36*
G01Y1594253D02*
G03I-491J0D01*
G37*
G36*
G01X1346664Y1593853D02*
G03I-491J0D01*
G37*
G36*
G01Y1587960D02*
G03I-491J0D01*
G37*
G36*
G01Y1598584D02*
G03I-491J0D01*
G37*
G36*
G01Y1603315D02*
G03I-491J0D01*
G37*
G36*
G01X1338003Y1609607D02*
G03I-491J0D01*
G37*
G36*
G01Y1604876D02*
G03I-491J0D01*
G37*
G36*
G01Y1598984D02*
G03I-491J0D01*
G37*
G36*
G01X1346664Y1609207D02*
G03I-491J0D01*
G37*
G36*
G01X1338003Y1614338D02*
G03I-491J0D01*
G37*
G36*
G01X1346664Y1613938D02*
G03I-491J0D01*
G37*
G36*
G01Y1618669D02*
G03I-491J0D01*
G37*
G36*
G01X1374704Y841694D02*
G03X1374949Y842470I-1106J776D01*
G03X1372245I-1352J0D01*
G01Y842469D01*
G03X1372490Y841693I1352J0D01*
G01X1372515Y841659D01*
X1372531Y841578D01*
X1372469Y841288D01*
X1372423Y841223D01*
X1372389Y841201D01*
G03X1372017Y840900I1213J-1879D01*
G01X1371603Y840486D01*
G02X1371321I-141J142D01*
G01X1371064Y840743D01*
G02X1371007Y840907I142J141D01*
G01X1371041Y841203D01*
X1371092Y841281D01*
X1371133Y841305D01*
G03X1371799Y842470I-686J1165D01*
G03X1370447Y843822I-1352J0D01*
G03X1369282Y843156I0J-1352D01*
G01X1369258Y843115D01*
X1369180Y843064D01*
X1368884Y843030D01*
G02X1368720Y843087I-23J199D01*
G01X1367915Y843892D01*
G02X1367858Y844056I142J141D01*
G01X1367892Y844352D01*
X1367943Y844430D01*
X1367984Y844454D01*
G03X1368650Y845619I-686J1165D01*
G03X1367298Y846971I-1352J0D01*
G03X1366133Y846305I0J-1352D01*
G01X1366109Y846264D01*
X1366031Y846213D01*
X1365735Y846179D01*
G02X1365571Y846236I-23J199D01*
G01X1364666Y847141D01*
X1364637Y847169D01*
X1364607Y847243D01*
Y847423D01*
X1364669Y847520D01*
X1364722Y847545D01*
G03X1365500Y848769I-574J1224D01*
G03X1362796I-1352J0D01*
G01Y848768D01*
G03X1363154Y847852I1352J1D01*
G01X1363196Y847807D01*
X1363215Y847690D01*
X1363063Y847351D01*
G02X1362881Y847233I-182J82D01*
G01X1361845D01*
G02X1361703Y847292I0J200D01*
G01X1361682Y847313D01*
G02Y847596I142J142D01*
G01X1361698Y847612D01*
X1361717Y847624D01*
G03X1362351Y848769I-717J1145D01*
G03X1360999Y850121I-1352J0D01*
G03X1359939Y849609I0J-1353D01*
G01X1359912Y849574D01*
X1359836Y849535D01*
X1359564Y849523D01*
G02X1359414Y849581I-9J200D01*
G01X1359134Y849861D01*
X1359105Y849889D01*
X1359075Y849963D01*
Y851213D01*
X1359086Y851258D01*
X1359097Y851279D01*
G03X1359123Y851335I-1258J618D01*
G01X1359125Y851338D01*
X1359126Y851341D01*
X1359176Y851456D01*
G03X1359261Y851757I-1104J474D01*
G01X1359285Y851827D01*
X1359286Y852024D01*
X1359262Y852094D01*
G03X1359123Y852512I-1190J-164D01*
G01X1359118Y852521D01*
X1359078Y852595D01*
G03X1358794Y852955I-1229J-677D01*
G01X1358764Y852982D01*
X1358712Y853094D01*
G02X1358694Y853178I182J83D01*
G01Y853810D01*
G02X1358751Y853950I200J0D01*
G01X1359056Y854255D01*
G02X1359184Y854314I142J-141D01*
G01X1359773D01*
X1359804Y854362D01*
X1359817Y854382D01*
X1359827Y854398D01*
X1359830Y854402D01*
X1359832Y854406D01*
X1359973Y854627D01*
Y854628D01*
G03X1359978Y854635I-160J119D01*
G01X1359981Y854640D01*
X1360004Y854676D01*
Y855268D01*
G02X1360062Y855409I200J0D01*
G01X1360688Y856036D01*
X1360716Y856064D01*
X1360731Y856100D01*
G03X1360746Y856176I-185J76D01*
G01Y857109D01*
G03X1360688Y857250I-200J0D01*
G01X1360033Y857905D01*
G03X1359891Y857964I-142J-141D01*
G01X1359645D01*
G02X1359510Y858017I1J200D01*
G01X1359310Y858200D01*
G02X1359265Y858262I136J146D01*
G01X1359249Y858295D01*
X1359246Y858331D01*
G03X1358683Y859346I-1398J-112D01*
G01X1358664Y859359D01*
X1358635Y859393D01*
X1358584Y859491D01*
G02X1358561Y859584I177J93D01*
G01Y860001D01*
G02X1358583Y860091I200J-1D01*
G01Y860093D01*
X1358617Y860156D01*
G02X1358644Y860196I178J-91D01*
G01X1358659Y860213D01*
X1358677Y860226D01*
G03X1358713Y860253I-828J1141D01*
G01X1358762Y860292D01*
G03X1358786Y860313I-916J1071D01*
G02X1358788Y860315I142J-140D01*
G03X1358819Y860343I-929J1060D01*
G01X1358820Y860344D01*
G02X1358822Y860346I142J-140D01*
G03X1358856Y860380I-980J1014D01*
G03X1358936Y860469I-1008J986D01*
G01X1358937Y860471D01*
X1358958Y860496D01*
G02X1359023Y860548I155J-127D01*
G01X1359110Y860591D01*
G02X1359127Y860599I93J-177D01*
G01X1359163Y860613D01*
X1359300Y860614D01*
X1359773D01*
X1359804Y860662D01*
X1359817Y860682D01*
X1359827Y860698D01*
X1359830Y860702D01*
X1359832Y860706D01*
X1359973Y860927D01*
Y860928D01*
G03X1359978Y860935I-160J119D01*
G01X1359981Y860940D01*
X1360004Y860976D01*
Y861552D01*
G02X1360027Y861645I200J0D01*
G01X1360045Y861680D01*
X1360401Y862036D01*
G03X1360486Y862131I-858J853D01*
G01X1360489Y862135D01*
X1360504Y862152D01*
X1360687Y862335D01*
G03X1360746Y862477I-141J142D01*
G01Y862755D01*
X1360747Y862766D01*
G03X1360754Y862893I-1203J130D01*
G01Y863216D01*
X1360746Y863242D01*
Y863408D01*
G03X1360687Y863550I-200J0D01*
G01X1360596Y863641D01*
X1360563Y863694D01*
G02X1360532Y863800I169J107D01*
G01Y865235D01*
G02X1360563Y865342I200J0D01*
G01X1360576Y865362D01*
X1360590Y865385D01*
X1360667Y865465D01*
X1360685Y865483D01*
G03X1360744Y865625I-141J142D01*
G01Y865857D01*
X1360746Y865871D01*
G03X1360747Y865879I-1200J154D01*
G01Y865885D01*
X1360748Y865893D01*
G03X1360750Y865922I-1206J98D01*
G01Y865924D01*
G03X1360752Y865991I-1208J70D01*
G01Y866138D01*
G03X1360745Y866265I-1210J-3D01*
G01X1360744Y866276D01*
Y866555D01*
G03X1360685Y866697I-200J0D01*
G01X1360494Y866888D01*
X1360487Y866896D01*
G03X1360399Y866995I-947J-753D01*
G01X1360118Y867276D01*
G02X1360059Y867418I141J142D01*
G01Y868155D01*
G03X1360000Y868297I-200J0D01*
G01X1359897Y868400D01*
G03X1359755Y868459I-142J-141D01*
G01X1359121D01*
G02X1359032Y868480I0J200D01*
G01X1359002Y868495D01*
X1358969Y868522D01*
X1358954Y868540D01*
G03X1358896Y868609I-1108J-872D01*
G01Y868611D01*
G03X1358866Y868643I-1044J-948D01*
G01X1358865Y868644D01*
G02X1358863Y868646I140J142D01*
G03X1358754Y868748I-1017J-978D01*
G01X1358737Y868762D01*
X1358712Y868794D01*
X1358674Y868872D01*
G02X1358654Y868959I180J87D01*
G01Y869520D01*
G02X1358674Y869606I200J-1D01*
G01X1358728Y869721D01*
X1358760Y869748D01*
G03X1359246Y870700I-911J1065D01*
G01X1359249Y870738D01*
X1359282Y870805D01*
X1359509Y871015D01*
G02X1359593Y871061I135J-147D01*
G01X1359619Y871068D01*
X1359888D01*
G03X1360030Y871127I0J200D01*
G01X1360685Y871782D01*
G03X1360744Y871924I-141J142D01*
G01Y872854D01*
G03X1360685Y872996I-200J0D01*
G01X1360053Y873628D01*
G02X1360000Y873765I147J136D01*
G01Y874296D01*
X1360016Y874312D01*
Y874462D01*
G03X1359957Y874604I-200J0D01*
G01X1359881Y874680D01*
G03X1359739Y874739I-142J-141D01*
G01X1359133D01*
G02X1359031Y874767I0J200D01*
G01X1358979Y874797D01*
X1358956Y874827D01*
G03X1358605Y875146I-1105J-863D01*
G02X1358512Y875315I107J169D01*
G01Y875456D01*
G02X1358571Y875598I200J0D01*
G01X1358662Y875689D01*
X1358663D01*
X1359415Y876441D01*
G02X1359557Y876500I142J-141D01*
G01X1359567D01*
G02X1359667Y876474I1J-200D01*
G01X1359746Y876428D01*
G02X1359815Y876362I-100J-173D01*
G01X1359816Y876361D01*
G03X1360883Y875717I1182J753D01*
G01X1360921Y875714D01*
X1360988Y875681D01*
X1361073Y875589D01*
G02X1361075Y875587I-140J-142D01*
G01X1361136Y875520D01*
G02X1361188Y875386I-148J-135D01*
G01Y875049D01*
G03X1361247Y874907I200J0D01*
G01X1361878Y874276D01*
G02X1361937Y874134I-141J-142D01*
G01Y873471D01*
G03X1361996Y873329I200J0D01*
G01X1362087Y873238D01*
G03X1362229Y873179I142J141D01*
G01X1362949D01*
X1363103Y873106D01*
G03X1364148Y872612I1045J858D01*
G03X1365500Y873964I0J1352D01*
G03X1364162Y875316I-1352J0D01*
G01X1364122D01*
X1364050Y875346D01*
X1364022Y875374D01*
G02Y875657I142J141D01*
G01X1364097Y875732D01*
X1364165Y875762D01*
X1364203Y875763D01*
G03X1365499Y877059I-55J1351D01*
G01X1365500Y877097D01*
X1365530Y877165D01*
X1365605Y877240D01*
G02X1365888I142J-142D01*
G01X1365916Y877212D01*
X1365946Y877140D01*
Y877100D01*
G03X1367298Y875762I1352J14D01*
G03X1368650Y877114I0J1352D01*
G03X1367312Y878466I-1352J0D01*
G01X1367272D01*
X1367200Y878496D01*
X1367172Y878524D01*
G02Y878807I142J142D01*
G01X1367246Y878881D01*
X1367314Y878911D01*
X1367352Y878912D01*
G03X1368649Y880209I-54J1351D01*
G01X1368650Y880247D01*
X1368680Y880315D01*
X1368754Y880389D01*
G02X1369037I141J-142D01*
G01X1369065Y880361D01*
X1369095Y880289D01*
Y880249D01*
G03X1370447Y878911I1352J14D01*
G03X1371799Y880263I0J1352D01*
G03X1370461Y881615I-1352J0D01*
G01X1370421D01*
X1370349Y881645D01*
X1370321Y881673D01*
G02Y881956I142J142D01*
G01X1370396Y882031D01*
X1370464Y882061D01*
X1370502Y882062D01*
G03X1371798Y883358I-55J1351D01*
G01X1371799Y883396D01*
X1371829Y883464D01*
X1371904Y883539D01*
G02X1372187I141J-142D01*
G01X1372215Y883511D01*
X1372245Y883439D01*
Y883399D01*
G03X1373597Y882061I1352J14D01*
G03X1374949Y883413I0J1352D01*
G03X1373611Y884765I-1352J0D01*
G01X1373571D01*
X1373499Y884795D01*
X1373471Y884823D01*
G02Y885106I142J142D01*
G01X1373545Y885180D01*
X1373613Y885210D01*
X1373651Y885211D01*
G03X1374948Y886508I-54J1351D01*
G01X1374949Y886546D01*
X1374979Y886614D01*
X1375054Y886689D01*
G02X1375337I141J-142D01*
G01X1375365Y886661D01*
X1375395Y886589D01*
Y886549D01*
G03X1376747Y885210I1352J13D01*
G03X1378099Y886562I0J1352D01*
G01Y886563D01*
G03X1377865Y887323I-1352J0D01*
G01X1377833Y887369D01*
X1377827Y887480D01*
X1377994Y887790D01*
G02X1377999Y887798I172J-102D01*
G02X1378167Y887895I171J-103D01*
G01X1378476D01*
G02X1378644Y887798I-3J-200D01*
G02X1378649Y887790I-167J-110D01*
G01X1378816Y887480D01*
X1378810Y887369D01*
X1378778Y887323D01*
G03X1378544Y886563I1118J-760D01*
G01Y886562D01*
G03X1379058Y885501I1352J0D01*
G02X1379134Y885345I-124J-157D01*
G01Y884630D01*
G02X1379058Y884474I-200J1D01*
G03X1378544Y883413I838J-1061D01*
G03X1379896Y882061I1352J0D01*
G03X1381222Y883150I0J1352D01*
G01X1381228Y883179D01*
X1381256Y883231D01*
X1381367Y883343D01*
G02X1381650I141J-142D01*
G01X1381673Y883319D01*
X1381702Y883261D01*
X1381707Y883228D01*
G03X1382834Y882078I1339J185D01*
G01X1382907Y882066D01*
X1383003Y881954D01*
Y881722D01*
X1382907Y881610D01*
X1382834Y881598D01*
G03Y878928I212J-1335D01*
G01X1382907Y878916D01*
X1383003Y878804D01*
Y878573D01*
X1382907Y878461D01*
X1382834Y878449D01*
G03Y875779I212J-1335D01*
G01X1382907Y875767D01*
X1383003Y875655D01*
Y875423D01*
X1382907Y875311D01*
X1382834Y875299D01*
G03Y872629I212J-1335D01*
G01X1382907Y872617D01*
X1383003Y872505D01*
Y872273D01*
X1382907Y872161D01*
X1382834Y872149D01*
G03X1381694Y870814I212J-1335D01*
G03X1382836Y869478I1352J0D01*
G01X1382868Y869473D01*
X1382924Y869445D01*
X1384148Y868221D01*
G03X1384290Y868162I142J141D01*
G01X1391010D01*
G02X1391150Y868105I0J-200D01*
G01X1391591Y867664D01*
G02X1391593Y867662I-140J-142D01*
G02X1391650Y867522I-143J-140D01*
G01Y866986D01*
X1391620Y866966D01*
Y866273D01*
X1391650Y866253D01*
Y863180D01*
X1391642Y863175D01*
Y862482D01*
X1391650Y862477D01*
Y862000D01*
G03X1391709Y861858I200J0D01*
G01X1392661Y860906D01*
G02X1392663Y860904I-140J-142D01*
G02X1392720Y860764I-143J-140D01*
G01Y850927D01*
G03X1392759Y850809I200J1D01*
G01X1392778Y850783D01*
X1392797Y850723D01*
Y842981D01*
G02X1392738Y842839I-200J0D01*
G01X1389614Y839715D01*
X1389586Y839686D01*
X1389512Y839656D01*
X1384439D01*
X1384337Y839727D01*
X1384315Y839787D01*
G03X1381777I-1269J-467D01*
G01X1381755Y839727D01*
X1381653Y839656D01*
X1381289D01*
X1381187Y839727D01*
X1381165Y839787D01*
G03X1378627I-1269J-467D01*
G01X1378605Y839727D01*
X1378503Y839656D01*
X1378278D01*
G02X1378136Y839715I0J200D01*
G01X1377984Y839867D01*
X1377969Y839899D01*
G03X1376747Y840672I-1222J-579D01*
G03X1375971Y840427I0J-1351D01*
G01X1375937Y840403D01*
X1375856Y840387D01*
X1375605Y840441D01*
G02X1375479Y840527I41J196D01*
G01Y840528D01*
G03X1374805Y841202I-1882J-1208D01*
G01X1374804D01*
G02X1374718Y841328I110J167D01*
G01X1374664Y841579D01*
X1374680Y841660D01*
X1374704Y841694D01*
G37*
G36*
G01X1358857Y1348187D02*
G03I-491J0D01*
G37*
G36*
G01Y1360099D02*
G03I-491J0D01*
G37*
G36*
G01Y1372385D02*
G03I-491J0D01*
G37*
G36*
G01Y1396583D02*
G03I-491J0D01*
G37*
G36*
G01Y1384297D02*
G03I-491J0D01*
G37*
G36*
G01Y1408495D02*
G03I-491J0D01*
G37*
G36*
G01X1355325Y1558813D02*
G03I-491J0D01*
G37*
G36*
G01X1363987Y1563144D02*
G03I-491J0D01*
G37*
G36*
G01X1355325Y1568275D02*
G03I-491J0D01*
G37*
G36*
G01Y1574167D02*
G03I-491J0D01*
G37*
G36*
G01X1363987Y1567875D02*
G03I-491J0D01*
G37*
G36*
G01Y1578498D02*
G03I-491J0D01*
G37*
G36*
G01Y1572606D02*
G03I-491J0D01*
G37*
G36*
G01X1355325Y1578898D02*
G03I-491J0D01*
G37*
G36*
G01Y1563544D02*
G03I-491J0D01*
G37*
G36*
G01Y1583629D02*
G03I-491J0D01*
G37*
G36*
G01Y1589522D02*
G03I-491J0D01*
G37*
G36*
G01Y1594253D02*
G03I-491J0D01*
G37*
G36*
G01X1363987Y1583229D02*
G03I-491J0D01*
G37*
G36*
G01Y1593853D02*
G03I-491J0D01*
G37*
G36*
G01Y1587960D02*
G03I-491J0D01*
G37*
G36*
G01X1355325Y1609607D02*
G03I-491J0D01*
G37*
G36*
G01Y1604876D02*
G03I-491J0D01*
G37*
G36*
G01Y1598984D02*
G03I-491J0D01*
G37*
G36*
G01X1363987Y1609207D02*
G03I-491J0D01*
G37*
G36*
G01Y1598584D02*
G03I-491J0D01*
G37*
G36*
G01Y1603315D02*
G03I-491J0D01*
G37*
G36*
G01X1355325Y1614338D02*
G03I-491J0D01*
G37*
G36*
G01X1363987Y1613938D02*
G03I-491J0D01*
G37*
G36*
G01Y1618669D02*
G03I-491J0D01*
G37*
G36*
G01X1398959Y1005966D02*
X1398673Y1005680D01*
X1394636D01*
X1393869Y1006447D01*
X1390666D01*
X1389899Y1005680D01*
X1375965D01*
X1375719Y1005926D01*
Y1011840D01*
X1376323Y1012444D01*
X1380027D01*
X1380559Y1012976D01*
X1380903Y1013320D01*
Y1022024D01*
X1384059Y1025180D01*
X1391059D01*
X1396868D01*
X1398992D01*
X1399373Y1024799D01*
Y1006380D01*
X1398959Y1005966D01*
G37*
G36*
G01X1414032Y1120863D02*
X1427271D01*
G02X1427413Y1120804I0J-200D01*
G01X1427740Y1120477D01*
G02X1427799Y1120335I-141J-142D01*
G01Y1107335D01*
G02X1427740Y1107193I-200J0D01*
G01X1426614Y1106067D01*
G02X1426472Y1106008I-142J141D01*
G01X1426306D01*
X1426287Y1106028D01*
X1420235D01*
G03X1420094Y1105969I1J-200D01*
G01X1419464Y1105339D01*
G03X1419406Y1105198I142J-141D01*
G01Y1100025D01*
G03X1419464Y1099884I200J0D01*
G01X1422067Y1097281D01*
G02X1422126Y1097139I-141J-142D01*
G01Y1092438D01*
X1422152Y1092412D01*
Y1088598D01*
G02X1422136Y1088522I-200J2D01*
G01X1422120Y1088483D01*
Y1072886D01*
G02X1422062Y1072745I-200J0D01*
G01X1422013Y1072696D01*
G02X1421871Y1072637I-142J141D01*
G01X1382371D01*
G02X1382229Y1072696I0J200D01*
G01X1381515Y1073410D01*
G02X1381456Y1073552I141J142D01*
G01Y1104857D01*
G03X1381458Y1104889I-1497J110D01*
G03Y1104903I-200J7D01*
G03X1381456Y1104935I-1499J-78D01*
G01Y1120414D01*
G02X1381515Y1120556I200J0D01*
G01X1381763Y1120804D01*
G02X1381905Y1120863I142J-141D01*
G01X1395366D01*
G02X1395508Y1120804I0J-200D01*
G01X1395612Y1120700D01*
G02X1395671Y1120558I-141J-142D01*
G01Y1107335D01*
G02X1395612Y1107193I-200J0D01*
G01X1394486Y1106067D01*
G02X1394344Y1106008I-142J141D01*
G01X1394178D01*
X1394159Y1106028D01*
X1388107D01*
G03X1387966Y1105969I1J-200D01*
G01X1387336Y1105339D01*
G03X1387278Y1105198I142J-141D01*
G01Y1100025D01*
G03X1387336Y1099884I200J0D01*
G01X1390789Y1096431D01*
G03X1390930Y1096372I142J141D01*
G01X1406198D01*
G03X1406339Y1096431I-1J200D01*
G01X1406363Y1096455D01*
X1406436Y1096485D01*
X1409068D01*
G03X1409210Y1096544I0J200D01*
G01X1413525Y1100859D01*
G03X1413584Y1101001I-141J142D01*
G01Y1120415D01*
G02X1413643Y1120557I200J0D01*
G01X1413890Y1120804D01*
G02X1414032Y1120863I142J-141D01*
G37*
G36*
G01X1401079Y1254968D02*
X1452457D01*
G02X1452599Y1254909I0J-200D01*
G01X1453196Y1254312D01*
X1453221Y1254270D01*
X1453228Y1254246D01*
G03X1464562Y1238120I30144J9140D01*
G01X1464582Y1238106D01*
X1464610Y1238071D01*
X1464659Y1237975D01*
G02X1464681Y1237884I-178J-91D01*
G01Y1159110D01*
G02X1464622Y1158968I-200J0D01*
G01X1462969Y1157315D01*
X1462941Y1157286D01*
X1462867Y1157256D01*
X1381828D01*
G02X1381686Y1157315I0J200D01*
G01X1381492Y1157509D01*
G02X1381433Y1157651I141J142D01*
G01Y1190766D01*
G02X1381492Y1190908I200J0D01*
G01X1382052Y1191468D01*
X1384089D01*
X1384632Y1192011D01*
Y1193986D01*
G02X1384654Y1193987I20J-199D01*
G01X1444326D01*
X1447380D01*
X1447962Y1194569D01*
Y1215393D01*
X1447536Y1215819D01*
X1440532D01*
X1439887Y1215174D01*
X1435889D01*
X1435271Y1215792D01*
X1433009D01*
X1432391Y1215174D01*
X1423088D01*
X1422504Y1215758D01*
X1422430Y1215832D01*
X1419290D01*
X1419216Y1215758D01*
X1418632Y1215174D01*
X1401329D01*
G02X1401187Y1215233I0J200D01*
G01X1400317Y1216103D01*
G02X1400258Y1216245I141J142D01*
G01Y1254147D01*
G02X1400317Y1254289I200J0D01*
G01X1400937Y1254909D01*
G02X1401079Y1254968I142J-141D01*
G37*
G36*
G01X1444580Y1256342D02*
X1399925D01*
X1399127Y1255544D01*
Y1215751D01*
X1398705Y1215329D01*
X1394907D01*
X1382178D01*
X1379494D01*
X1378977Y1215846D01*
Y1241077D01*
X1381116Y1243216D01*
Y1259168D01*
X1381086Y1259198D01*
Y1260824D01*
X1380576Y1261334D01*
X1379868D01*
X1378977Y1262225D01*
Y1263785D01*
X1379139Y1263947D01*
X1403580D01*
X1406257Y1266624D01*
X1422153D01*
X1423561Y1268032D01*
X1433351D01*
X1434567Y1266816D01*
X1434805Y1266578D01*
X1448170D01*
X1448958Y1265790D01*
Y1256968D01*
X1448332Y1256342D01*
X1444580D01*
G37*
G36*
G01X1378984Y1286208D02*
X1413714D01*
G02X1413856Y1286149I0J-200D01*
G01X1418869Y1281136D01*
G03X1419011Y1281077I142J141D01*
G01X1421380D01*
G03X1421500Y1281074I116J2223D01*
G01X1445101D01*
G02X1445242Y1281015I-1J-200D01*
G01X1446364Y1279893D01*
G02X1446423Y1279751I-141J-142D01*
G01Y1278081D01*
G02X1446364Y1277939I-200J0D01*
G01X1445780Y1277355D01*
G02X1445638Y1277296I-142J141D01*
G01X1417066D01*
G02X1416924Y1277355I0J200D01*
G01X1414234Y1280045D01*
G03X1414092Y1280104I-142J-141D01*
G01X1378985D01*
G02X1378843Y1280163I0J200D01*
G01X1377826Y1281180D01*
G02X1377767Y1281322I141J142D01*
G01Y1284991D01*
G02X1377826Y1285133I200J0D01*
G01X1378842Y1286149D01*
G02X1378984Y1286208I142J-141D01*
G37*
G36*
G01X1372648Y1558813D02*
G03I-491J0D01*
G37*
G36*
G01Y1578898D02*
G03I-491J0D01*
G37*
G36*
G01Y1563544D02*
G03I-491J0D01*
G37*
G36*
G01Y1568275D02*
G03I-491J0D01*
G37*
G36*
G01Y1574167D02*
G03I-491J0D01*
G37*
G36*
G01Y1583629D02*
G03I-491J0D01*
G37*
G36*
G01Y1589522D02*
G03I-491J0D01*
G37*
G36*
G01Y1594253D02*
G03I-491J0D01*
G37*
G36*
G01Y1604876D02*
G03I-491J0D01*
G37*
G36*
G01Y1598984D02*
G03I-491J0D01*
G37*
G36*
G01Y1609607D02*
G03I-491J0D01*
G37*
G36*
G01Y1614338D02*
G03I-491J0D01*
G37*
G36*
G01X1395677Y203641D02*
X1406885D01*
X1407857Y202669D01*
Y195995D01*
X1406303Y194441D01*
X1395158D01*
X1394446Y195153D01*
Y202410D01*
X1395677Y203641D01*
G37*
G36*
G01X1386520Y323222D02*
G03I-577J0D01*
G37*
G36*
G01X1405565Y909432D02*
X1419709D01*
X1419783Y909402D01*
X1419811Y909373D01*
X1421155Y908029D01*
G02X1421214Y907887I-141J-142D01*
G01Y900994D01*
G03X1421273Y900852I200J0D01*
G01X1423903Y898222D01*
G02X1423962Y898080I-141J-142D01*
G01Y852975D01*
G02X1423903Y852833I-200J0D01*
G01X1421112Y850042D01*
X1421084Y850013D01*
X1421010Y849983D01*
X1396137D01*
G02X1395995Y850042I0J200D01*
G01X1393850Y852187D01*
X1393821Y852215D01*
X1393791Y852289D01*
Y859405D01*
G02X1393850Y859547I200J0D01*
G01X1393947Y859644D01*
G02X1394089Y859703I142J-141D01*
G01X1397263D01*
G03X1397405Y859762I0J200D01*
G01X1398688Y861045D01*
G03X1398747Y861187I-141J142D01*
G01Y862315D01*
X1398754Y862341D01*
G03X1398818Y862829I-1838J489D01*
G03X1398754Y863317I-1902J-1D01*
G01X1398747Y863343D01*
Y876646D01*
G03X1398688Y876788I-200J0D01*
G01X1396975Y878501D01*
G03X1396833Y878560I-142J-141D01*
G01X1393981D01*
G02X1393839Y878619I0J200D01*
G01X1392664Y879794D01*
X1392635Y879822D01*
X1392605Y879896D01*
Y883325D01*
G02X1392664Y883467I200J0D01*
G01X1393732Y884535D01*
G02X1393874Y884594I142J-141D01*
G01X1398341D01*
G03X1398483Y884653I0J200D01*
G01X1400628Y886798D01*
G03X1400687Y886940I-141J142D01*
G01Y890047D01*
X1400736Y890136D01*
X1400779Y890164D01*
X1401062Y890346D01*
G02X1401253Y890360I108J-168D01*
G03X1402000Y890198I747J1641D01*
G03Y893802I0J1802D01*
G01X1401939D01*
G03X1401252Y893641I60J-1802D01*
G02X1401061Y893655I-83J182D01*
G01X1400779Y893836D01*
G02X1400687Y894004I108J168D01*
G01Y898047D01*
X1400736Y898136D01*
X1400779Y898164D01*
X1401062Y898346D01*
G02X1401253Y898360I108J-168D01*
G03X1402000Y898198I747J1641D01*
G03Y901802I0J1802D01*
G03X1400198Y900001I0J-1802D01*
G01Y899999D01*
G03X1400200Y899904I1802J-10D01*
G01X1400202Y899862D01*
X1400172Y899783D01*
X1400142Y899753D01*
G02X1399859I-141J142D01*
G01X1399776Y899836D01*
G03X1399634Y899895I-142J-141D01*
G01X1395706D01*
G02X1395564Y899954I0J200D01*
G01X1394604Y900914D01*
X1394575Y900942D01*
X1394545Y901016D01*
Y907982D01*
X1394575Y908056D01*
X1394604Y908084D01*
X1395893Y909373D01*
G02X1396035Y909432I142J-141D01*
G01X1400121D01*
G02X1400285Y909346I0J-200D01*
G01X1400501Y909037D01*
X1400513Y908940D01*
X1400496Y908894D01*
G03X1400385Y908270I1691J-623D01*
G03X1403989I1802J0D01*
G03X1403925Y908745I-1802J-1D01*
G01X1403911Y908795D01*
X1403935Y908894D01*
X1404236Y909221D01*
X1404332Y909253D01*
X1404384Y909243D01*
G03X1404689Y909216I300J1654D01*
G03X1405472Y909409I1J1681D01*
G02X1405565Y909432I93J-177D01*
G37*
G36*
G01X1390743Y882100D02*
G02X1390802Y881958I-141J-142D01*
G01Y877384D01*
X1390608Y877190D01*
Y875613D01*
X1390802Y875419D01*
Y871752D01*
G02X1390743Y871610I-200J0D01*
G01X1389461Y870328D01*
G02X1389319Y870269I-142J141D01*
G01X1384878D01*
G02X1384736Y870328I0J200D01*
G01X1384472Y870592D01*
X1384442Y870673D01*
X1384445Y870717D01*
G03X1384448Y870814I-1399J92D01*
G03X1384351Y871327I-1402J1D01*
G01X1384337Y871362D01*
Y873416D01*
X1384351Y873451D01*
G03X1384448Y873964I-1305J512D01*
G03X1384351Y874477I-1402J1D01*
G01X1384337Y874512D01*
Y876566D01*
X1384351Y876601D01*
G03X1384448Y877114I-1305J512D01*
G03X1384351Y877627I-1402J1D01*
G01X1384337Y877662D01*
Y879715D01*
X1384351Y879750D01*
G03X1384448Y880263I-1305J512D01*
G01X1384767Y880582D01*
Y888042D01*
X1385404Y888678D01*
X1393592D01*
X1394388Y887882D01*
Y886497D01*
X1393635Y885744D01*
X1392348D01*
X1390743Y884139D01*
Y882100D01*
G37*
G36*
G01X1384689Y897933D02*
X1398154D01*
G02X1398296Y897874I0J-200D01*
G01X1398447Y897723D01*
G02X1398506Y897581I-141J-142D01*
G01Y892736D01*
G02X1398447Y892594I-200J0D01*
G01X1395817Y889964D01*
G02X1395675Y889905I-142J141D01*
G01X1384850D01*
G02X1384708Y889964I0J200D01*
G01X1384262Y890410D01*
X1384250Y890431D01*
G03X1384115Y890620I-1205J-718D01*
G02X1384067Y890749I152J130D01*
G01Y891825D01*
G02X1384115Y891954I200J-1D01*
G03X1384448Y892862I-1069J907D01*
G03X1384115Y893770I-1402J1D01*
G02X1384067Y893899I152J130D01*
G01Y897311D01*
G02X1384126Y897453I200J0D01*
G01X1384547Y897874D01*
G02X1384689Y897933I142J-141D01*
G37*
G36*
G01X1397580Y1097374D02*
X1391262D01*
X1388279Y1100357D01*
Y1104866D01*
X1388439Y1105026D01*
X1393827D01*
X1395597Y1103256D01*
G03X1395739Y1103197I142J141D01*
G01X1397880D01*
X1399649D01*
X1400826Y1102020D01*
X1403037Y1099809D01*
X1404945D01*
X1405485D01*
X1406023Y1099271D01*
Y1097531D01*
X1405866Y1097374D01*
X1400401D01*
X1397580D01*
G37*
G36*
G01X1453840Y174205D02*
X1457392D01*
G02X1457532Y174148I0J-200D01*
G01X1457533Y174147D01*
X1459735Y171945D01*
G02X1459737Y171943I-140J-142D01*
G02X1459794Y171803I-143J-140D01*
G01Y147990D01*
G02X1459684Y147811I-200J0D01*
G01X1459366Y147650D01*
G02X1459156Y147668I-90J178D01*
G03X1458262Y147963I-894J-1207D01*
G03Y144959I0J-1502D01*
G03X1459156Y145254I0J1502D01*
G02X1459366Y145272I120J-160D01*
G01X1459684Y145111D01*
G02X1459794Y144932I-90J-179D01*
G01Y138227D01*
X1459721Y138124D01*
X1459661Y138103D01*
G03X1458960Y137587I502J-1416D01*
G01X1458939Y137559D01*
X1458852Y137501D01*
G02X1458785Y137473I-109J168D01*
G01X1458666Y137446D01*
X1458592Y137457D01*
X1458559Y137475D01*
G03X1458258Y137612I-894J-1565D01*
G03X1457667Y137712I-592J-1703D01*
G03X1457076Y137612I1J-1803D01*
G03X1456775Y137475I593J-1702D01*
G01X1456742Y137457D01*
X1456668Y137446D01*
X1456549Y137473D01*
G02X1456482Y137501I42J196D01*
G01X1456394Y137560D01*
X1456374Y137588D01*
G03X1455171Y138189I-1202J-901D01*
G01X1455128D01*
X1455127Y138188D01*
G03X1453669Y136687I44J-1501D01*
G03X1455171Y135185I1502J0D01*
G03X1455403Y135203I0J1502D01*
G01X1455446Y135210D01*
X1455530Y135186D01*
X1455828Y134932D01*
X1455864Y134853D01*
Y133610D01*
Y133565D01*
X1455828Y133486D01*
X1455530Y133232D01*
X1455446Y133208D01*
X1455403Y133215D01*
G03X1455168Y133233I-232J-1484D01*
G01X1455167D01*
G03X1453669Y131731I4J-1502D01*
G03X1455171Y130229I1502J0D01*
G01X1455172D01*
G03X1456374Y130830I0J1502D01*
G01X1456394Y130858D01*
X1456482Y130917D01*
G02X1456549Y130945I109J-168D01*
G01X1456668Y130972D01*
X1456742Y130961D01*
X1456775Y130943D01*
G03X1457076Y130806I894J1565D01*
G03X1457667Y130706I592J1703D01*
G03X1458258Y130806I-1J1803D01*
G03X1458559Y130943I-593J1702D01*
G01X1458592Y130961D01*
X1458666Y130972D01*
X1458785Y130945D01*
G02X1458852Y130917I-42J-196D01*
G01X1458939Y130859D01*
X1458960Y130831D01*
G03X1459661Y130315I1203J900D01*
G01X1459721Y130294D01*
X1459794Y130191D01*
Y124053D01*
X1459721Y123950D01*
X1459661Y123929D01*
G03X1458960Y123413I502J-1416D01*
G01X1458939Y123385D01*
X1458852Y123327D01*
G02X1458785Y123299I-109J168D01*
G01X1458666Y123272D01*
X1458592Y123283D01*
X1458559Y123301D01*
G03X1458258Y123438I-894J-1565D01*
G03X1457667Y123538I-592J-1703D01*
G03X1457076Y123438I1J-1803D01*
G03X1456775Y123301I593J-1702D01*
G01X1456742Y123283D01*
X1456668Y123272D01*
X1456549Y123299D01*
G02X1456482Y123327I42J196D01*
G01X1456394Y123386D01*
X1456374Y123414D01*
G03X1455171Y124015I-1202J-901D01*
G01X1455128D01*
X1455127Y124014D01*
G03X1453669Y122513I44J-1501D01*
G03X1455171Y121011I1502J0D01*
G03X1455403Y121029I0J1502D01*
G01X1455446Y121036D01*
X1455530Y121012D01*
X1455828Y120758D01*
X1455864Y120679D01*
Y119436D01*
Y119391D01*
X1455828Y119312D01*
X1455530Y119058D01*
X1455446Y119034D01*
X1455403Y119041D01*
G03X1455168Y119059I-232J-1484D01*
G01X1455167D01*
G03X1453669Y117557I4J-1502D01*
G03X1455171Y116055I1502J0D01*
G01X1455172D01*
G03X1456374Y116656I0J1502D01*
G01X1456394Y116684D01*
X1456482Y116743D01*
G02X1456549Y116771I109J-168D01*
G01X1456668Y116798D01*
X1456742Y116787D01*
X1456775Y116769D01*
G03X1457076Y116632I894J1565D01*
G03X1457667Y116532I592J1703D01*
G03X1458258Y116632I-1J1803D01*
G03X1458559Y116769I-593J1702D01*
G01X1458592Y116787D01*
X1458666Y116798D01*
X1458785Y116771D01*
G02X1458852Y116743I-42J-196D01*
G01X1458939Y116685D01*
X1458960Y116657D01*
G03X1459661Y116141I1203J900D01*
G01X1459721Y116120D01*
X1459794Y116017D01*
Y78102D01*
G02X1459768Y78003I-200J0D01*
G01X1459708Y77899D01*
X1459676Y77865D01*
X1459655Y77851D01*
G03X1459217Y77421I811J-1264D01*
G01X1459216Y77420D01*
Y77419D01*
G02X1459082Y77334I-165J113D01*
G01X1458793Y77288D01*
G02X1458639Y77327I-32J197D01*
G03X1457718Y77642I-920J-1187D01*
G01X1457688D01*
G03X1456216Y76140I30J-1502D01*
G03X1457718Y74638I1502J0D01*
G01X1457734D01*
X1457794Y74639D01*
X1457897Y74572D01*
X1458064Y74174D01*
G02X1458021Y73955I-184J-78D01*
G01X1456567Y72501D01*
X1456539Y72472D01*
X1456465Y72442D01*
X1410352D01*
G02X1410210Y72501I0J200D01*
G01X1408894Y73817D01*
X1408865Y73845D01*
X1408835Y73919D01*
Y100421D01*
G02X1408894Y100563I200J0D01*
G01X1409096Y100763D01*
G02X1409237Y100821I141J-142D01*
G01X1409248D01*
G03Y103825I0J1502D01*
G01X1409237D01*
G02X1409096Y103883I0J200D01*
G01X1408894Y104083D01*
G02X1408835Y104225I141J142D01*
G01Y107508D01*
G02X1408894Y107650I200J0D01*
G01X1409096Y107850D01*
G02X1409237Y107908I141J-142D01*
G01X1409248D01*
G03Y110912I0J1502D01*
G01X1409237D01*
G02X1409096Y110970I0J200D01*
G01X1408894Y111170D01*
G02X1408835Y111312I141J142D01*
G01Y114594D01*
G02X1408894Y114736I200J0D01*
G01X1409096Y114936D01*
G02X1409237Y114994I141J-142D01*
G01X1409248D01*
G03Y117998I0J1502D01*
G01X1409237D01*
G02X1409096Y118056I0J200D01*
G01X1408894Y118256D01*
G02X1408835Y118398I141J142D01*
G01Y121681D01*
G02X1408894Y121823I200J0D01*
G01X1409096Y122023D01*
G02X1409237Y122081I141J-142D01*
G01X1409248D01*
G03Y125085I0J1502D01*
G01X1409237D01*
G02X1409096Y125143I0J200D01*
G01X1408894Y125343D01*
G02X1408835Y125485I141J142D01*
G01Y128768D01*
G02X1408894Y128910I200J0D01*
G01X1409096Y129110D01*
G02X1409237Y129168I141J-142D01*
G01X1409248D01*
G03Y132172I0J1502D01*
G01X1409237D01*
G02X1409096Y132230I0J200D01*
G01X1408894Y132430D01*
G02X1408835Y132572I141J142D01*
G01Y135854D01*
G02X1408894Y135996I200J0D01*
G01X1409096Y136196D01*
G02X1409237Y136254I141J-142D01*
G01X1409248D01*
G03Y139258I0J1502D01*
G01X1409237D01*
G02X1409096Y139316I0J200D01*
G01X1408894Y139516D01*
G02X1408835Y139658I141J142D01*
G01Y172123D01*
G02X1408892Y172263I200J0D01*
G01X1408893Y172264D01*
X1410775Y174146D01*
G02X1410777Y174148I142J-140D01*
G02X1410917Y174205I140J-143D01*
G01X1450846D01*
G02X1451032Y174078I0J-200D01*
G01X1451191Y173673D01*
X1451164Y173554D01*
X1451118Y173512D01*
G03X1450541Y172190I1226J-1322D01*
G03X1454145I1802J0D01*
G03X1454134Y172390I-1802J1D01*
G01X1454135D01*
G03X1453568Y173512I-1792J-201D01*
G01X1453523Y173555D01*
X1453495Y173674D01*
X1453654Y174078D01*
G02X1453840Y174205I186J-73D01*
G37*
G36*
G01X1408412Y478982D02*
G03X1406910Y480484I-1502J0D01*
G03X1406104Y480249I1J-1502D01*
G01X1406071Y480228D01*
X1406056Y480218D01*
X1406009Y480186D01*
X1405899Y480179D01*
X1405536Y480370D01*
G02X1405499Y480395I93J177D01*
G02X1405429Y480547I130J152D01*
G01Y482417D01*
G02X1405527Y482589I200J0D01*
G01X1405531Y482592D01*
X1405899Y482785D01*
X1406009Y482778D01*
X1406056Y482746D01*
X1406071Y482736D01*
X1406104Y482715D01*
G03X1406910Y482480I807J1267D01*
G01X1406938D01*
G03X1408412Y483982I-28J1502D01*
G03X1406910Y485484I-1502J0D01*
G03X1406104Y485249I1J-1502D01*
G01X1406071Y485228D01*
X1406056Y485218D01*
X1406009Y485186D01*
X1405899Y485179D01*
X1405536Y485370D01*
G02X1405499Y485395I93J177D01*
G02X1405429Y485547I130J152D01*
G01Y486417D01*
G02X1405527Y486589I200J0D01*
G01X1405531Y486592D01*
X1405899Y486785D01*
X1406009Y486778D01*
X1406056Y486746D01*
X1406071Y486736D01*
X1406104Y486715D01*
G03X1406910Y486480I807J1267D01*
G01X1406938D01*
G03X1408412Y487982I-28J1502D01*
G03X1406910Y489484I-1502J0D01*
G03X1406104Y489249I1J-1502D01*
G01X1406071Y489228D01*
X1406056Y489218D01*
X1406009Y489186D01*
X1405899Y489179D01*
X1405536Y489370D01*
G02X1405499Y489395I93J177D01*
G02X1405429Y489547I130J152D01*
G01Y490417D01*
G02X1405527Y490589I200J0D01*
G01X1405531Y490592D01*
X1405899Y490785D01*
X1406009Y490778D01*
X1406056Y490746D01*
X1406071Y490736D01*
X1406104Y490715D01*
G03X1406910Y490480I807J1267D01*
G01X1406938D01*
G03X1408412Y491982I-28J1502D01*
G03X1406910Y493484I-1502J0D01*
G03X1406104Y493249I1J-1502D01*
G01X1406071Y493228D01*
X1406056Y493218D01*
X1406009Y493186D01*
X1405899Y493179D01*
X1405536Y493370D01*
G02X1405499Y493395I93J177D01*
G02X1405429Y493547I130J152D01*
G01Y498417D01*
G02X1405527Y498589I200J0D01*
G01X1405531Y498592D01*
X1405899Y498785D01*
X1406009Y498778D01*
X1406056Y498746D01*
X1406071Y498736D01*
X1406104Y498715D01*
G03X1406910Y498480I807J1267D01*
G01X1406938D01*
G03X1408412Y499982I-28J1502D01*
G03X1406910Y501484I-1502J0D01*
G01X1406905D01*
G02X1406720Y501607I0J200D01*
G01X1406578Y501949D01*
G02X1406621Y502167I185J77D01*
G01X1406821Y502367D01*
G02X1406823Y502369I142J-140D01*
G02X1406963Y502426I140J-143D01*
G01X1454280D01*
G03X1454422Y502485I0J200D01*
G01X1455607Y503670D01*
G03X1455666Y503812I-141J142D01*
G01Y528321D01*
G02X1455725Y528463I200J0D01*
G01X1478370Y551108D01*
G02X1478372Y551110I142J-140D01*
G02X1478512Y551167I140J-143D01*
G01X1512478D01*
G02X1512573Y551143I0J-200D01*
G03X1513995I711J1323D01*
G02X1514090Y551167I95J-176D01*
G01X1531851D01*
G03X1531993Y551226I0J200D01*
G01X1540181Y559414D01*
G02X1540183Y559416I142J-140D01*
G02X1540323Y559473I140J-143D01*
G01X1551846D01*
G02X1551987Y559415I0J-200D01*
G01X1552091Y559312D01*
X1552231Y559172D01*
G02X1552280Y559060I-151J-133D01*
G01Y549446D01*
G02X1552234Y549318I-200J0D01*
G01X1552228Y549311D01*
X1552067Y549150D01*
X1552039Y549121D01*
X1551965Y549091D01*
X1546169D01*
G03X1546027Y549032I0J-200D01*
G01X1538082Y541087D01*
X1538054Y541058D01*
X1537980Y541028D01*
X1508114D01*
G03X1507972Y540969I0J-200D01*
G01X1494408Y527405D01*
G03X1494349Y527263I141J-142D01*
G01Y474821D01*
G02X1494290Y474679I-200J0D01*
G01X1473641Y454030D01*
X1473613Y454001D01*
X1473539Y453971D01*
X1427828D01*
G02X1427749Y453988I2J200D01*
G01X1427714Y454003D01*
X1427460Y454253D01*
X1427430Y454324D01*
X1427429Y454364D01*
G03X1427060Y455325I-1502J-25D01*
G01X1427059Y455326D01*
X1427058Y455327D01*
G02X1427010Y455457I152J130D01*
G01Y455721D01*
G02X1427058Y455851I200J0D01*
G01X1427059Y455852D01*
X1427060Y455853D01*
G03Y457825I-1132J986D01*
G01X1427059Y457826D01*
X1427058Y457827D01*
G02X1427010Y457957I152J130D01*
G01Y458221D01*
G02X1427058Y458351I200J0D01*
G01X1427059Y458352D01*
X1427060Y458353D01*
G03X1427429Y459339I-1133J986D01*
G03X1427380Y459718I-1502J-1D01*
G02X1427408Y459880I194J50D01*
G01X1427576Y460130D01*
G02X1427715Y460217I166J-111D01*
G01X1427716D01*
G03X1429286Y462004I-232J1787D01*
G03X1425682I-1802J0D01*
G01Y462001D01*
G03X1425813Y461329I1802J3D01*
G01Y461328D01*
X1425814Y461325D01*
G02X1425806Y461163I-186J-72D01*
G01X1425672Y460895D01*
G02X1425620Y460831I-178J92D01*
G01X1425585Y460802D01*
X1425542Y460791D01*
G03X1424941Y460471I387J-1451D01*
G02X1424939Y460470I-88J173D01*
G02X1424809Y460422I-130J152D01*
G01X1424545D01*
G02X1424415Y460470I0J200D01*
G01X1424414Y460471D01*
G03X1423427Y460841I-987J-1131D01*
G03X1421925Y459339I0J-1502D01*
G03X1422294Y458353I1502J0D01*
G01X1422295Y458352D01*
X1422296Y458351D01*
G02X1422344Y458221I-152J-130D01*
G01Y457957D01*
G02X1422296Y457827I-200J0D01*
G01X1422295Y457826D01*
X1422294Y457825D01*
G03Y455853I1132J-986D01*
G01X1422295Y455852D01*
X1422296Y455851D01*
G02X1422344Y455721I-152J-130D01*
G01Y455457D01*
G02X1422296Y455327I-200J0D01*
G01X1422295Y455326D01*
X1422294Y455325D01*
G03X1421925Y454364I1133J-986D01*
G01X1421924Y454324D01*
X1421894Y454253D01*
X1421667Y454029D01*
G02X1421606Y453988I-140J143D01*
G01X1421567Y453971D01*
X1421525D01*
X1419355D01*
X1419260Y454029D01*
X1419234Y454079D01*
X1419044Y454444D01*
X1419051Y454555D01*
X1419084Y454601D01*
G03X1419358Y455466I-1228J865D01*
G03X1416354I-1502J0D01*
G03X1416628Y454601I1502J0D01*
G02X1416645Y454398I-163J-116D01*
G02X1416642Y454393I-173J100D01*
G01X1416478Y454079D01*
X1416452Y454029D01*
X1416357Y453971D01*
X1410023D01*
G02X1409881Y454030I0J200D01*
G01X1405488Y458423D01*
X1405459Y458451D01*
X1405429Y458525D01*
Y477417D01*
G02X1405527Y477589I200J0D01*
G01X1405531Y477592D01*
X1405899Y477785D01*
X1406009Y477778D01*
X1406056Y477746D01*
X1406071Y477736D01*
X1406104Y477715D01*
G03X1406910Y477480I807J1267D01*
G01X1406938D01*
G03X1408412Y478982I-28J1502D01*
G37*
G36*
G01X1413997Y615351D02*
X1414022Y615376D01*
X1414095Y615406D01*
X1426917D01*
G02X1427059Y615347I0J-200D01*
G01X1428441Y613965D01*
G02X1428500Y613823I-141J-142D01*
G01Y604009D01*
G02X1428474Y603911I-200J1D01*
G03X1428182Y602800I1970J-1112D01*
G03X1428474Y601689I2262J1D01*
G01X1428487Y601666D01*
X1428500Y601617D01*
Y600833D01*
X1428487Y600784D01*
X1428474Y600761D01*
G03X1428182Y599650I1970J-1112D01*
G01Y595000D01*
G03X1428474Y593889I2262J1D01*
G02X1428500Y593791I-174J-99D01*
G01Y589083D01*
G03X1428559Y588941I200J0D01*
G01X1429366Y588134D01*
G02X1429425Y587992I-141J-142D01*
G01Y573216D01*
G03X1429484Y573074I200J0D01*
G01X1432865Y569693D01*
G03X1433007Y569634I142J141D01*
G01X1439141D01*
G03X1439283Y569693I0J200D01*
G01X1440046Y570456D01*
X1441996Y572407D01*
G03X1442055Y572549I-141J142D01*
G01Y577148D01*
G02X1442114Y577290I200J0D01*
G01X1442544Y577720D01*
G02X1442686Y577779I142J-141D01*
G01X1447475D01*
G02X1447617Y577720I0J-200D01*
G01X1447843Y577494D01*
G02X1447902Y577352I-141J-142D01*
G01Y570820D01*
G02X1447843Y570678I-200J0D01*
G01X1445761Y568596D01*
G03X1445702Y568454I141J-142D01*
G01Y556856D01*
X1445731Y556827D01*
Y551474D01*
G03X1445790Y551332I200J0D01*
G01X1447437Y549685D01*
G03X1447579Y549626I142J141D01*
G01X1450740D01*
G02X1450882Y549567I0J-200D01*
G01X1451767Y548682D01*
G02X1451826Y548540I-141J-142D01*
G01Y536820D01*
G02X1451767Y536678I-200J0D01*
G01X1451137Y536048D01*
G02X1450995Y535989I-142J141D01*
G01X1415262D01*
G02X1415120Y536048I0J200D01*
G01X1414074Y537094D01*
G02X1414015Y537236I141J142D01*
G01Y554389D01*
X1413997Y554407D01*
Y615351D01*
G37*
G36*
G01X1405369Y910897D02*
G03I-680J0D01*
G37*
G36*
G01X1404008Y1059146D02*
Y1069654D01*
X1405071Y1070717D01*
X1420986D01*
X1421955Y1069748D01*
Y1059792D01*
X1421941Y1059778D01*
Y1058387D01*
X1420609Y1057055D01*
X1404897D01*
X1404008Y1057944D01*
Y1059146D01*
G37*
G36*
G01X1414936Y1303020D02*
G03I-590J0D01*
G37*
G36*
G01X1405033Y1573776D02*
X1436103D01*
G02X1436245Y1573717I0J-200D01*
G01X1439226Y1570736D01*
G02X1439285Y1570594I-141J-142D01*
G01Y1564418D01*
G02X1439210Y1564262I-200J0D01*
G03Y1561924I943J-1169D01*
G02X1439285Y1561768I-125J-156D01*
G01Y1539015D01*
G02X1439226Y1538873I-200J0D01*
G01X1429293Y1528940D01*
X1429246Y1528913D01*
X1429219Y1528906D01*
G03X1428085Y1527450I368J-1456D01*
G03X1428125Y1527107I1502J1D01*
G01X1428130Y1527084D01*
Y1522080D01*
G02X1428071Y1521939I-200J1D01*
G01X1418858Y1512726D01*
G02X1418717Y1512667I-142J141D01*
G01X1405404D01*
G02X1405262Y1512726I0J200D01*
G01X1401538Y1516450D01*
G02X1401479Y1516592I141J142D01*
G01Y1570222D01*
G02X1401538Y1570364I200J0D01*
G01X1401587Y1570413D01*
G02X1401789Y1570461I140J-142D01*
G01X1402182Y1570335D01*
X1402255Y1570249D01*
X1402264Y1570194D01*
G03X1403747Y1568931I1483J239D01*
G03X1405249Y1570433I0J1502D01*
G03X1403986Y1571916I-1502J0D01*
G01X1403931Y1571925D01*
X1403845Y1571998D01*
X1403719Y1572391D01*
G02X1403767Y1572593I190J62D01*
G01X1404891Y1573717D01*
G02X1405033Y1573776I142J-141D01*
G37*
G36*
G01X1423493Y910065D02*
G03I-680J0D01*
G37*
G36*
G01X1508917Y54588D02*
X1537184D01*
X1537398Y54374D01*
Y52805D01*
X1537184Y52591D01*
X1508917D01*
G03X1502980Y46654I0J-5937D01*
G01Y7874D01*
G02X1497106Y2000I-5874J0D01*
G01X1449862D01*
G02X1443988Y7874I0J5874D01*
G01Y46654D01*
G03X1442424Y50670I-5938J0D01*
G01Y50786D01*
X1442657Y51019D01*
X1444546D01*
X1444895Y50670D01*
G02X1445986Y46656I-6843J-4015D01*
G01Y7874D01*
G03X1449862Y3998I3876J0D01*
G01X1497106D01*
G03X1500982Y7874I0J3876D01*
G01Y46654D01*
G02X1508917Y54588I7935J-1D01*
G37*
G36*
G01X1469480Y581389D02*
X1531579D01*
X1538415D01*
X1541933Y577871D01*
X1550677D01*
G02X1550819Y577812I0J-200D01*
G01X1551317Y577314D01*
G02X1551376Y577172I-141J-142D01*
G01Y576781D01*
G02X1551317Y576640I-200J1D01*
G01X1551312Y576634D01*
X1551282Y576561D01*
Y561385D01*
G02X1551223Y561244I-200J1D01*
G01X1551222Y561243D01*
G02X1551080Y561184I-142J141D01*
G01X1539264D01*
G03X1539122Y561125I0J-200D01*
G01X1530403Y552406D01*
G02X1530261Y552347I-142J141D01*
G01X1514903D01*
X1514788Y552457D01*
X1514784Y552537D01*
G03X1511784I-1500J-71D01*
G01X1511780Y552457D01*
X1511665Y552347D01*
X1448991D01*
G02X1448849Y552406I0J200D01*
G01X1447663Y553592D01*
G02X1447604Y553734I141J142D01*
G01Y567086D01*
G02X1447663Y567228I200J0D01*
G01X1453571Y573136D01*
G02X1453713Y573195I142J-141D01*
G01X1461120D01*
G03X1461262Y573254I0J200D01*
G01X1469338Y581330D01*
G02X1469480Y581389I142J-141D01*
G37*
G36*
G01X1435921Y593796D02*
G03I-680J0D01*
G37*
G36*
G01X1438868Y867633D02*
G03I-680J0D01*
G37*
G36*
G01X1449752Y892581D02*
G03I-680J0D01*
G37*
G36*
G01X1441876Y1335776D02*
G03I-590J0D01*
G37*
G36*
G01X1433976Y1343309D02*
G03I-590J0D01*
G37*
G36*
G01X1461921Y867475D02*
G03I-680J0D01*
G37*
G36*
G01X1462823Y880804D02*
X1467669D01*
X1467863Y880610D01*
Y874249D01*
X1467304Y873690D01*
X1461754D01*
X1461063Y874381D01*
Y879997D01*
X1461870Y880804D01*
X1462823D01*
G37*
G36*
G01X1461152Y885985D02*
G03I-680J0D01*
G37*
G36*
G01X1463409Y949996D02*
G03I-590J0D01*
G37*
G36*
G01X1476322Y1415920D02*
X1810704D01*
G02X1810846Y1415861I0J-200D01*
G01X1823007Y1403700D01*
G02X1823066Y1403558I-141J-142D01*
G01Y1341405D01*
G02X1823007Y1341263I-200J0D01*
G01X1803802Y1322058D01*
G02X1803660Y1321999I-142J141D01*
G01X1466342D01*
G02X1466200Y1322058I0J200D01*
G01X1453661Y1334597D01*
G02X1453602Y1334739I141J142D01*
G01Y1393200D01*
G02X1453661Y1393342I200J0D01*
G01X1476180Y1415861D01*
G02X1476322Y1415920I142J-141D01*
G37*
G36*
G01X1475998Y715822D02*
X1588179D01*
G02X1588319Y715765I0J-200D01*
G01X1588320Y715764D01*
X1589532Y714552D01*
G02X1589534Y714550I-140J-142D01*
G02X1589591Y714410I-143J-140D01*
G01Y662318D01*
G02X1589532Y662176I-200J0D01*
G01X1589281Y661925D01*
G02X1589140Y661866I-142J141D01*
G01X1577713D01*
G02X1577547Y661955I0J200D01*
G01X1577333Y662272D01*
X1577323Y662370D01*
X1577342Y662417D01*
G03X1577452Y662981I-1391J564D01*
G03X1574448I-1502J0D01*
G03X1574558Y662417I1501J0D01*
G01X1574577Y662370D01*
X1574567Y662272D01*
X1574353Y661955D01*
G02X1574187Y661866I-166J111D01*
G01X1569753D01*
G02X1569553Y662066I0J200D01*
G01Y666983D01*
G02X1569611Y667124I200J0D01*
G01X1569836Y667352D01*
X1569907Y667383D01*
X1569947D01*
G03Y670387I-21J1502D01*
G01X1569907D01*
X1569836Y670418D01*
X1569611Y670646D01*
G02X1569553Y670787I142J141D01*
G01Y675512D01*
X1569644Y675622D01*
X1569716Y675636D01*
G03Y678586I-282J1475D01*
G01X1569644Y678600D01*
X1569553Y678710D01*
Y679496D01*
G03X1569494Y679638I-200J0D01*
G01X1568463Y680669D01*
G03X1568321Y680728I-142J-141D01*
G01X1553967D01*
G02X1553825Y680787I0J200D01*
G01X1553807Y680805D01*
X1553734Y680835D01*
X1477264D01*
G02X1477064Y681025I0J200D01*
G03X1475264Y682735I-1800J-92D01*
G01X1475222D01*
G03X1475098Y682727I54J-1801D01*
G01X1475049Y682723D01*
X1475007Y682738D01*
G02X1474933Y682785I68J188D01*
G01X1474644Y683074D01*
G02X1474622Y683100I141J142D01*
G01Y683101D01*
G02X1474596Y683282I163J116D01*
G01X1474715Y683622D01*
G02X1474881Y683754I188J-67D01*
G03X1476215Y685247I-168J1493D01*
G03X1474713Y686749I-1502J0D01*
G03X1473220Y685415I0J-1502D01*
G02X1473088Y685249I-199J22D01*
G01X1472748Y685130D01*
G02X1472567Y685156I-65J189D01*
G01X1472552Y685166D01*
X1471185Y686533D01*
X1471156Y686561D01*
X1471126Y686635D01*
Y705496D01*
G02X1471189Y705642I200J0D01*
G03Y708272I-1232J1315D01*
G02X1471126Y708418I137J146D01*
G01Y715297D01*
G02X1471183Y715437I200J0D01*
G01X1471184Y715438D01*
X1471509Y715763D01*
G02X1471511Y715765I142J-140D01*
G02X1471651Y715822I140J-143D01*
G01X1472852D01*
X1472959Y715740D01*
X1472977Y715675D01*
G03X1475873I1448J400D01*
G01X1475891Y715740D01*
X1475998Y715822D01*
G37*
G36*
G01X1472095Y748629D02*
G03I-680J0D01*
G37*
G36*
G01X1474314Y864337D02*
G03I-680J0D01*
G37*
G36*
G01X1469640Y880998D02*
X1474389D01*
X1475139Y880248D01*
Y870984D01*
X1474521Y870366D01*
X1469157D01*
X1468994Y870529D01*
Y880352D01*
X1469640Y880998D01*
G37*
G36*
G01X1482134Y911570D02*
G03I-680J0D01*
G37*
G36*
G01X1466756Y979746D02*
G03I-680J0D01*
G37*
G36*
G01X1505691Y1066535D02*
G02I-17700J0D01*
G37*
G36*
G01Y1263386D02*
G02I-17700J0D01*
G37*
G36*
G01X1476585Y1461182D02*
G03I-491J0D01*
G37*
G36*
G01Y1456451D02*
G03I-491J0D01*
G37*
G36*
G01Y1471805D02*
G03I-491J0D01*
G37*
G36*
G01Y1481267D02*
G03I-491J0D01*
G37*
G36*
G01Y1476536D02*
G03I-491J0D01*
G37*
G36*
G01Y1465913D02*
G03I-491J0D01*
G37*
G36*
G01Y1491891D02*
G03I-491J0D01*
G37*
G36*
G01Y1487160D02*
G03I-491J0D01*
G37*
G36*
G01Y1496622D02*
G03I-491J0D01*
G37*
G36*
G01Y1511976D02*
G03I-491J0D01*
G37*
G36*
G01Y1507245D02*
G03I-491J0D01*
G37*
G36*
G01Y1502514D02*
G03I-491J0D01*
G37*
G36*
G01Y1558813D02*
G03I-491J0D01*
G37*
G36*
G01Y1578898D02*
G03I-491J0D01*
G37*
G36*
G01Y1563544D02*
G03I-491J0D01*
G37*
G36*
G01Y1568275D02*
G03I-491J0D01*
G37*
G36*
G01Y1574167D02*
G03I-491J0D01*
G37*
G36*
G01Y1583629D02*
G03I-491J0D01*
G37*
G36*
G01Y1594253D02*
G03I-491J0D01*
G37*
G36*
G01Y1589522D02*
G03I-491J0D01*
G37*
G36*
G01Y1609607D02*
G03I-491J0D01*
G37*
G36*
G01Y1598984D02*
G03I-491J0D01*
G37*
G36*
G01Y1604876D02*
G03I-491J0D01*
G37*
G36*
G01Y1614338D02*
G03I-491J0D01*
G37*
G36*
G01X1498039Y203641D02*
X1509247D01*
X1510219Y202669D01*
Y198059D01*
X1509409Y197249D01*
X1497877D01*
X1496808Y198318D01*
Y202410D01*
X1498039Y203641D01*
G37*
G36*
G01X1488503Y347387D02*
G03I-577J0D01*
G37*
G36*
G01X1484390Y368516D02*
G03I-577J0D01*
G37*
G36*
G01X1491742Y793003D02*
G03I-680J0D01*
G37*
G36*
G01X1490330Y836985D02*
G03I-680J0D01*
G37*
G36*
G01X1490485Y866386D02*
G03I-680J0D01*
G37*
G36*
G01X1492094Y875383D02*
G03I-680J0D01*
G37*
G36*
G01X1492781Y894860D02*
G03I-680J0D01*
G37*
G36*
G01X1485906Y973886D02*
G03I-680J0D01*
G37*
G36*
G01X1493240Y974654D02*
G03I-680J0D01*
G37*
G36*
G01X1485246Y1460782D02*
G03I-491J0D01*
G37*
G36*
G01X1493908Y1456451D02*
G03I-491J0D01*
G37*
G36*
G01Y1461182D02*
G03I-491J0D01*
G37*
G36*
G01Y1476536D02*
G03I-491J0D01*
G37*
G36*
G01Y1481267D02*
G03I-491J0D01*
G37*
G36*
G01X1485246Y1465513D02*
G03I-491J0D01*
G37*
G36*
G01X1493908Y1465913D02*
G03I-491J0D01*
G37*
G36*
G01X1485246Y1476136D02*
G03I-491J0D01*
G37*
G36*
G01Y1470244D02*
G03I-491J0D01*
G37*
G36*
G01Y1480867D02*
G03I-491J0D01*
G37*
G36*
G01X1493908Y1471805D02*
G03I-491J0D01*
G37*
G36*
G01X1485246Y1485598D02*
G03I-491J0D01*
G37*
G36*
G01Y1496222D02*
G03I-491J0D01*
G37*
G36*
G01X1493908Y1487160D02*
G03I-491J0D01*
G37*
G36*
G01Y1491891D02*
G03I-491J0D01*
G37*
G36*
G01Y1496622D02*
G03I-491J0D01*
G37*
G36*
G01X1485246Y1491491D02*
G03I-491J0D01*
G37*
G36*
G01Y1506845D02*
G03I-491J0D01*
G37*
G36*
G01Y1500953D02*
G03I-491J0D01*
G37*
G36*
G01Y1511576D02*
G03I-491J0D01*
G37*
G36*
G01X1493908Y1507245D02*
G03I-491J0D01*
G37*
G36*
G01Y1502514D02*
G03I-491J0D01*
G37*
G36*
G01Y1511976D02*
G03I-491J0D01*
G37*
G36*
G01X1485246Y1516307D02*
G03I-491J0D01*
G37*
G36*
G01X1493908Y1558813D02*
G03I-491J0D01*
G37*
G36*
G01Y1578898D02*
G03I-491J0D01*
G37*
G36*
G01X1485246Y1563144D02*
G03I-491J0D01*
G37*
G36*
G01X1493908Y1563544D02*
G03I-491J0D01*
G37*
G36*
G01X1485246Y1567875D02*
G03I-491J0D01*
G37*
G36*
G01Y1578498D02*
G03I-491J0D01*
G37*
G36*
G01Y1572606D02*
G03I-491J0D01*
G37*
G36*
G01X1493908Y1568275D02*
G03I-491J0D01*
G37*
G36*
G01Y1574167D02*
G03I-491J0D01*
G37*
G36*
G01X1485246Y1583229D02*
G03I-491J0D01*
G37*
G36*
G01Y1593853D02*
G03I-491J0D01*
G37*
G36*
G01Y1587960D02*
G03I-491J0D01*
G37*
G36*
G01X1493908Y1583629D02*
G03I-491J0D01*
G37*
G36*
G01Y1589522D02*
G03I-491J0D01*
G37*
G36*
G01Y1594253D02*
G03I-491J0D01*
G37*
G36*
G01X1485246Y1609207D02*
G03I-491J0D01*
G37*
G36*
G01Y1598584D02*
G03I-491J0D01*
G37*
G36*
G01Y1603315D02*
G03I-491J0D01*
G37*
G36*
G01X1493908Y1609607D02*
G03I-491J0D01*
G37*
G36*
G01Y1604876D02*
G03I-491J0D01*
G37*
G36*
G01Y1598984D02*
G03I-491J0D01*
G37*
G36*
G01X1485246Y1613938D02*
G03I-491J0D01*
G37*
G36*
G01Y1618669D02*
G03I-491J0D01*
G37*
G36*
G01X1493908Y1614338D02*
G03I-491J0D01*
G37*
G36*
G01X1556202Y174205D02*
X1559754D01*
G02X1559894Y174148I0J-200D01*
G01X1559895Y174147D01*
X1562097Y171945D01*
G02X1562099Y171943I-140J-142D01*
G02X1562156Y171803I-143J-140D01*
G01Y147990D01*
G02X1562046Y147811I-200J0D01*
G01X1561728Y147650D01*
G02X1561518Y147668I-90J178D01*
G03X1560624Y147963I-894J-1207D01*
G03Y144959I0J-1502D01*
G03X1561518Y145254I0J1502D01*
G02X1561728Y145272I120J-160D01*
G01X1562046Y145111D01*
G02X1562156Y144932I-90J-179D01*
G01Y138227D01*
X1562083Y138124D01*
X1562023Y138103D01*
G03X1561322Y137587I502J-1416D01*
G01X1561301Y137559D01*
X1561214Y137501D01*
G02X1561147Y137473I-109J168D01*
G01X1561028Y137446D01*
X1560954Y137457D01*
X1560921Y137475D01*
G03X1560620Y137612I-894J-1565D01*
G03X1560029Y137712I-592J-1703D01*
G03X1559438Y137612I1J-1803D01*
G03X1559137Y137475I593J-1702D01*
G01X1559104Y137457D01*
X1559030Y137446D01*
X1558911Y137473D01*
G02X1558844Y137501I42J196D01*
G01X1558756Y137560D01*
X1558736Y137588D01*
G03X1557533Y138189I-1202J-901D01*
G01X1557490D01*
X1557489Y138188D01*
G03X1556031Y136687I44J-1501D01*
G03X1557533Y135185I1502J0D01*
G03X1557765Y135203I0J1502D01*
G01X1557808Y135210D01*
X1557892Y135186D01*
X1558190Y134932D01*
X1558226Y134853D01*
Y133610D01*
Y133565D01*
X1558190Y133486D01*
X1557892Y133232D01*
X1557808Y133208D01*
X1557765Y133215D01*
G03X1557530Y133233I-232J-1484D01*
G01X1557529D01*
G03X1556031Y131731I4J-1502D01*
G03X1557533Y130229I1502J0D01*
G01X1557534D01*
G03X1558736Y130830I0J1502D01*
G01X1558756Y130858D01*
X1558844Y130917D01*
G02X1558911Y130945I109J-168D01*
G01X1559030Y130972D01*
X1559104Y130961D01*
X1559137Y130943D01*
G03X1559438Y130806I894J1565D01*
G03X1560029Y130706I592J1703D01*
G03X1560620Y130806I-1J1803D01*
G03X1560921Y130943I-593J1702D01*
G01X1560954Y130961D01*
X1561028Y130972D01*
X1561147Y130945D01*
G02X1561214Y130917I-42J-196D01*
G01X1561301Y130859D01*
X1561322Y130831D01*
G03X1562023Y130315I1203J900D01*
G01X1562083Y130294D01*
X1562156Y130191D01*
Y124053D01*
X1562083Y123950D01*
X1562023Y123929D01*
G03X1561322Y123413I502J-1416D01*
G01X1561301Y123385D01*
X1561214Y123327D01*
G02X1561147Y123299I-109J168D01*
G01X1561028Y123272D01*
X1560954Y123283D01*
X1560921Y123301D01*
G03X1560620Y123438I-894J-1565D01*
G03X1560029Y123538I-592J-1703D01*
G03X1559438Y123438I1J-1803D01*
G03X1559137Y123301I593J-1702D01*
G01X1559104Y123283D01*
X1559030Y123272D01*
X1558911Y123299D01*
G02X1558844Y123327I42J196D01*
G01X1558756Y123386D01*
X1558736Y123414D01*
G03X1557533Y124015I-1202J-901D01*
G01X1557490D01*
X1557489Y124014D01*
G03X1556031Y122513I44J-1501D01*
G03X1557533Y121011I1502J0D01*
G03X1557765Y121029I0J1502D01*
G01X1557808Y121036D01*
X1557892Y121012D01*
X1558190Y120758D01*
X1558226Y120679D01*
Y119436D01*
Y119391D01*
X1558190Y119312D01*
X1557892Y119058D01*
X1557808Y119034D01*
X1557765Y119041D01*
G03X1557530Y119059I-232J-1484D01*
G01X1557529D01*
G03X1556031Y117557I4J-1502D01*
G03X1557533Y116055I1502J0D01*
G01X1557534D01*
G03X1558736Y116656I0J1502D01*
G01X1558756Y116684D01*
X1558844Y116743D01*
G02X1558911Y116771I109J-168D01*
G01X1559030Y116798D01*
X1559104Y116787D01*
X1559137Y116769D01*
G03X1559438Y116632I894J1565D01*
G03X1560029Y116532I592J1703D01*
G03X1560620Y116632I-1J1803D01*
G03X1560921Y116769I-593J1702D01*
G01X1560954Y116787D01*
X1561028Y116798D01*
X1561147Y116771D01*
G02X1561214Y116743I-42J-196D01*
G01X1561301Y116685D01*
X1561322Y116657D01*
G03X1562023Y116141I1203J900D01*
G01X1562083Y116120D01*
X1562156Y116017D01*
Y78102D01*
G02X1562130Y78003I-200J0D01*
G01X1562070Y77899D01*
X1562038Y77865D01*
X1562017Y77851D01*
G03X1561579Y77421I811J-1264D01*
G01X1561578Y77420D01*
Y77419D01*
G02X1561444Y77334I-165J113D01*
G01X1561155Y77288D01*
G02X1561001Y77327I-32J197D01*
G03X1560080Y77642I-920J-1187D01*
G01X1560050D01*
G03X1558578Y76140I30J-1502D01*
G03X1560080Y74638I1502J0D01*
G01X1560096D01*
X1560156Y74639D01*
X1560259Y74572D01*
X1560426Y74174D01*
G02X1560383Y73955I-184J-78D01*
G01X1558929Y72501D01*
X1558901Y72472D01*
X1558827Y72442D01*
X1512714D01*
G02X1512572Y72501I0J200D01*
G01X1511256Y73817D01*
X1511227Y73845D01*
X1511197Y73919D01*
Y100421D01*
G02X1511256Y100563I200J0D01*
G01X1511458Y100763D01*
G02X1511599Y100821I141J-142D01*
G01X1511610D01*
G03Y103825I0J1502D01*
G01X1511599D01*
G02X1511458Y103883I0J200D01*
G01X1511256Y104083D01*
G02X1511197Y104225I141J142D01*
G01Y107508D01*
G02X1511256Y107650I200J0D01*
G01X1511458Y107850D01*
G02X1511599Y107908I141J-142D01*
G01X1511610D01*
G03Y110912I0J1502D01*
G01X1511599D01*
G02X1511458Y110970I0J200D01*
G01X1511256Y111170D01*
G02X1511197Y111312I141J142D01*
G01Y114594D01*
G02X1511256Y114736I200J0D01*
G01X1511458Y114936D01*
G02X1511599Y114994I141J-142D01*
G01X1511610D01*
G03Y117998I0J1502D01*
G01X1511599D01*
G02X1511458Y118056I0J200D01*
G01X1511256Y118256D01*
G02X1511197Y118398I141J142D01*
G01Y121681D01*
G02X1511256Y121823I200J0D01*
G01X1511458Y122023D01*
G02X1511599Y122081I141J-142D01*
G01X1511610D01*
G03Y125085I0J1502D01*
G01X1511599D01*
G02X1511458Y125143I0J200D01*
G01X1511256Y125343D01*
G02X1511197Y125485I141J142D01*
G01Y128768D01*
G02X1511256Y128910I200J0D01*
G01X1511458Y129110D01*
G02X1511599Y129168I141J-142D01*
G01X1511610D01*
G03Y132172I0J1502D01*
G01X1511599D01*
G02X1511458Y132230I0J200D01*
G01X1511256Y132430D01*
G02X1511197Y132572I141J142D01*
G01Y135854D01*
G02X1511256Y135996I200J0D01*
G01X1511458Y136196D01*
G02X1511599Y136254I141J-142D01*
G01X1511610D01*
G03Y139258I0J1502D01*
G01X1511599D01*
G02X1511458Y139316I0J200D01*
G01X1511256Y139516D01*
G02X1511197Y139658I141J142D01*
G01Y172123D01*
G02X1511254Y172263I200J0D01*
G01X1511255Y172264D01*
X1513137Y174146D01*
G02X1513139Y174148I142J-140D01*
G02X1513279Y174205I140J-143D01*
G01X1553208D01*
G02X1553394Y174078I0J-200D01*
G01X1553553Y173673D01*
X1553526Y173554D01*
X1553480Y173512D01*
G03X1552903Y172190I1226J-1322D01*
G03X1556507I1802J0D01*
G03X1556496Y172390I-1802J1D01*
G01X1556497D01*
G03X1555930Y173512I-1792J-201D01*
G01X1555885Y173555D01*
X1555857Y173674D01*
X1556016Y174078D01*
G02X1556202Y174205I186J-73D01*
G37*
G36*
G01X1504912Y897979D02*
X1514451D01*
X1518439D01*
X1518510Y897908D01*
Y886347D01*
X1517142Y884979D01*
X1513618D01*
X1500117D01*
G02X1499975Y885038I0J200D01*
G01X1499093Y885920D01*
G02X1499034Y886062I141J142D01*
G01Y893570D01*
G02X1499099Y893718I200J0D01*
G03X1499580Y894961I-1015J1107D01*
G01X1500009Y895390D01*
Y895879D01*
X1500629Y896499D01*
X1503432D01*
X1504912Y897979D01*
G37*
G36*
G01X1507000Y932417D02*
Y920415D01*
X1505495Y918910D01*
X1504815Y918230D01*
X1503600Y917015D01*
Y915385D01*
X1502215Y914000D01*
X1502083D01*
X1501938Y913855D01*
X1499543D01*
X1498207Y915191D01*
Y916139D01*
X1499008Y916940D01*
X1499955D01*
X1501000Y917985D01*
Y932917D01*
G02X1501059Y933059I200J0D01*
G01X1501441Y933441D01*
G02X1501583Y933500I142J-141D01*
G01X1505917D01*
G02X1506059Y933441I0J-200D01*
G01X1506941Y932559D01*
G02X1507000Y932417I-141J-142D01*
G37*
G36*
G01X1515083Y936000D02*
X1517917D01*
G02X1518059Y935941I0J-200D01*
G01X1518441Y935559D01*
G02X1518500Y935417I-141J-142D01*
G01Y924921D01*
G02X1518465Y924809I-200J1D01*
G03Y922671I1572J-1069D01*
G02X1518500Y922559I-165J-113D01*
G01Y916583D01*
G02X1518441Y916441I-200J0D01*
G01X1517059Y915059D01*
G02X1516917Y915000I-142J141D01*
G01X1514583D01*
X1513584Y914001D01*
X1508702D01*
X1506321D01*
X1505691D01*
X1504791Y914901D01*
Y916649D01*
X1506686Y918544D01*
X1507148D01*
X1508823D01*
X1510086D01*
X1511861Y920319D01*
Y924740D01*
X1513500Y926379D01*
Y934417D01*
G02X1513559Y934559I200J0D01*
G01X1514941Y935941D01*
G02X1515083Y936000I142J-141D01*
G37*
G36*
G01X1514545Y950396D02*
G03I-590J0D01*
G37*
G36*
G01X1502569Y1460782D02*
G03I-491J0D01*
G37*
G36*
G01X1511231Y1456451D02*
G03I-491J0D01*
G37*
G36*
G01Y1461182D02*
G03I-491J0D01*
G37*
G36*
G01X1502569Y1465513D02*
G03I-491J0D01*
G37*
G36*
G01X1511231Y1465913D02*
G03I-491J0D01*
G37*
G36*
G01X1502569Y1476136D02*
G03I-491J0D01*
G37*
G36*
G01Y1470244D02*
G03I-491J0D01*
G37*
G36*
G01Y1480867D02*
G03I-491J0D01*
G37*
G36*
G01X1511231Y1471805D02*
G03I-491J0D01*
G37*
G36*
G01Y1476536D02*
G03I-491J0D01*
G37*
G36*
G01Y1481267D02*
G03I-491J0D01*
G37*
G36*
G01X1502569Y1485598D02*
G03I-491J0D01*
G37*
G36*
G01Y1496222D02*
G03I-491J0D01*
G37*
G36*
G01X1511231Y1487160D02*
G03I-491J0D01*
G37*
G36*
G01Y1491891D02*
G03I-491J0D01*
G37*
G36*
G01Y1496622D02*
G03I-491J0D01*
G37*
G36*
G01X1502569Y1491491D02*
G03I-491J0D01*
G37*
G36*
G01Y1506845D02*
G03I-491J0D01*
G37*
G36*
G01Y1500953D02*
G03I-491J0D01*
G37*
G36*
G01Y1511576D02*
G03I-491J0D01*
G37*
G36*
G01X1511231Y1507245D02*
G03I-491J0D01*
G37*
G36*
G01Y1502514D02*
G03I-491J0D01*
G37*
G36*
G01Y1511976D02*
G03I-491J0D01*
G37*
G36*
G01X1502569Y1516307D02*
G03I-491J0D01*
G37*
G36*
G01X1511231Y1558813D02*
G03I-491J0D01*
G37*
G36*
G01Y1574167D02*
G03I-491J0D01*
G37*
G36*
G01X1502569Y1567875D02*
G03I-491J0D01*
G37*
G36*
G01X1511231Y1578898D02*
G03I-491J0D01*
G37*
G36*
G01X1502569Y1578498D02*
G03I-491J0D01*
G37*
G36*
G01Y1572606D02*
G03I-491J0D01*
G37*
G36*
G01X1511231Y1568275D02*
G03I-491J0D01*
G37*
G36*
G01Y1563544D02*
G03I-491J0D01*
G37*
G36*
G01X1502569Y1563144D02*
G03I-491J0D01*
G37*
G36*
G01X1511231Y1594253D02*
G03I-491J0D01*
G37*
G36*
G01X1502569Y1583229D02*
G03I-491J0D01*
G37*
G36*
G01Y1593853D02*
G03I-491J0D01*
G37*
G36*
G01Y1587960D02*
G03I-491J0D01*
G37*
G36*
G01X1511231Y1583629D02*
G03I-491J0D01*
G37*
G36*
G01Y1589522D02*
G03I-491J0D01*
G37*
G36*
G01Y1604876D02*
G03I-491J0D01*
G37*
G36*
G01Y1598984D02*
G03I-491J0D01*
G37*
G36*
G01X1502569Y1609207D02*
G03I-491J0D01*
G37*
G36*
G01Y1598584D02*
G03I-491J0D01*
G37*
G36*
G01Y1603315D02*
G03I-491J0D01*
G37*
G36*
G01X1511231Y1609607D02*
G03I-491J0D01*
G37*
G36*
G01X1502569Y1613938D02*
G03I-491J0D01*
G37*
G36*
G01Y1618669D02*
G03I-491J0D01*
G37*
G36*
G01X1511231Y1614338D02*
G03I-491J0D01*
G37*
G36*
G01X1793246Y984660D02*
X1798680D01*
G02X1798822Y984601I0J-200D01*
G01X1799104Y984319D01*
G02X1799163Y984177I-141J-142D01*
G01Y971836D01*
G03X1799222Y971694I200J0D01*
G01X1799231Y971685D01*
X1799262Y971611D01*
Y961928D01*
G03X1799320Y961787I200J0D01*
G01X1800390Y960717D01*
G03X1800531Y960658I142J141D01*
G01X1810175D01*
G02X1810316Y960600I0J-200D01*
G01X1817576Y953340D01*
G02X1817635Y953198I-141J-142D01*
G01Y536229D01*
X1817605Y536155D01*
X1817576Y536127D01*
X1797586Y516137D01*
G02X1797444Y516078I-142J141D01*
G01X1696257D01*
X1696157Y516144D01*
X1696133Y516200D01*
G03X1694749Y517119I-1384J-583D01*
G03X1693546Y516516I0J-1502D01*
G01X1693525Y516488D01*
X1693441Y516432D01*
G02X1693382Y516406I-109J168D01*
G02X1693372Y516403I-62J190D01*
G01X1693302Y516387D01*
G02X1693207Y516389I-43J195D01*
G01X1693146Y516405D01*
X1693124Y516417D01*
G03X1692253Y516642I-872J-1578D01*
G03X1691382Y516417I1J-1803D01*
G01X1691360Y516405D01*
X1691299Y516389D01*
G02X1691204Y516387I-52J193D01*
G01X1691134Y516403D01*
G02X1691124Y516406I52J193D01*
G02X1691065Y516432I50J194D01*
G01X1690981Y516488D01*
X1690960Y516516D01*
G03X1689757Y517119I-1203J-899D01*
G03X1688373Y516200I0J-1502D01*
G01X1688349Y516144D01*
X1688249Y516078D01*
X1646469D01*
X1646450Y516082D01*
G03X1646160Y516110I-289J-1474D01*
G01X1646154D01*
G03X1645866Y516082I1J-1502D01*
G01X1645847Y516078D01*
X1636731D01*
G02X1636653Y516094I0J200D01*
G01X1636549Y516138D01*
X1636522Y516164D01*
G03X1634008I-1257J-1292D01*
G01X1633981Y516138D01*
X1633877Y516094D01*
G02X1633799Y516078I-78J184D01*
G01X1619641D01*
X1619567Y516108D01*
X1619539Y516137D01*
X1608653Y527023D01*
G02X1608594Y527164I141J142D01*
G01Y633071D01*
G02X1608653Y633213I200J0D01*
G01X1629818Y654378D01*
G03X1630628Y656334I-1957J1956D01*
G01Y656851D01*
G02X1630687Y656992I200J-1D01*
G01X1635063Y661368D01*
G03X1635866Y663307I-1940J1939D01*
G01Y667842D01*
G02X1635925Y667983I200J-1D01*
G01X1765502Y797561D01*
G03X1766312Y799517I-1957J1956D01*
G01Y820518D01*
G03X1765502Y822474I-2767J0D01*
G01X1762940Y825036D01*
G03X1761653Y825764I-1956J-1956D01*
G02X1761643Y825767I53J193D01*
G03X1760851Y825884I-792J-2625D01*
G01X1758848D01*
G02X1758754Y825907I-1J200D01*
G01X1758676Y825949D01*
G02X1758640Y825973I92J178D01*
G01X1758623Y825988D01*
X1758609Y826006D01*
X1758608Y826008D01*
G03X1757402Y826613I-1206J-900D01*
G03X1756807Y826490I0J-1501D01*
G02X1756605Y826516I-79J184D01*
G03X1755415Y827052I-1699J-2183D01*
G01X1755360Y827063D01*
X1755278Y827136D01*
X1755157Y827528D01*
G02X1755206Y827728I191J59D01*
G01X1762083Y834605D01*
G03X1762142Y834747I-141J142D01*
G01Y835972D01*
G03X1762146Y836124I-2762J149D01*
G01Y863574D01*
X1762232Y863683D01*
X1762300Y863699D01*
G03Y866621I-347J1461D01*
G01X1762232Y866637D01*
X1762146Y866746D01*
Y904178D01*
G02X1762183Y904294I200J0D01*
G03X1762686Y905885I-2263J1591D01*
G01Y907475D01*
G03X1762391Y908720I-2766J2D01*
G02Y908900I178J90D01*
G03X1762686Y910145I-2471J1243D01*
G01Y911735D01*
G03X1762391Y912980I-2766J2D01*
G02Y913160I178J90D01*
G03X1762686Y914405I-2471J1243D01*
G01Y915995D01*
G03X1762183Y917586I-2766J0D01*
G02X1762146Y917702I163J116D01*
G01Y926519D01*
G02X1762205Y926661I200J0D01*
G01X1762229Y926685D01*
G02X1762371Y926744I142J-141D01*
G01X1763854D01*
G02X1764054Y926544I-1J-201D01*
G01Y926109D01*
G02X1763995Y925967I-200J0D01*
G01X1763708Y925680D01*
G03X1762898Y923724I1957J-1956D01*
G03X1765664Y920958I2766J0D01*
G03X1767249Y921457I0J2767D01*
G02X1767479I115J-164D01*
G03X1769064Y920958I1585J2268D01*
G03X1771830Y923724I0J2766D01*
G03X1771020Y925680I-2767J0D01*
G01X1770725Y925975D01*
G02X1770666Y926117I141J142D01*
G01Y928575D01*
G03X1769856Y930531I-2767J0D01*
G01X1767841Y932546D01*
G03X1765885Y933356I-1956J-1957D01*
G01X1760694D01*
G03X1760339Y933334I-7J-2766D01*
G01X1760326Y933332D01*
X1759641D01*
G03X1759499Y933273I0J-200D01*
G01X1759014Y932788D01*
X1759004Y932780D01*
G03X1758738Y932546I1690J-2190D01*
G01X1756344Y930152D01*
G03X1756110Y929886I1956J-1956D01*
G01X1756102Y929876D01*
X1755687Y929461D01*
G03X1755628Y929319I141J-142D01*
G01Y928913D01*
X1755622Y928889D01*
G03X1755534Y928196I2678J-692D01*
G01Y837801D01*
G02X1755475Y837659I-200J0D01*
G01X1748264Y830448D01*
G03X1747877Y829963I1955J-1957D01*
G01X1747865Y829944D01*
X1747687Y829766D01*
G03X1747628Y829624I141J-142D01*
G01Y829460D01*
X1747616Y829427D01*
G03X1747454Y828492I2604J-933D01*
G01Y795021D01*
G02X1747395Y794879I-200J0D01*
G01X1619145Y666630D01*
G02X1618888Y666608I-142J141D01*
G03X1617843Y666942I-1045J-1468D01*
G03X1616041Y665140I0J-1802D01*
G03X1616133Y664572I1802J0D01*
G01X1616148Y664526D01*
X1616133Y664431D01*
X1615915Y664129D01*
G02X1615753Y664046I-162J117D01*
G01X1602827D01*
G03X1602685Y663987I0J-200D01*
G01X1600936Y662238D01*
G02X1600794Y662179I-142J141D01*
G01X1597234D01*
X1597160Y662209D01*
X1597132Y662238D01*
X1593122Y666248D01*
G02X1593063Y666390I141J142D01*
G01Y714057D01*
G03X1593004Y714199I-200J0D01*
G01X1589585Y717618D01*
G03X1589443Y717677I-142J-141D01*
G01X1526518D01*
X1526444Y717707D01*
X1526416Y717736D01*
X1521567Y722585D01*
G02X1521508Y722727I141J142D01*
G01Y744026D01*
G02X1521708Y744226I200J0D01*
G01X1603351D01*
G02X1603492Y744167I-1J-200D01*
G01X1609250Y738409D01*
G03X1610142Y738040I891J892D01*
G01X1618533D01*
X1618607Y738009D01*
X1618632Y737984D01*
G03X1620100Y736798I1468J316D01*
G03X1620422Y736833I0J1502D01*
G01X1620467Y736843D01*
X1620554Y736822D01*
X1620833Y736598D01*
G02X1620908Y736442I-125J-156D01*
G01Y732658D01*
G02X1620849Y732517I-200J1D01*
G01X1612079Y723747D01*
G02X1611938Y723688I-142J141D01*
G01X1611872D01*
X1611820Y723703D01*
X1611797Y723717D01*
G03X1611027Y723929I-769J-1290D01*
G03Y720925I0J-1502D01*
G03X1611797Y721137I1J1502D01*
G02X1611899Y721166I104J-171D01*
G01X1612543D01*
G03X1613435Y721535I1J1261D01*
G01X1616854Y724954D01*
G02X1617072Y724998I142J-141D01*
G01X1617129Y724974D01*
X1617196Y724874D01*
Y708043D01*
G03X1617565Y707151I1261J-1D01*
G01X1619110Y705606D01*
X1619137Y705559D01*
X1619144Y705532D01*
G03X1620600Y704398I1456J368D01*
G03X1622102Y705900I0J1502D01*
G03X1620968Y707356I-1502J0D01*
G01X1620941Y707363D01*
X1620894Y707390D01*
X1619777Y708507D01*
G02X1619718Y708648I141J142D01*
G01Y721337D01*
G02X1619792Y721492I200J0D01*
G01X1620068Y721717D01*
X1620154Y721738D01*
X1620199Y721729D01*
G03X1620500Y721698I304J1471D01*
G03X1621956Y722832I0J1502D01*
G01X1621963Y722859D01*
X1621990Y722906D01*
X1626380Y727296D01*
G03X1626750Y728188I-892J893D01*
G01Y745807D01*
G02X1626863Y745988I200J1D01*
G01X1627241Y746168D01*
X1627355Y746155D01*
X1627400Y746119D01*
G03X1628343Y745786I943J1169D01*
G03Y748790I0J1502D01*
G03X1627400Y748457I0J-1502D01*
G01X1627355Y748421D01*
X1627241Y748408D01*
X1626863Y748588D01*
G02X1626750Y748769I87J180D01*
G01Y750203D01*
G03X1626380Y751095I-1262J-1D01*
G01X1622847Y754628D01*
G02X1622788Y754770I141J142D01*
G01Y759180D01*
G02X1622881Y759349I200J0D01*
G01X1623210Y759558D01*
X1623312Y759564D01*
X1623359Y759542D01*
G03X1624000Y759398I642J1358D01*
G03Y762402I0J1502D01*
G03X1623359Y762258I1J-1502D01*
G01X1623312Y762236D01*
X1623210Y762242D01*
X1622881Y762451D01*
G02X1622788Y762620I107J169D01*
G01Y766817D01*
G03X1622729Y766959I-200J0D01*
G01X1622249Y767439D01*
G02X1622190Y767580I141J142D01*
G01Y770138D01*
G03X1621821Y771030I-1261J1D01*
G01X1618943Y773908D01*
G02X1618884Y774049I141J142D01*
G01Y813704D01*
G03X1618515Y814596I-1261J1D01*
G01X1613054Y820057D01*
G03X1612162Y820426I-891J-892D01*
G01X1608077D01*
G02X1607941Y820480I1J200D01*
G03X1606709Y820967I-1232J-1315D01*
G03Y817363I0J-1802D01*
G03X1607941Y817850I0J1802D01*
G02X1608077Y817904I137J-146D01*
G01X1611557D01*
G02X1611698Y817845I-1J-200D01*
G01X1616303Y813240D01*
G02X1616362Y813099I-141J-142D01*
G01Y801949D01*
G02X1616238Y801764I-200J0D01*
G01X1616181Y801741D01*
X1616064Y801764D01*
X1613162Y804666D01*
G03X1612270Y805036I-893J-892D01*
G01X1607558D01*
G02X1607422Y805089I0J200D01*
G03X1606190Y805576I-1232J-1315D01*
G03Y801972I0J-1802D01*
G03X1607422Y802459I0J1802D01*
G02X1607558Y802512I136J-147D01*
G01X1611665D01*
G02X1611806Y802454I0J-200D01*
G01X1614283Y799977D01*
G02X1614342Y799836I-141J-142D01*
G01Y799723D01*
G02X1614218Y799538I-200J0D01*
G01X1614161Y799515D01*
X1614044Y799538D01*
X1612976Y800606D01*
G03X1612084Y800976I-893J-892D01*
G01X1550604D01*
G02X1550463Y801034I0J200D01*
G01X1521567Y829930D01*
G02X1521508Y830072I141J142D01*
G01Y872223D01*
G02X1521567Y872365I200J0D01*
G01X1531446Y882244D01*
G03X1531505Y882386I-141J142D01*
G01Y896430D01*
G02X1531564Y896572I200J0D01*
G01X1539990Y904998D01*
G02X1540131Y905056I141J-142D01*
G01X1543498D01*
G02X1543639Y904998I0J-200D01*
G01X1545842Y902795D01*
X1545870Y902743D01*
X1545875Y902714D01*
G03X1547644Y901258I1769J347D01*
G03X1549446Y903060I0J1802D01*
G03X1547990Y904829I-1803J0D01*
G01X1547961Y904834D01*
X1547909Y904862D01*
X1546334Y906437D01*
G02X1546277Y906599I142J141D01*
G01X1546314Y906953D01*
X1546361Y907030D01*
X1546399Y907055D01*
G03X1546637Y907248I-796J1225D01*
G01X1548345Y908955D01*
X1548397Y908983D01*
X1548426Y908988D01*
G03X1549882Y910757I-347J1769D01*
G03X1548080Y912559I-1802J0D01*
G03X1546311Y911103I0J-1803D01*
G01X1546306Y911074D01*
X1546278Y911022D01*
X1545057Y909801D01*
G02X1544916Y909742I-142J141D01*
G01X1537511D01*
G02X1537326Y909866I0J200D01*
G01X1537303Y909923D01*
X1537326Y910040D01*
X1542130Y914844D01*
G03X1542500Y915736I-892J893D01*
G01Y929027D01*
G02X1542623Y929212I200J0D01*
G01X1542680Y929235D01*
X1542797Y929212D01*
X1547184Y924825D01*
G02X1547242Y924684I-142J-141D01*
G01Y916561D01*
G02X1547214Y916459I-200J0D01*
G03X1547002Y915689I1290J-769D01*
G03X1550006I1502J0D01*
G03X1549794Y916459I-1502J1D01*
G02X1549766Y916561I172J102D01*
G01Y925289D01*
G03X1549396Y926181I-1262J-1D01*
G01X1549350Y926227D01*
G02Y926510I141J141D01*
G01X1549368Y926528D01*
X1549390Y926541D01*
G03X1550131Y927836I-761J1295D01*
G03X1548997Y929292I-1502J0D01*
G01X1548970Y929299D01*
X1548923Y929326D01*
X1548779Y929470D01*
G02X1548728Y929666I141J141D01*
G01X1548837Y930055D01*
X1548914Y930129D01*
X1548968Y930142D01*
G03X1550118Y931602I-352J1460D01*
G03X1548984Y933058I-1502J0D01*
G01X1548957Y933065D01*
X1548910Y933092D01*
X1545918Y936084D01*
G02X1545860Y936225I142J141D01*
G01Y962939D01*
G02X1545918Y963080I200J0D01*
G01X1551285Y968447D01*
X1551400Y968472D01*
X1551457Y968450D01*
G03X1552000Y968348I544J1400D01*
G03X1553267Y969044I0J1501D01*
G02X1553294Y969078I169J-107D01*
G01X1556349Y972132D01*
G02X1556490Y972190I141J-142D01*
G01X1769202D01*
G03X1769724Y972287I-2J1462D01*
G01X1769758Y972300D01*
X1791617D01*
G03X1791759Y972359I0J200D01*
G01X1792504Y973104D01*
G03X1792563Y973246I-141J142D01*
G01Y983977D01*
G02X1792622Y984119I200J0D01*
G01X1793104Y984601D01*
G02X1793246Y984660I142J-141D01*
G37*
G36*
G01X1535044Y950024D02*
G03X1535146Y950029I-42J1901D01*
G01X1535188Y950032D01*
X1535266Y950005D01*
X1535512Y949777D01*
G02X1535576Y949630I-136J-147D01*
G01Y932720D01*
G02X1535512Y932573I-200J0D01*
G01X1535266Y932345D01*
X1535188Y932318D01*
X1535146Y932321D01*
G03X1535000Y932326I-138J-1896D01*
G01X1530359D01*
G02X1530218Y932385I1J200D01*
G01X1528612Y933992D01*
G03X1527267Y934548I-1344J-1346D01*
G03X1525366Y932647I0J-1901D01*
G03X1525922Y931302I1902J-1D01*
G01X1528144Y929080D01*
G03X1529489Y928524I1344J1346D01*
G01X1535000D01*
G03X1535146Y928529I8J1901D01*
G01X1535188Y928532D01*
X1535266Y928505D01*
X1535512Y928277D01*
G02X1535576Y928130I-136J-147D01*
G01Y918758D01*
G02X1535518Y918617I-200J0D01*
G01X1529133Y912232D01*
G02X1528850I-141J141D01*
G01X1524344Y916738D01*
G02X1524300Y916956I141J142D01*
G01X1524324Y917013D01*
X1524424Y917080D01*
X1524875D01*
X1524944Y917052D01*
X1524973Y917025D01*
G03X1526206Y916538I1233J1317D01*
G03Y920144I0J1803D01*
G03X1524975Y919659I0J-1805D01*
G01X1524948Y919634D01*
X1524909Y919617D01*
G02X1524833Y919602I-76J185D01*
G01X1522936D01*
G02X1522834Y919763I98J175D01*
G01Y920290D01*
G02X1522838Y920329I200J-1D01*
G01X1522846Y920367D01*
X1522856Y920401D01*
X1522859Y920408D01*
G03X1522930Y920633I-1774J684D01*
G03X1522986Y921093I-1845J458D01*
G01X1522987Y921117D01*
G03X1521650Y922910I-1902J-23D01*
G01X1521649D01*
G02X1521508Y923101I59J191D01*
G01Y932138D01*
G02X1521708Y932338I200J0D01*
G01X1522837D01*
X1523963D01*
G03X1524464Y932840I0J501D01*
G01Y935617D01*
X1524465Y935640D01*
G03X1524342Y935969I-502J0D01*
G02X1524308Y936024I151J131D01*
G01X1524279Y936093D01*
G02X1524264Y936169I185J76D01*
G01Y937692D01*
G03X1524148Y938348I-1901J2D01*
G03X1523708Y939037I-1785J-655D01*
G01X1523554Y939191D01*
G03X1523279Y939418I-1343J-1347D01*
G03X1523097Y939527I-1066J-1574D01*
G01X1523076Y939539D01*
X1523042Y939568D01*
X1523028Y939588D01*
G02X1522993Y939674I163J116D01*
G01X1522945Y939992D01*
G02X1523001Y940163I198J30D01*
G01X1523643Y940805D01*
G02X1523785Y940864I142J-141D01*
G01X1528072D01*
G03X1528214Y940923I0J200D01*
G01X1531660Y944369D01*
G03X1531719Y944511I-141J142D01*
G01Y948798D01*
G02X1531778Y948940I200J0D01*
G01X1532803Y949965D01*
G02X1532944Y950024I142J-141D01*
G01X1535044D01*
G37*
G36*
G01X1514944Y938811D02*
G03I-590J0D01*
G37*
G36*
G01X1524646Y980281D02*
G03I-680J0D01*
G37*
G36*
G01X1528553Y1461182D02*
G03I-491J0D01*
G37*
G36*
G01X1519892Y1460782D02*
G03I-491J0D01*
G37*
G36*
G01X1528553Y1456451D02*
G03I-491J0D01*
G37*
G36*
G01Y1481267D02*
G03I-491J0D01*
G37*
G36*
G01X1519892Y1465513D02*
G03I-491J0D01*
G37*
G36*
G01X1528553Y1465913D02*
G03I-491J0D01*
G37*
G36*
G01X1519892Y1476136D02*
G03I-491J0D01*
G37*
G36*
G01Y1470244D02*
G03I-491J0D01*
G37*
G36*
G01Y1480867D02*
G03I-491J0D01*
G37*
G36*
G01X1528553Y1471805D02*
G03I-491J0D01*
G37*
G36*
G01Y1476536D02*
G03I-491J0D01*
G37*
G36*
G01X1519892Y1491491D02*
G03I-491J0D01*
G37*
G36*
G01Y1485598D02*
G03I-491J0D01*
G37*
G36*
G01Y1496222D02*
G03I-491J0D01*
G37*
G36*
G01X1528553Y1487160D02*
G03I-491J0D01*
G37*
G36*
G01Y1491891D02*
G03I-491J0D01*
G37*
G36*
G01Y1496622D02*
G03I-491J0D01*
G37*
G36*
G01X1519892Y1506845D02*
G03I-491J0D01*
G37*
G36*
G01Y1500953D02*
G03I-491J0D01*
G37*
G36*
G01Y1511576D02*
G03I-491J0D01*
G37*
G36*
G01X1528553Y1507245D02*
G03I-491J0D01*
G37*
G36*
G01Y1502514D02*
G03I-491J0D01*
G37*
G36*
G01Y1511976D02*
G03I-491J0D01*
G37*
G36*
G01X1519892Y1516307D02*
G03I-491J0D01*
G37*
G36*
G01X1528553Y1558813D02*
G03I-491J0D01*
G37*
G36*
G01X1519892Y1567875D02*
G03I-491J0D01*
G37*
G36*
G01Y1578498D02*
G03I-491J0D01*
G37*
G36*
G01Y1572606D02*
G03I-491J0D01*
G37*
G36*
G01X1528553Y1578898D02*
G03I-491J0D01*
G37*
G36*
G01X1519892Y1563144D02*
G03I-491J0D01*
G37*
G36*
G01X1528553Y1563544D02*
G03I-491J0D01*
G37*
G36*
G01Y1568275D02*
G03I-491J0D01*
G37*
G36*
G01Y1574167D02*
G03I-491J0D01*
G37*
G36*
G01X1519892Y1587960D02*
G03I-491J0D01*
G37*
G36*
G01X1528553Y1583629D02*
G03I-491J0D01*
G37*
G36*
G01Y1589522D02*
G03I-491J0D01*
G37*
G36*
G01Y1594253D02*
G03I-491J0D01*
G37*
G36*
G01X1519892Y1583229D02*
G03I-491J0D01*
G37*
G36*
G01Y1593853D02*
G03I-491J0D01*
G37*
G36*
G01X1528553Y1609607D02*
G03I-491J0D01*
G37*
G36*
G01Y1604876D02*
G03I-491J0D01*
G37*
G36*
G01Y1598984D02*
G03I-491J0D01*
G37*
G36*
G01X1519892Y1609207D02*
G03I-491J0D01*
G37*
G36*
G01Y1598584D02*
G03I-491J0D01*
G37*
G36*
G01Y1603315D02*
G03I-491J0D01*
G37*
G36*
G01Y1618669D02*
G03I-491J0D01*
G37*
G36*
G01X1528553Y1614338D02*
G03I-491J0D01*
G37*
G36*
G01X1519892Y1613938D02*
G03I-491J0D01*
G37*
G36*
G01X1611280Y54588D02*
X1639405D01*
X1639599Y54394D01*
Y52785D01*
X1639405Y52591D01*
X1611280D01*
G03X1605343Y46654I0J-5937D01*
G01Y7874D01*
G02X1599469Y2000I-5874J0D01*
G01X1552224D01*
G02X1546350Y7874I0J5874D01*
G01Y46654D01*
G03X1545263Y50079I-5939J0D01*
G01Y50191D01*
X1545272Y50200D01*
X1547511D01*
G02X1548348Y46654I-7097J-3547D01*
G01Y7874D01*
G03X1552224Y3998I3876J0D01*
G01X1599469D01*
G03X1603346Y7874I0J3877D01*
G01Y46654D01*
G02X1611280Y54588I7934J0D01*
G37*
G36*
G01X1556699Y1141870D02*
X1556557Y1141788D01*
X1556449Y1141725D01*
G02X1556348Y1141698I-100J173D01*
G01X1556296D01*
X1556248Y1141727D01*
G03X1555611Y1141901I-637J-1078D01*
G01X1555582D01*
G03X1554358Y1140649I28J-1252D01*
G03X1555610Y1139397I1252J0D01*
G01X1555611D01*
G03X1556248Y1139571I0J1252D01*
G02X1556352Y1139600I104J-171D01*
G01X1556402D01*
X1556525Y1139529D01*
X1556687Y1139436D01*
X1556701Y1139428D01*
G02X1556771Y1139357I-103J-172D01*
G01X1556785Y1139329D01*
G02X1556798Y1139280I-186J-75D01*
G02X1556799Y1139255I-199J-20D01*
G01Y1138303D01*
G02X1556699Y1138130I-200J0D01*
G01X1556557Y1138048D01*
X1556449Y1137985D01*
G02X1556348Y1137958I-100J173D01*
G01X1556296D01*
X1556248Y1137987D01*
G03X1555611Y1138161I-637J-1078D01*
G01X1555582D01*
G03X1554358Y1136909I28J-1252D01*
G03X1554965Y1135836I1252J0D01*
G02X1555062Y1135665I-103J-171D01*
G01Y1134413D01*
G02X1554965Y1134242I-200J0D01*
G03X1554358Y1133169I645J-1073D01*
G03X1555610Y1131917I1252J0D01*
G01X1555611D01*
G03X1556248Y1132091I0J1252D01*
G02X1556352Y1132120I104J-171D01*
G01X1556402D01*
X1556525Y1132049D01*
X1556687Y1131956D01*
X1556701Y1131948D01*
G02X1556771Y1131877I-103J-172D01*
G01X1556785Y1131849D01*
G02X1556798Y1131800I-186J-75D01*
G02X1556799Y1131775I-199J-20D01*
G01Y1130823D01*
G02X1556699Y1130650I-200J0D01*
G01X1556557Y1130568D01*
X1556449Y1130505D01*
G02X1556348Y1130478I-100J173D01*
G01X1556296D01*
X1556248Y1130507D01*
G03X1555611Y1130681I-637J-1078D01*
G01X1555582D01*
G03X1554358Y1129429I28J-1252D01*
G03X1555610Y1128177I1252J0D01*
G01X1555611D01*
G03X1556248Y1128351I0J1252D01*
G02X1556352Y1128380I104J-171D01*
G01X1556402D01*
X1556525Y1128309D01*
X1556687Y1128216D01*
X1556701Y1128208D01*
G02X1556771Y1128137I-103J-172D01*
G01X1556785Y1128109D01*
G02X1556798Y1128060I-186J-75D01*
G02X1556799Y1128035I-199J-20D01*
G01Y1127082D01*
G02X1556699Y1126909I-200J0D01*
G01X1556557Y1126827D01*
X1556449Y1126764D01*
G02X1556348Y1126737I-100J173D01*
G01X1556296D01*
X1556248Y1126766D01*
G03X1555611Y1126940I-637J-1078D01*
G01X1555582D01*
G03X1554358Y1125688I28J-1252D01*
G03X1555610Y1124436I1252J0D01*
G01X1555611D01*
G03X1556248Y1124610I0J1252D01*
G02X1556352Y1124639I104J-171D01*
G01X1556402D01*
X1556525Y1124568D01*
X1556687Y1124475D01*
X1556701Y1124467D01*
G02X1556771Y1124396I-103J-172D01*
G01X1556785Y1124368D01*
G02X1556798Y1124319I-186J-75D01*
G02X1556799Y1124294I-199J-20D01*
G01Y1123537D01*
G03X1556858Y1123395I200J0D01*
G01X1556973Y1123280D01*
G02X1557027Y1123173I-143J-139D01*
G02X1557030Y1123140I-197J-35D01*
G01Y1122735D01*
Y1122721D01*
G02X1556900Y1122547I-200J14D01*
G01X1556886Y1122543D01*
G02X1556759Y1122547I-58J192D01*
G01X1556730Y1122558D01*
X1556681Y1122598D01*
X1556662Y1122627D01*
Y1122628D01*
G03X1555610Y1123200I-1052J-681D01*
G03Y1120696I0J-1252D01*
G01X1555611D01*
G03X1556360Y1120945I0J1252D01*
G01X1556386Y1120964D01*
X1556505Y1121005D01*
G02X1556594Y1120985I2J-200D01*
G01X1556720Y1120924D01*
X1556722D01*
X1556929Y1120822D01*
G02X1557026Y1120686I-99J-174D01*
G02X1557030Y1120648I-196J-40D01*
G01Y1119508D01*
G02X1557026Y1119470I-200J2D01*
G02X1556929Y1119334I-196J38D01*
G01X1556722Y1119232D01*
X1556720D01*
X1556594Y1119171D01*
G02X1556505Y1119151I-87J180D01*
G01X1556414Y1119182D01*
G02X1556359Y1119211I65J189D01*
G03X1555610Y1119460I-749J-1003D01*
G03Y1116956I0J-1252D01*
G03X1556652Y1117513I0J1253D01*
G01X1556664Y1117532D01*
G02X1556874Y1117616I166J-111D01*
G01X1556920Y1117603D01*
X1556951Y1117593D01*
X1556990Y1117541D01*
G02X1557030Y1117421I-160J-120D01*
G01Y1117158D01*
G02X1556985Y1117032I-200J0D01*
G02X1556972Y1117017I-157J123D01*
G01X1555733Y1115778D01*
G02X1555671Y1115736I-141J142D01*
G01X1555635Y1115720D01*
X1555595D01*
G03X1554396Y1114775I15J-1252D01*
G02X1554384Y1114741I-194J49D01*
G02X1554202Y1114624I-182J83D01*
G01X1553278D01*
G02X1553096Y1114741I0J200D01*
G02X1553084Y1114775I182J83D01*
G03X1550656I-1214J-307D01*
G02X1550644Y1114741I-194J49D01*
G02X1550462Y1114624I-182J83D01*
G01X1549538D01*
G02X1549356Y1114741I0J200D01*
G02X1549344Y1114775I182J83D01*
G03X1546916I-1214J-307D01*
G02X1546904Y1114741I-194J49D01*
G02X1546722Y1114624I-182J83D01*
G01X1545796D01*
G02X1545603Y1114775I1J200D01*
G03X1543175I-1214J-307D01*
G02X1542982Y1114624I-194J49D01*
G01X1542048D01*
G02X1541972Y1114639I0J200D01*
G01X1541946Y1114650D01*
G03X1541885Y1114664I-75J-185D01*
G03X1540649Y1115720I-1236J-195D01*
G03X1539445Y1114810I0J-1251D01*
G01X1539427Y1114746D01*
X1539320Y1114665D01*
X1538306D01*
G02X1538194Y1114700I1J200D01*
G01X1538186Y1114706D01*
G02X1538137Y1114757I117J162D01*
G01X1538123Y1114778D01*
X1538113Y1114811D01*
G03X1535705I-1204J-342D01*
G01X1535695Y1114778D01*
X1535681Y1114757D01*
G02X1535632Y1114706I-166J111D01*
G01X1535624Y1114700D01*
G02X1535512Y1114665I-113J165D01*
G01X1534566D01*
G02X1534454Y1114700I1J200D01*
G01X1534446Y1114706D01*
G02X1534397Y1114757I117J162D01*
G01X1534383Y1114778D01*
X1534373Y1114811D01*
G03X1533169Y1115720I-1204J-343D01*
G03X1532244Y1115312I0J-1253D01*
G01X1532241Y1115308D01*
X1532236Y1115303D01*
G02X1531956Y1115304I-139J144D01*
G01X1531955Y1115305D01*
X1531818Y1115442D01*
G02X1531774Y1115509I142J141D01*
G01X1531760Y1115543D01*
Y1122350D01*
G02X1531763Y1122383I200J-2D01*
G02X1531817Y1122490I197J-32D01*
G01X1532224Y1122897D01*
G02X1532348Y1122955I142J-141D01*
G01X1532386D01*
G03X1532506Y1122948I130J1195D01*
G01X1534866D01*
G02X1534978Y1122913I-1J-200D01*
G03X1535655Y1122704I677J993D01*
G01X1538949D01*
X1538951D01*
G03X1539014Y1122705I12J1201D01*
G01X1539061Y1122708D01*
X1539147Y1122671D01*
X1539415Y1122355D01*
X1539438Y1122264D01*
X1539437Y1122260D01*
G03X1539397Y1121948I1211J-314D01*
G03X1540649Y1123200I1252J0D01*
G03X1540473Y1123187I4J-1252D01*
G01X1540471D01*
X1540421Y1123180D01*
X1540371Y1123199D01*
X1540369Y1123200D01*
G02X1540295Y1123252I75J185D01*
G01X1540149Y1123438D01*
G02X1540113Y1123610I158J123D01*
G03X1540149Y1123887I-1165J292D01*
G01X1540203Y1123941D01*
G03X1540262Y1124083I-141J142D01*
G01Y1127726D01*
G02X1540320Y1127867I200J0D01*
G01X1540353Y1127900D01*
X1540521Y1128069D01*
G02X1540586Y1128112I141J-142D01*
G01X1540616Y1128125D01*
X1540659Y1128126D01*
X1540660D01*
G03X1541951Y1129428I-11J1302D01*
G03X1541737Y1130143I-1301J0D01*
G01X1541720Y1130169D01*
X1541712Y1130195D01*
G02X1541704Y1130252I192J56D01*
G01Y1130621D01*
G03X1541645Y1130763I-200J0D01*
G01X1537997Y1134411D01*
G03X1537855Y1134470I-142J-141D01*
G01X1533904D01*
G02X1533704Y1134670I0J200D01*
G01Y1136060D01*
G02X1533707Y1136093I200J-2D01*
G02X1533761Y1136200I197J-32D01*
G01X1534080Y1136519D01*
G02X1534187Y1136573I139J-143D01*
G02X1534220Y1136576I35J-197D01*
G01X1535558D01*
G02X1535671Y1136541I0J-200D01*
G01X1535693Y1136526D01*
X1535732Y1136478D01*
X1535744Y1136449D01*
G03X1538074I1165J461D01*
G01Y1136450D01*
G02X1538148Y1136542I186J-74D01*
G01X1538172Y1136559D01*
X1538229Y1136576D01*
X1539244D01*
G02X1539412Y1136484I0J-200D01*
G01X1539430Y1136447D01*
X1539433Y1136439D01*
G03X1540649Y1135604I1216J468D01*
G01X1544389D01*
G03Y1138210I0J1303D01*
G01X1541904D01*
G02X1541704Y1138410I0J200D01*
G01Y1139824D01*
G02X1541734Y1139929I200J0D01*
G03Y1141369I-1084J720D01*
G02X1541704Y1141474I170J105D01*
G01Y1143564D01*
G02X1541734Y1143669I200J0D01*
G03X1541737Y1145104I-1084J720D01*
G01X1541720Y1145130D01*
X1541712Y1145156D01*
G02X1541704Y1145213I192J56D01*
G01Y1145307D01*
G02X1541726Y1145398I200J0D01*
G02X1541762Y1145448I178J-90D01*
G01X1542907Y1146593D01*
G02X1542957Y1146629I140J-142D01*
G02X1543048Y1146651I91J-178D01*
G01X1543117D01*
G03X1543136Y1146650I73J1199D01*
G01X1545284D01*
G03X1545303Y1146651I-54J1200D01*
G01X1545888D01*
G03X1546030Y1146710I0J200D01*
G01X1546651Y1147331D01*
G03X1546710Y1147473I-141J142D01*
G01Y1167514D01*
G02X1546732Y1167605I200J0D01*
G02X1546768Y1167655I178J-90D01*
G01X1546852Y1167739D01*
G02X1546902Y1167775I140J-142D01*
G02X1546993Y1167797I91J-178D01*
G01X1548906D01*
G02X1548938Y1167794I-3J-200D01*
G01X1548940D01*
G02X1549044Y1167742I-34J-197D01*
G01X1549568Y1167217D01*
G02X1549606Y1167148I-153J-129D01*
G01X1549607Y1167144D01*
G02X1549614Y1167104I-192J-54D01*
G01Y1148125D01*
G03X1549615Y1148111I1198J79D01*
G01Y1147528D01*
G03X1549674Y1147386I200J0D01*
G01X1550601Y1146459D01*
G03X1550743Y1146400I142J141D01*
G01X1556077D01*
G02X1556110Y1146397I-2J-200D01*
G02X1556217Y1146343I-32J-197D01*
G01X1556742Y1145818D01*
G02X1556796Y1145711I-143J-139D01*
G02X1556799Y1145678I-197J-35D01*
G01Y1142043D01*
G02X1556699Y1141870I-200J0D01*
G37*
G36*
G01X1534857Y1130999D02*
X1538778D01*
G02X1538920Y1130940I0J-200D01*
G01X1539090Y1130770D01*
G02X1539148Y1130629I-142J-141D01*
G01Y1123905D01*
G02X1538948Y1123705I-200J0D01*
G01X1535658D01*
G02X1535516Y1123764I0J200D01*
G01X1534413Y1124867D01*
X1534384Y1124895D01*
X1534354Y1124969D01*
Y1125147D01*
X1534370Y1125184D01*
G03X1534471Y1125688I-1201J503D01*
G03X1534370Y1126192I-1302J1D01*
G01X1534354Y1126229D01*
Y1128888D01*
X1534370Y1128925D01*
G03X1534471Y1129429I-1201J503D01*
G03X1534370Y1129933I-1302J1D01*
G01X1534354Y1129970D01*
Y1130496D01*
G02X1534413Y1130638I200J0D01*
G01X1534715Y1130940D01*
G02X1534857Y1130999I142J-141D01*
G37*
G36*
G01X1543093Y1167697D02*
X1545327D01*
G02X1545469Y1167638I0J-200D01*
G01X1545650Y1167457D01*
G02X1545708Y1167316I-142J-141D01*
G01Y1148078D01*
G02X1545650Y1147937I-200J0D01*
G01X1545424Y1147711D01*
G02X1545283Y1147652I-142J141D01*
G01X1543137D01*
G02X1542996Y1147711I1J200D01*
G01X1542469Y1148238D01*
G02X1542410Y1148380I141J142D01*
G01Y1155227D01*
X1542414Y1155247D01*
G03X1542451Y1155610I-1765J363D01*
G03X1542414Y1155973I-1802J0D01*
G01X1542410Y1155993D01*
Y1167014D01*
G02X1542469Y1167156I200J0D01*
G01X1542951Y1167638D01*
G02X1543093Y1167697I142J-141D01*
G37*
G36*
G01X1545708Y1170295D02*
X1545169Y1169756D01*
X1545141Y1169727D01*
X1545067Y1169697D01*
X1543193D01*
G02X1543051Y1169756I0J200D01*
G01X1542669Y1170138D01*
X1542640Y1170166D01*
X1542610Y1170240D01*
Y1181895D01*
X1543305Y1182590D01*
X1545226D01*
X1545708Y1182108D01*
Y1171465D01*
Y1170295D01*
G37*
G36*
G01X1537215Y1460782D02*
G03I-491J0D01*
G37*
G36*
G01X1545876Y1456452D02*
G03I-491J0D01*
G37*
G36*
G01Y1461183D02*
G03I-491J0D01*
G37*
G36*
G01Y1481268D02*
G03I-491J0D01*
G37*
G36*
G01X1537215Y1465513D02*
G03I-491J0D01*
G37*
G36*
G01X1545876Y1465914D02*
G03I-491J0D01*
G37*
G36*
G01X1537215Y1476136D02*
G03I-491J0D01*
G37*
G36*
G01Y1470244D02*
G03I-491J0D01*
G37*
G36*
G01Y1480867D02*
G03I-491J0D01*
G37*
G36*
G01X1545876Y1476537D02*
G03I-491J0D01*
G37*
G36*
G01Y1471806D02*
G03I-491J0D01*
G37*
G36*
G01Y1487161D02*
G03I-491J0D01*
G37*
G36*
G01Y1496623D02*
G03I-491J0D01*
G37*
G36*
G01X1537215Y1491491D02*
G03I-491J0D01*
G37*
G36*
G01Y1485598D02*
G03I-491J0D01*
G37*
G36*
G01Y1496222D02*
G03I-491J0D01*
G37*
G36*
G01X1545876Y1491892D02*
G03I-491J0D01*
G37*
G36*
G01X1537215Y1506845D02*
G03I-491J0D01*
G37*
G36*
G01Y1500953D02*
G03I-491J0D01*
G37*
G36*
G01Y1511576D02*
G03I-491J0D01*
G37*
G36*
G01X1545876Y1507246D02*
G03I-491J0D01*
G37*
G36*
G01Y1502515D02*
G03I-491J0D01*
G37*
G36*
G01Y1511977D02*
G03I-491J0D01*
G37*
G36*
G01X1537215Y1516307D02*
G03I-491J0D01*
G37*
G36*
G01X1545876Y1558813D02*
G03I-491J0D01*
G37*
G36*
G01Y1578898D02*
G03I-491J0D01*
G37*
G36*
G01X1537215Y1567875D02*
G03I-491J0D01*
G37*
G36*
G01X1545876Y1568275D02*
G03I-491J0D01*
G37*
G36*
G01X1537215Y1563144D02*
G03I-491J0D01*
G37*
G36*
G01X1545876Y1563544D02*
G03I-491J0D01*
G37*
G36*
G01X1537215Y1578498D02*
G03I-491J0D01*
G37*
G36*
G01Y1572606D02*
G03I-491J0D01*
G37*
G36*
G01X1545876Y1574167D02*
G03I-491J0D01*
G37*
G36*
G01X1537215Y1583229D02*
G03I-491J0D01*
G37*
G36*
G01X1545876Y1583629D02*
G03I-491J0D01*
G37*
G36*
G01X1537215Y1593853D02*
G03I-491J0D01*
G37*
G36*
G01Y1587960D02*
G03I-491J0D01*
G37*
G36*
G01X1545876Y1594253D02*
G03I-491J0D01*
G37*
G36*
G01Y1589522D02*
G03I-491J0D01*
G37*
G36*
G01X1537215Y1603315D02*
G03I-491J0D01*
G37*
G36*
G01X1545876Y1609607D02*
G03I-491J0D01*
G37*
G36*
G01Y1598984D02*
G03I-491J0D01*
G37*
G36*
G01Y1604876D02*
G03I-491J0D01*
G37*
G36*
G01X1537215Y1609207D02*
G03I-491J0D01*
G37*
G36*
G01Y1598584D02*
G03I-491J0D01*
G37*
G36*
G01Y1613938D02*
G03I-491J0D01*
G37*
G36*
G01Y1618669D02*
G03I-491J0D01*
G37*
G36*
G01X1545876Y1614338D02*
G03I-491J0D01*
G37*
G36*
G01X1556998Y340958D02*
G03I-500J0D01*
G37*
G36*
G01X1556880Y336917D02*
G03I-500J0D01*
G37*
G36*
G01X1556930Y345636D02*
G03I-577J0D01*
G37*
G36*
G01X1552343Y576249D02*
X1556102D01*
X1557543D01*
X1558782D01*
X1559641Y575390D01*
Y549500D01*
X1559141Y549000D01*
X1553781D01*
X1553281Y549500D01*
Y559538D01*
X1552283Y560536D01*
Y576189D01*
X1552343Y576249D01*
G37*
G36*
G01X1556499Y1192000D02*
X1557477D01*
G02X1557619Y1191941I0J-200D01*
G01X1558101Y1191459D01*
G02X1558160Y1191317I-141J-142D01*
G01Y1187283D01*
G02X1558101Y1187141I-200J0D01*
G01X1558019Y1187059D01*
G02X1557877Y1187000I-142J141D01*
G01X1554543D01*
G03X1554401Y1186941I0J-200D01*
G01X1553519Y1186059D01*
G03X1553460Y1185917I141J-142D01*
G01Y1176483D01*
G03X1553519Y1176341I200J0D01*
G01X1554901Y1174959D01*
G02X1554960Y1174817I-141J-142D01*
G01Y1173083D01*
G02X1554901Y1172941I-200J0D01*
G01X1553419Y1171459D01*
G03X1553360Y1171317I141J-142D01*
G01Y1150583D01*
G03X1553419Y1150441I200J0D01*
G01X1554801Y1149059D01*
G02X1554860Y1148917I-141J-142D01*
G01Y1147602D01*
G02X1554660Y1147402I-200J0D01*
G01X1551341D01*
G02X1551200Y1147460I0J200D01*
G01X1550675Y1147985D01*
G02X1550616Y1148126I141J142D01*
G01Y1167089D01*
G03X1550568Y1167426I-1201J1D01*
G01X1550560Y1167453D01*
Y1171854D01*
X1550572Y1171888D01*
G03X1550648Y1172305I-1126J421D01*
G01Y1182779D01*
G03X1550572Y1183196I-1202J-4D01*
G01X1550560Y1183230D01*
Y1186105D01*
G02X1550659Y1186278I200J0D01*
G03Y1188524I-659J1123D01*
G02X1550560Y1188697I101J173D01*
G01Y1189517D01*
G02X1550619Y1189659I200J0D01*
G01X1552901Y1191941D01*
G02X1553043Y1192000I142J-141D01*
G01X1554721D01*
G02X1554840Y1191961I0J-200D01*
G03X1556380I770J1050D01*
G02X1556499Y1192000I119J-161D01*
G37*
G36*
G01X1561141Y1186298D02*
X1564360D01*
G02X1564505Y1186236I0J-200D01*
G01X1564734Y1185994D01*
X1564762Y1185918D01*
X1564759Y1185876D01*
G03X1564758Y1185850I451J-30D01*
G01Y1184350D01*
G03X1565210Y1183898I452J0D01*
G01X1566410D01*
G03X1566548Y1183920I-1J452D01*
G01X1566577Y1183929D01*
X1566608D01*
G02X1566808Y1183729I0J-200D01*
G01Y1182719D01*
G03X1567066Y1181977I1202J2D01*
G02X1567131Y1181792I-236J-187D01*
G01X1567130Y1181791D01*
X1567131Y1181790D01*
G02X1567066Y1181605I-301J2D01*
G03X1566808Y1180863I944J-744D01*
G01Y1179652D01*
G02X1566608Y1179452I-200J-1D01*
G01X1565410D01*
G03X1564958Y1179000I0J-452D01*
G01Y1177500D01*
G03X1565410Y1177048I452J0D01*
G01X1566016D01*
G02X1566128Y1177014I1J-200D01*
G03X1566830Y1176799I702J1037D01*
G03X1567317Y1176898I-1J1252D01*
G01X1567374Y1176921D01*
X1567492Y1176898D01*
X1567942Y1176448D01*
G03X1568486Y1176135I851J849D01*
G01X1568512Y1176128D01*
X1568558Y1176102D01*
X1568801Y1175859D01*
G03X1568943Y1175800I142J141D01*
G01X1569330D01*
G02X1569512Y1175682I0J-200D01*
G01X1569686Y1175297D01*
X1569669Y1175180D01*
X1569630Y1175136D01*
G03X1569319Y1174310I941J-826D01*
G03X1569363Y1173983I1252J2D01*
G01X1569370Y1173957D01*
Y1172890D01*
G03X1569821Y1172438I452J0D01*
G01X1571321D01*
G03X1571772Y1172890I0J451D01*
G01Y1173957D01*
X1571779Y1173983D01*
G03X1571823Y1174310I-1208J329D01*
G03X1571512Y1175136I-1252J0D01*
G01X1571473Y1175180D01*
X1571456Y1175297D01*
X1571630Y1175682D01*
G02X1571812Y1175800I182J-82D01*
G01X1576810D01*
G02X1576992Y1175682I0J-200D01*
G01X1577166Y1175297D01*
X1577149Y1175180D01*
X1577110Y1175136D01*
G03X1576799Y1174310I941J-826D01*
G03X1576843Y1173983I1252J2D01*
G01X1576850Y1173957D01*
Y1172890D01*
G03X1577301Y1172438I452J0D01*
G01X1578801D01*
G03X1579252Y1172890I0J451D01*
G01Y1173957D01*
X1579259Y1173983D01*
G03X1579303Y1174310I-1208J329D01*
G03X1578992Y1175136I-1252J0D01*
G01X1578953Y1175180D01*
X1578936Y1175297D01*
X1579110Y1175682D01*
G02X1579292Y1175800I182J-82D01*
G01X1584290D01*
G02X1584472Y1175682I0J-200D01*
G01X1584646Y1175297D01*
X1584629Y1175180D01*
X1584590Y1175136D01*
G03X1584279Y1174310I941J-826D01*
G03X1584323Y1173983I1252J2D01*
G01X1584330Y1173957D01*
Y1172890D01*
G03X1584781Y1172438I452J0D01*
G01X1586281D01*
G03X1586732Y1172890I0J451D01*
G01Y1173957D01*
X1586739Y1173983D01*
G03X1586783Y1174310I-1208J329D01*
G03X1586472Y1175136I-1252J0D01*
G01X1586433Y1175180D01*
X1586416Y1175297D01*
X1586590Y1175682D01*
G02X1586772Y1175800I182J-82D01*
G01X1591770D01*
G02X1591952Y1175682I0J-200D01*
G01X1592126Y1175297D01*
X1592109Y1175180D01*
X1592070Y1175136D01*
G03X1591759Y1174310I941J-826D01*
G03X1591803Y1173980I1252J-1D01*
G01X1591810Y1173954D01*
Y1172890D01*
G03X1592262Y1172438I452J0D01*
G01X1593762D01*
G03X1594214Y1172890I0J452D01*
G01Y1173960D01*
X1594220Y1173986D01*
G03X1594263Y1174310I-1209J325D01*
G03X1593952Y1175136I-1252J0D01*
G01X1593913Y1175180D01*
X1593896Y1175297D01*
X1594070Y1175682D01*
G02X1594252Y1175800I182J-82D01*
G01X1599251D01*
G02X1599433Y1175682I0J-200D01*
G01X1599607Y1175297D01*
X1599590Y1175180D01*
X1599551Y1175136D01*
G03X1599240Y1174310I941J-826D01*
G03X1599335Y1173831I1252J-1D01*
G01X1599350Y1173794D01*
Y1172890D01*
G03X1599802Y1172438I452J0D01*
G01X1601302D01*
G03X1601754Y1172890I0J452D01*
G01Y1174090D01*
G03X1601745Y1174178I-452J-2D01*
G02X1601741Y1174230I196J41D01*
G03X1601744Y1174310I-1249J87D01*
G03X1601433Y1175136I-1252J0D01*
G01X1601394Y1175180D01*
X1601377Y1175297D01*
X1601551Y1175682D01*
G02X1601733Y1175800I182J-82D01*
G01X1610471D01*
G02X1610653Y1175682I0J-200D01*
G01X1610827Y1175297D01*
X1610810Y1175180D01*
X1610771Y1175136D01*
G03X1610460Y1174310I941J-826D01*
G03X1610504Y1173983I1252J2D01*
G01X1610510Y1173957D01*
Y1172890D01*
G03X1610962Y1172438I452J0D01*
G01X1612462D01*
G03X1612914Y1172890I0J452D01*
G01Y1173957D01*
X1612920Y1173983D01*
G03X1612964Y1174310I-1208J329D01*
G03X1612653Y1175136I-1252J0D01*
G01X1612614Y1175180D01*
X1612597Y1175297D01*
X1612771Y1175682D01*
G02X1612953Y1175800I182J-82D01*
G01X1617952D01*
G02X1618134Y1175682I0J-200D01*
G01X1618308Y1175297D01*
X1618291Y1175180D01*
X1618252Y1175136D01*
G03X1617941Y1174310I941J-826D01*
G03X1617985Y1173983I1252J2D01*
G01X1617992Y1173957D01*
Y1172890D01*
G03X1618443Y1172438I452J0D01*
G01X1619943D01*
G03X1620394Y1172890I0J451D01*
G01Y1173957D01*
X1620401Y1173983D01*
G03X1620445Y1174310I-1208J329D01*
G03X1620134Y1175136I-1252J0D01*
G01X1620095Y1175180D01*
X1620078Y1175297D01*
X1620252Y1175682D01*
G02X1620434Y1175800I182J-82D01*
G01X1625432D01*
G02X1625614Y1175682I0J-200D01*
G01X1625788Y1175297D01*
X1625771Y1175180D01*
X1625732Y1175136D01*
G03X1625421Y1174310I941J-826D01*
G03X1625465Y1173983I1252J2D01*
G01X1625472Y1173957D01*
Y1172890D01*
G03X1625923Y1172438I452J0D01*
G01X1627423D01*
G03X1627874Y1172890I0J451D01*
G01Y1173957D01*
X1627881Y1173983D01*
G03X1627925Y1174310I-1208J329D01*
G03X1627614Y1175136I-1252J0D01*
G01X1627575Y1175180D01*
X1627558Y1175297D01*
X1627732Y1175682D01*
G02X1627914Y1175800I182J-82D01*
G01X1630877D01*
G02X1631019Y1175741I0J-200D01*
G01X1631601Y1175159D01*
G02X1631660Y1175017I-141J-142D01*
G01Y1172836D01*
G02X1631593Y1172687I-200J0D01*
G01X1631338Y1172459D01*
X1631258Y1172434D01*
X1631214Y1172439D01*
G03X1631163Y1172442I-52J-449D01*
G01X1629663D01*
G03X1629212Y1171990I0J-451D01*
G01Y1170923D01*
X1629205Y1170897D01*
G03X1629161Y1170570I1208J-329D01*
G03X1630413Y1169318I1252J0D01*
G03X1631055Y1169495I0J1253D01*
G01X1631102Y1169523D01*
X1631209Y1169524D01*
X1631559Y1169326D01*
G02X1631660Y1169152I-99J-174D01*
G01Y1160768D01*
G02X1631559Y1160594I-200J0D01*
G01X1631209Y1160396D01*
X1631102Y1160397D01*
X1631055Y1160425D01*
G03X1630413Y1160602I-642J-1076D01*
G03X1629161Y1159350I0J-1252D01*
G03X1629205Y1159023I1252J2D01*
G01X1629212Y1158997D01*
Y1157930D01*
G03X1629663Y1157478I452J0D01*
G01X1631163D01*
G03X1631214Y1157481I-1J452D01*
G01X1631258Y1157486D01*
X1631338Y1157461D01*
X1631593Y1157233D01*
G02X1631660Y1157084I-133J-149D01*
G01Y1155683D01*
G02X1631601Y1155541I-200J0D01*
G01X1630820Y1154760D01*
G02X1630679Y1154702I-141J142D01*
G01X1628245D01*
G02X1628083Y1154784I-1J200D01*
G01X1627864Y1155085D01*
X1627849Y1155178D01*
X1627864Y1155225D01*
G03X1627925Y1155610I-1191J386D01*
G03X1627881Y1155937I-1252J-2D01*
G01X1627874Y1155963D01*
Y1157030D01*
G03X1627423Y1157482I-452J0D01*
G01X1625923D01*
G03X1625472Y1157030I0J-451D01*
G01Y1155963D01*
X1625465Y1155937D01*
G03X1625421Y1155610I1208J-329D01*
G03X1625482Y1155225I1252J1D01*
G01X1625497Y1155178D01*
X1625482Y1155085D01*
X1625263Y1154784D01*
G02X1625101Y1154702I-161J118D01*
G01X1620765D01*
G02X1620603Y1154784I-1J200D01*
G01X1620384Y1155085D01*
X1620369Y1155178D01*
X1620384Y1155225D01*
G03X1620445Y1155610I-1191J386D01*
G03X1620401Y1155940I-1252J1D01*
G01X1620394Y1155966D01*
Y1157030D01*
G03X1619942Y1157482I-452J0D01*
G01X1618442D01*
G03X1617990Y1157030I0J-452D01*
G01Y1155960D01*
X1617984Y1155934D01*
G03X1617941Y1155610I1209J-325D01*
G03X1618002Y1155225I1252J1D01*
G01X1618017Y1155178D01*
X1618002Y1155085D01*
X1617783Y1154784D01*
G02X1617621Y1154702I-161J118D01*
G01X1613284D01*
G02X1613122Y1154784I-1J200D01*
G01X1612903Y1155085D01*
X1612888Y1155178D01*
X1612903Y1155225D01*
G03X1612964Y1155610I-1191J386D01*
G03X1612920Y1155937I-1252J-2D01*
G01X1612914Y1155963D01*
Y1157030D01*
G03X1612462Y1157482I-452J0D01*
G01X1610962D01*
G03X1610510Y1157030I0J-452D01*
G01Y1155963D01*
X1610504Y1155937D01*
G03X1610460Y1155610I1208J-329D01*
G03X1610521Y1155225I1252J1D01*
G01X1610536Y1155178D01*
X1610521Y1155085D01*
X1610302Y1154784D01*
G02X1610140Y1154702I-161J118D01*
G01X1602064D01*
G02X1601902Y1154784I-1J200D01*
G01X1601683Y1155085D01*
X1601668Y1155178D01*
X1601683Y1155225D01*
G03X1601744Y1155610I-1191J386D01*
G03X1601700Y1155937I-1252J-2D01*
G01X1601694Y1155963D01*
Y1157030D01*
G03X1601242Y1157482I-452J0D01*
G01X1599742D01*
G03X1599290Y1157030I0J-452D01*
G01Y1155963D01*
X1599284Y1155937D01*
G03X1599240Y1155610I1208J-329D01*
G03X1599301Y1155225I1252J1D01*
G01X1599316Y1155178D01*
X1599301Y1155085D01*
X1599082Y1154784D01*
G02X1598920Y1154702I-161J118D01*
G01X1594583D01*
G02X1594421Y1154784I-1J200D01*
G01X1594202Y1155085D01*
X1594187Y1155178D01*
X1594202Y1155225D01*
G03X1594263Y1155610I-1191J386D01*
G03X1594220Y1155934I-1252J-1D01*
G01X1594214Y1155960D01*
Y1157030D01*
G03X1593762Y1157482I-452J0D01*
G01X1592262D01*
G03X1591810Y1157030I0J-452D01*
G01Y1155966D01*
X1591803Y1155940D01*
G03X1591759Y1155610I1208J-329D01*
G03X1591820Y1155225I1252J1D01*
G01X1591835Y1155178D01*
X1591820Y1155085D01*
X1591601Y1154784D01*
G02X1591439Y1154702I-161J118D01*
G01X1587103D01*
G02X1586941Y1154784I-1J200D01*
G01X1586722Y1155085D01*
X1586707Y1155178D01*
X1586722Y1155225D01*
G03X1586783Y1155610I-1191J386D01*
G03X1586739Y1155937I-1252J-2D01*
G01X1586732Y1155963D01*
Y1157030D01*
G03X1586281Y1157482I-452J0D01*
G01X1584781D01*
G03X1584330Y1157030I0J-451D01*
G01Y1155963D01*
X1584323Y1155937D01*
G03X1584279Y1155610I1208J-329D01*
G03X1584340Y1155225I1252J1D01*
G01X1584355Y1155178D01*
X1584340Y1155085D01*
X1584121Y1154784D01*
G02X1583959Y1154702I-161J118D01*
G01X1579623D01*
G02X1579461Y1154784I-1J200D01*
G01X1579242Y1155085D01*
X1579227Y1155178D01*
X1579242Y1155225D01*
G03X1579303Y1155610I-1191J386D01*
G03X1579259Y1155937I-1252J-2D01*
G01X1579252Y1155963D01*
Y1157030D01*
G03X1578801Y1157482I-452J0D01*
G01X1577301D01*
G03X1576850Y1157030I0J-451D01*
G01Y1155963D01*
X1576843Y1155937D01*
G03X1576799Y1155610I1208J-329D01*
G03X1576860Y1155225I1252J1D01*
G01X1576875Y1155178D01*
X1576860Y1155085D01*
X1576641Y1154784D01*
G02X1576479Y1154702I-161J118D01*
G01X1572143D01*
G02X1571981Y1154784I-1J200D01*
G01X1571762Y1155085D01*
X1571747Y1155178D01*
X1571762Y1155225D01*
G03X1571823Y1155610I-1191J386D01*
G03X1571779Y1155937I-1252J-2D01*
G01X1571772Y1155963D01*
Y1157030D01*
G03X1571321Y1157482I-452J0D01*
G01X1569821D01*
G03X1569370Y1157030I0J-451D01*
G01Y1155963D01*
X1569363Y1155937D01*
G03X1569319Y1155610I1208J-329D01*
G03X1569497Y1154967I1252J0D01*
G01X1569532Y1154908D01*
X1569515Y1154772D01*
X1567668Y1152925D01*
X1567532Y1152908D01*
X1567473Y1152943D01*
G03X1566830Y1153121I-643J-1074D01*
G03X1566503Y1153077I2J-1252D01*
G01X1566477Y1153070D01*
X1565410D01*
G03X1564958Y1152619I0J-452D01*
G01Y1151119D01*
G03X1565410Y1150668I451J0D01*
G01X1566477D01*
X1566503Y1150661D01*
G03X1566830Y1150617I329J1208D01*
G03X1567231Y1150683I0J1251D01*
G01X1567277Y1150698D01*
X1567372Y1150684D01*
X1567622Y1150504D01*
Y1145754D01*
X1567372Y1145574D01*
X1567277Y1145560D01*
X1567231Y1145575D01*
G03X1566830Y1145641I-401J-1185D01*
G03X1566503Y1145597I2J-1252D01*
G01X1566477Y1145590D01*
X1565410D01*
G03X1564958Y1145139I0J-452D01*
G01Y1143639D01*
G03X1565410Y1143188I451J0D01*
G01X1566477D01*
X1566503Y1143181D01*
G03X1566830Y1143137I329J1208D01*
G03X1567458Y1143306I0J1251D01*
G01X1567481Y1143319D01*
X1567532Y1143333D01*
X1567558D01*
G02X1567758Y1143133I0J-200D01*
G01Y1142985D01*
X1567760Y1142984D01*
Y1142683D01*
G02X1567701Y1142541I-200J0D01*
G01X1567090Y1141930D01*
X1567017Y1141900D01*
X1566992D01*
G03X1566830Y1141910I-159J-1251D01*
G03X1566679Y1141901I-1J-1261D01*
G01X1566667Y1141900D01*
X1563253D01*
X1563241Y1141901D01*
G03X1563090Y1141910I-150J-1252D01*
G03X1562939Y1141901I-1J-1261D01*
G01X1562927Y1141900D01*
X1561043D01*
G02X1560901Y1141959I0J200D01*
G01X1560719Y1142141D01*
G02X1560660Y1142283I141J142D01*
G01Y1185817D01*
G02X1560719Y1185959I200J0D01*
G01X1561000Y1186240D01*
G02X1561141Y1186298I141J-142D01*
G37*
G36*
G01X1549587Y1172164D02*
X1549103Y1171680D01*
G02X1548850Y1171654I-142J141D01*
G03X1548130Y1171872I-721J-1083D01*
G01X1548129D01*
G03X1547378Y1171634I0J-1302D01*
G01X1547353Y1171615D01*
X1547295Y1171597D01*
X1546993D01*
G02X1546851Y1171656I0J200D01*
G01X1546769Y1171738D01*
X1546740Y1171766D01*
X1546710Y1171840D01*
Y1182227D01*
X1547580Y1183097D01*
X1549327D01*
G02X1549469Y1183038I0J-200D01*
G01X1549587Y1182920D01*
G02X1549646Y1182778I-141J-142D01*
G01Y1172306D01*
G02X1549587Y1172164I-200J0D01*
G37*
G36*
G01X1564979Y1187523D02*
G02X1564966Y1187508I-157J123D01*
G01X1564816Y1187358D01*
G02X1564749Y1187314I-141J142D01*
G01X1564715Y1187300D01*
X1560317D01*
G02X1560191Y1187345I0J200D01*
G02X1560176Y1187358I123J157D01*
G01X1559751Y1187783D01*
G02X1559707Y1187850I142J141D01*
G01X1559693Y1187884D01*
Y1191610D01*
G02X1559728Y1191723I200J0D01*
G01Y1191724D01*
G02X1559820Y1191796I164J-115D01*
G01X1559821Y1191797D01*
G03X1559853Y1191810I-474J1213D01*
G01X1559950D01*
G03X1560397Y1192198I0J451D01*
G02X1560429Y1192282I198J-27D01*
G03X1560652Y1193011I-1080J729D01*
G03X1560429Y1193739I-1301J0D01*
G02X1560397Y1193823I166J111D01*
G03X1560390Y1193860I-447J-65D01*
G02X1560429Y1194029I195J44D01*
G01X1560625Y1194273D01*
G02X1560781Y1194348I156J-125D01*
G01X1565528D01*
G02X1565728Y1194148I0J-200D01*
G01Y1193630D01*
X1565718Y1193586D01*
X1565707Y1193565D01*
G03X1565578Y1193011I1123J-554D01*
G03X1565625Y1192670I1252J-1D01*
G02X1565574Y1192474I-192J-55D01*
G01X1565083Y1191983D01*
G03X1565024Y1191841I141J-142D01*
G01Y1187649D01*
G02X1564979Y1187523I-200J0D01*
G37*
G36*
G01X1566375Y1197625D02*
X1566967D01*
G02X1567109Y1197566I0J-200D01*
G01X1567239Y1197435D01*
G03X1567381Y1197376I142J141D01*
G01X1638510D01*
G02X1638710Y1197176I0J-200D01*
G01Y1196502D01*
G02X1638651Y1196360I-200J0D01*
G01X1637699Y1195408D01*
X1637671Y1195379D01*
X1637597Y1195349D01*
X1560998D01*
G02X1560856Y1195408I0J200D01*
G01X1560720Y1195544D01*
Y1197370D01*
X1560916Y1197566D01*
X1566233D01*
G02X1566375Y1197625I142J-141D01*
G37*
G36*
G01X1569740Y1141927D02*
X1569750Y1141937D01*
G02X1569891Y1141996I142J-141D01*
G01X1638829D01*
G02X1638970Y1141937I-1J-200D01*
G01X1638980Y1141927D01*
X1639010Y1141854D01*
Y1139998D01*
G02X1638810Y1139798I-200J0D01*
G01X1570191D01*
G02X1570050Y1139857I1J200D01*
G01X1569769Y1140138D01*
G02X1569710Y1140280I141J142D01*
G01Y1141854D01*
X1569740Y1141927D01*
G37*
G36*
G01X1569993Y1134697D02*
X1638527D01*
G02X1638669Y1134638I0J-200D01*
G01X1638951Y1134356D01*
G02X1639010Y1134214I-141J-142D01*
G01Y1132980D01*
G02X1638951Y1132838I-200J0D01*
G01X1638570Y1132457D01*
G02X1638429Y1132398I-142J141D01*
G01X1570091D01*
G02X1569950Y1132457I1J200D01*
G01X1569669Y1132738D01*
G02X1569610Y1132880I141J142D01*
G01Y1134314D01*
G02X1569669Y1134456I200J0D01*
G01X1569851Y1134638D01*
G02X1569993Y1134697I142J-141D01*
G37*
G36*
G01X1647703Y1127129D02*
X1648859D01*
G02X1649001Y1127070I0J-200D01*
G01X1649319Y1126752D01*
X1649744Y1126326D01*
X1649746D01*
X1649951Y1126120D01*
G02X1650010Y1125978I-141J-142D01*
G01Y1125091D01*
G02X1649951Y1124949I-200J0D01*
G01X1649822Y1124820D01*
G02X1649681Y1124762I-141J142D01*
G01X1622099D01*
G03X1621557Y1124639I1J-1262D01*
G02X1621475Y1124620I-85J181D01*
G03X1621002Y1124514I29J-1237D01*
G01X1620964Y1124497D01*
X1617242D01*
G02X1617127Y1124533I-1J200D01*
G03X1616403Y1124762I-725J-1033D01*
G01X1607373D01*
G03X1606481Y1124392I1J-1262D01*
G01X1605515Y1123426D01*
G03X1605146Y1122534I892J-891D01*
G01Y1122492D01*
G02X1604946Y1122292I-200J0D01*
G01X1602620D01*
G02X1602478Y1122351I0J200D01*
G01X1600391Y1124438D01*
G03X1600249Y1124497I-142J-141D01*
G01X1568227D01*
G02X1568085Y1124556I0J200D01*
G01X1567941Y1124700D01*
G02X1567892Y1124900I142J141D01*
G01X1567910Y1124960D01*
X1567925Y1124983D01*
G03X1568132Y1125690I-1095J704D01*
G01Y1125715D01*
G03X1567740Y1126619I-1302J-27D01*
G01X1567711Y1126648D01*
X1567680Y1126721D01*
Y1126806D01*
G02X1567880Y1127006I200J0D01*
G01X1640704D01*
G03X1640841Y1127061I-1J200D01*
G01X1640846Y1127066D01*
X1640866Y1127083D01*
G02X1640994Y1127129I128J-154D01*
G01X1642940D01*
G03X1642950Y1127128I124J1193D01*
G01X1647668D01*
G03X1647700Y1127129I-22J1201D01*
G01X1647703D01*
G37*
G36*
G01X1569993Y1138797D02*
X1638727D01*
G02X1638869Y1138738I0J-200D01*
G01X1639151Y1138456D01*
G02X1639210Y1138314I-141J-142D01*
G01Y1135980D01*
G02X1639151Y1135838I-200J0D01*
G01X1639070Y1135757D01*
G02X1638929Y1135698I-142J141D01*
G01X1569710D01*
G02X1569510Y1135898I0J200D01*
G01Y1138314D01*
G02X1569569Y1138456I200J0D01*
G01X1569851Y1138738D01*
G02X1569993Y1138797I142J-141D01*
G37*
G36*
G01X1600829Y1131397D02*
X1639798D01*
G02X1639940Y1131338I0J-200D01*
G01X1640428Y1130850D01*
G02X1640487Y1130708I-141J-142D01*
G01Y1130072D01*
X1640477Y1130028D01*
X1640466Y1130007D01*
G03X1640331Y1129429I1167J-577D01*
G03X1640466Y1128851I1302J-1D01*
G01X1640477Y1128830D01*
X1640487Y1128786D01*
Y1128206D01*
G02X1640428Y1128064I-200J0D01*
G01X1640402Y1128038D01*
X1640329Y1128008D01*
X1568081D01*
G02X1567939Y1128067I0J200D01*
G01X1567923Y1128083D01*
Y1128692D01*
X1567937Y1128743D01*
X1567951Y1128766D01*
G03X1568132Y1129429I-1121J662D01*
G03X1568084Y1129779I-1302J0D01*
G02X1568095Y1129916I193J53D01*
G01X1568146Y1130027D01*
G02X1568242Y1130125I182J-82D01*
G03X1568586Y1130368I-531J1117D01*
G01X1569230Y1131012D01*
G03X1569441Y1131293I-873J875D01*
G01X1569468Y1131342D01*
X1569561Y1131397D01*
X1600351D01*
X1600368Y1131394D01*
G03X1600590Y1131375I222J1283D01*
G03X1600812Y1131394I0J1302D01*
G01X1600829Y1131397D01*
G37*
G36*
G01X1633343Y1172100D02*
X1642777D01*
G02X1642919Y1172041I0J-200D01*
G01X1643101Y1171859D01*
G02X1643160Y1171717I-141J-142D01*
G01Y1158483D01*
G03X1643219Y1158341I200J0D01*
G01X1644151Y1157409D01*
G02X1644210Y1157267I-141J-142D01*
G01Y1156072D01*
X1644198Y1156039D01*
G03X1644122Y1155610I1176J-430D01*
G03X1644198Y1155181I1252J1D01*
G01X1644210Y1155148D01*
Y1152331D01*
X1644198Y1152298D01*
G03X1644122Y1151869I1176J-430D01*
G03X1644198Y1151440I1252J1D01*
G01X1644210Y1151407D01*
Y1148591D01*
X1644198Y1148558D01*
G03X1644122Y1148129I1176J-430D01*
G03X1644198Y1147700I1252J1D01*
G01X1644210Y1147667D01*
Y1144851D01*
X1644198Y1144818D01*
G03X1644122Y1144389I1176J-430D01*
G03X1644198Y1143960I1252J1D01*
G01X1644210Y1143927D01*
Y1142833D01*
G02X1644151Y1142691I-200J0D01*
G01X1643919Y1142459D01*
G02X1643777Y1142400I-142J141D01*
G01X1639941D01*
X1639841Y1142468D01*
X1639830Y1142493D01*
X1639679Y1142645D01*
G03X1639270Y1142913I-849J-850D01*
G01X1639231Y1142929D01*
X1639219Y1142941D01*
G03X1639077Y1143000I-142J-141D01*
G01X1569243D01*
G02X1569101Y1143059I0J200D01*
G01X1568819Y1143341D01*
X1568790Y1143369D01*
X1568760Y1143443D01*
Y1152517D01*
G02X1568819Y1152659I200J0D01*
G01X1569801Y1153641D01*
G02X1569943Y1153700I142J-141D01*
G01X1632277D01*
G03X1632419Y1153759I0J200D01*
G01X1633002Y1154342D01*
G03X1633045Y1154407I-142J141D01*
G01X1633057Y1154434D01*
X1633106Y1154488D01*
X1633323Y1154594D01*
X1633428Y1154588D01*
X1633472Y1154559D01*
G03X1634153Y1154358I680J1051D01*
G03X1635405Y1155610I0J1252D01*
G03X1635368Y1155912I-1251J0D01*
G01X1635362Y1155936D01*
Y1157030D01*
G03X1634910Y1157482I-452J0D01*
G01X1633410D01*
G03X1633349Y1157477I6J-451D01*
G01X1633348D01*
G03X1633306Y1157469I63J-447D01*
G01X1633136Y1157604D01*
G02X1633060Y1157761I124J157D01*
G01Y1165331D01*
G02X1633153Y1165499I200J-1D01*
G01X1633480Y1165708D01*
X1633582Y1165715D01*
X1633628Y1165693D01*
G03X1634153Y1165578I524J1137D01*
G03X1634479Y1165621I1J1252D01*
G01X1634504Y1165628D01*
X1635040D01*
X1635573D01*
G03X1636024Y1166080I0J451D01*
G01Y1166830D01*
X1636025D01*
Y1167580D01*
G03X1635574Y1168032I-452J0D01*
G01X1634504D01*
X1634479Y1168039D01*
G03X1634153Y1168082I-325J-1209D01*
G03X1633628Y1167967I-1J-1252D01*
G01X1633582Y1167945D01*
X1633480Y1167952D01*
X1633153Y1168161D01*
G02X1633060Y1168329I107J169D01*
G01Y1171817D01*
G02X1633119Y1171959I200J0D01*
G01X1633201Y1172041D01*
G02X1633343Y1172100I142J-141D01*
G37*
G36*
G01X1566229Y1190090D02*
X1567953D01*
X1567958Y1190084D01*
X1638251D01*
G02X1638392Y1190026I0J-200D01*
G01X1638683Y1189735D01*
G02X1638742Y1189593I-141J-142D01*
G01Y1188414D01*
G02X1638683Y1188272I-200J0D01*
G01X1638339Y1187928D01*
G02X1638197Y1187869I-142J141D01*
G01X1566323D01*
G02X1566181Y1187928I0J200D01*
G01X1566084Y1188025D01*
G02X1566026Y1188166I142J141D01*
G01Y1189886D01*
G02X1566084Y1190028I200J1D01*
G01X1566087Y1190031D01*
G02X1566229Y1190090I142J-141D01*
G37*
G36*
G01X1638724Y1186897D02*
X1639327D01*
G02X1639469Y1186838I0J-200D01*
G01X1640345Y1185962D01*
X1640373Y1185864D01*
X1640362Y1185814D01*
G03X1640331Y1185531I1271J-282D01*
G03X1641006Y1184390I1302J0D01*
G01X1641055Y1184363D01*
X1641110Y1184270D01*
Y1183052D01*
X1641055Y1182959D01*
X1641006Y1182932D01*
G03X1640539Y1181086I627J-1141D01*
G01Y1178757D01*
G03X1640331Y1178051I1094J-706D01*
G03X1640377Y1177707I1302J-1D01*
G01X1640392Y1177655D01*
X1640364Y1177551D01*
X1640244Y1177431D01*
G02X1640102Y1177372I-142J141D01*
G01X1638113D01*
G03X1637715Y1177175I1J-502D01*
G01X1637686Y1177138D01*
X1637603Y1177097D01*
X1568793D01*
G02X1568651Y1177156I0J200D01*
G01X1568131Y1177676D01*
X1568102Y1177769D01*
X1568111Y1177818D01*
G03X1568132Y1178051I-1282J233D01*
G03X1567853Y1178857I-1302J1D01*
G02X1567810Y1178980I157J124D01*
G01Y1180862D01*
G02X1567853Y1180985I200J-1D01*
G03X1568132Y1181791I-1023J805D01*
G03X1567853Y1182597I-1302J1D01*
G02X1567810Y1182720I157J124D01*
G01Y1184602D01*
G02X1567853Y1184725I200J-1D01*
G03X1568132Y1185531I-1023J805D01*
G03X1567853Y1186337I-1302J1D01*
G01X1567832Y1186364D01*
X1567810Y1186426D01*
Y1186714D01*
G02X1567869Y1186856I200J0D01*
G01X1567880Y1186868D01*
X1638695D01*
X1638724Y1186897D01*
G37*
G36*
G01X1642029Y1202824D02*
X1641540D01*
X1572330D01*
X1566102D01*
X1566016Y1202910D01*
Y1204954D01*
X1566403Y1205341D01*
X1572279D01*
X1573332D01*
X1600486D01*
G03X1600628Y1205400I0J200D01*
G01X1602736Y1207508D01*
G02X1602878Y1207567I142J-141D01*
G01X1605678D01*
G02X1605820Y1207508I0J-200D01*
G01X1607869Y1205459D01*
G03X1608011Y1205400I142J141D01*
G01X1642052D01*
X1642560D01*
X1642760Y1205200D01*
Y1203000D01*
X1642584Y1202824D01*
X1642029D01*
G37*
G36*
G01X1638287Y1194497D02*
X1638427D01*
G02X1638569Y1194438I0J-200D01*
G01X1639451Y1193556D01*
G02X1639510Y1193414I-141J-142D01*
G01Y1191380D01*
G02X1639451Y1191238I-200J0D01*
G01X1639358Y1191145D01*
G02X1639216Y1191086I-142J141D01*
G01X1568960D01*
X1568660Y1191386D01*
Y1194148D01*
X1568860Y1194348D01*
X1637972D01*
G03X1638113Y1194406I0J200D01*
G01X1638146Y1194438D01*
G02X1638287Y1194497I142J-141D01*
G37*
G36*
G01X1640314Y1199246D02*
X1639504Y1198437D01*
X1639476Y1198408D01*
X1639402Y1198378D01*
X1567797D01*
G02X1567655Y1198437I0J200D01*
G01X1567507Y1198585D01*
G02X1567487Y1198608I141J142D01*
G02X1567448Y1198727I161J119D01*
G01Y1199231D01*
G02X1567539Y1199399I200J0D01*
G03X1568132Y1200491I-709J1092D01*
G03X1567919Y1201203I-1302J-2D01*
G01X1567904Y1201226D01*
X1567888Y1201278D01*
X1567887Y1201306D01*
G02X1567911Y1201408I200J7D01*
G01X1568078Y1201718D01*
G02X1568254Y1201823I176J-95D01*
G01X1639960D01*
X1640314Y1201469D01*
Y1199246D01*
G37*
G36*
G01X1696194Y514918D02*
X1762819D01*
G02X1762961Y514859I0J-200D01*
G01X1773366Y504454D01*
G02X1773425Y504312I-141J-142D01*
G01Y489688D01*
G02X1773302Y489503I-200J0D01*
G01X1773245Y489479D01*
X1773127Y489503D01*
X1771625Y491005D01*
X1771598Y491052D01*
X1771591Y491079D01*
G03X1770135Y492213I-1456J-368D01*
G03X1768633Y490711I0J-1502D01*
G03X1769767Y489255I1502J0D01*
G01X1769794Y489248D01*
X1769841Y489221D01*
X1773180Y485882D01*
G02X1773238Y485741I-142J-141D01*
G01Y475331D01*
G02X1773180Y475190I-200J0D01*
G01X1772510Y474520D01*
G02X1772369Y474462I-141J142D01*
G01X1766814D01*
X1766701Y474560D01*
X1766690Y474634D01*
G03X1764906Y476184I-1784J-252D01*
G03X1763104Y474382I0J-1802D01*
G03X1764847Y472581I1802J0D01*
G01X1764886Y472580D01*
X1764954Y472550D01*
X1765196Y472308D01*
G03X1766088Y471938I893J892D01*
G01X1772974D01*
G03X1773013Y471939I-13J1262D01*
G01X1773053Y471940D01*
X1773129Y471911D01*
X1773364Y471683D01*
G02X1773425Y471539I-139J-144D01*
G01Y451933D01*
G02X1773366Y451791I-200J0D01*
G01X1772330Y450755D01*
G02X1772188Y450696I-142J141D01*
G01X1768309D01*
G02X1768136Y450796I0J200D01*
G03X1767854Y451147I-1299J-755D01*
G02X1767789Y451294I135J148D01*
G01Y451588D01*
G02X1767854Y451735I200J-1D01*
G03X1768339Y452841I-1017J1105D01*
G03X1767854Y453947I-1502J1D01*
G02X1767789Y454094I135J148D01*
G01Y454388D01*
G02X1767854Y454535I200J-1D01*
G03X1768339Y455641I-1017J1105D01*
G03X1765335I-1502J0D01*
G03X1765820Y454535I1502J-1D01*
G02X1765885Y454388I-135J-148D01*
G01Y454094D01*
G02X1765820Y453947I-200J1D01*
G03X1765335Y452841I1017J-1105D01*
G03X1765820Y451735I1502J-1D01*
G02X1765885Y451588I-135J-148D01*
G01Y451294D01*
G02X1765820Y451147I-200J1D01*
G03X1765538Y450796I1017J-1106D01*
G02X1765365Y450696I-173J100D01*
G01X1758316D01*
G02X1758143Y450796I0J200D01*
G03X1757861Y451147I-1299J-755D01*
G02X1757796Y451294I135J148D01*
G01Y451588D01*
G02X1757861Y451735I200J-1D01*
G03X1758346Y452841I-1017J1105D01*
G03X1757861Y453947I-1502J1D01*
G02X1757796Y454094I135J148D01*
G01Y454388D01*
G02X1757861Y454535I200J-1D01*
G03X1758346Y455641I-1017J1105D01*
G03X1755342I-1502J0D01*
G03X1755827Y454535I1502J-1D01*
G02X1755892Y454388I-135J-148D01*
G01Y454094D01*
G02X1755827Y453947I-200J1D01*
G03X1755342Y452841I1017J-1105D01*
G03X1755827Y451735I1502J-1D01*
G02X1755892Y451588I-135J-148D01*
G01Y451294D01*
G02X1755827Y451147I-200J1D01*
G03X1755545Y450796I1017J-1106D01*
G02X1755372Y450696I-173J100D01*
G01X1737714D01*
G02X1737537Y450801I-1J200D01*
G03X1734891I-1323J-709D01*
G02X1734714Y450696I-176J95D01*
G01X1734514D01*
G02X1734337Y450801I-1J200D01*
G03X1731691I-1323J-709D01*
G01X1731664Y450752D01*
X1731570Y450696D01*
X1731458D01*
X1731364Y450752D01*
X1731337Y450801D01*
G03X1728691I-1323J-709D01*
G02X1728514Y450696I-176J95D01*
G01X1725646D01*
X1725610Y450711D01*
G03X1724236I-687J-1667D01*
G01X1724200Y450696D01*
X1668387D01*
G03X1668245Y450637I0J-200D01*
G01X1667397Y449789D01*
G02X1667255Y449730I-142J141D01*
G01X1660812D01*
G02X1660670Y449789I0J200D01*
G01X1660251Y450208D01*
G02X1660192Y450350I141J142D01*
G01Y464268D01*
G03X1660133Y464410I-200J0D01*
G01X1657594Y466949D01*
G03X1657452Y467008I-142J-141D01*
G01X1655602D01*
G02X1655402Y467208I0J200D01*
G01Y467216D01*
X1655403Y467223D01*
G03X1655408Y467367I-1896J138D01*
G01Y470136D01*
G03X1655355Y470583I-1901J1D01*
G01X1655344Y470629D01*
X1655364Y470718D01*
X1655621Y471039D01*
X1655704Y471078D01*
X1655751Y471077D01*
X1655776D01*
G03X1654274Y472579I0J1502D01*
G03X1654280Y472443I1502J-2D01*
G01X1654284Y472396D01*
X1654252Y472310D01*
X1653951Y472031D01*
X1653863Y472004D01*
X1653817Y472012D01*
G03X1653507Y472038I-313J-1876D01*
G03X1651606Y470136I0J-1901D01*
G01Y468816D01*
G02X1651406Y468616I-201J0D01*
G01X1651098D01*
G02X1650898Y468816I1J200D01*
G01Y468852D01*
X1649845D01*
G03X1649305Y468670I-1J-890D01*
G02X1649184Y468628I-123J158D01*
G01X1648476D01*
G02X1648374Y468657I2J200D01*
G03X1647604Y468869I-769J-1290D01*
G03X1646163Y467790I0J-1502D01*
G01X1646152Y467755D01*
X1646108Y467697D01*
X1645821Y467517D01*
X1645749Y467502D01*
X1645713Y467508D01*
G03X1645465Y467529I-250J-1481D01*
G03X1644383Y467069I0J-1503D01*
G02X1644239Y467008I-144J139D01*
G01X1637263D01*
G02X1637063Y467208I0J200D01*
G01Y467214D01*
X1637064Y467221D01*
G03X1637068Y467337I-1799J120D01*
G01Y470737D01*
G03X1637066Y470813I-1803J-9D01*
G02X1637135Y470973I200J9D01*
G01X1637231Y471056D01*
G02X1637397Y471101I130J-152D01*
G03X1637665Y471077I267J1478D01*
G03Y474081I0J1502D01*
G03X1636182Y472814I0J-1501D01*
G01X1636175Y472772D01*
X1636130Y472703D01*
X1635814Y472492D01*
X1635733Y472478D01*
X1635692Y472488D01*
G03X1635265Y472540I-430J-1751D01*
G03X1634838Y472488I3J-1803D01*
G01X1634797Y472478D01*
X1634716Y472492D01*
X1634400Y472703D01*
X1634355Y472772D01*
X1634348Y472814D01*
G03X1632865Y474081I-1483J-234D01*
G03X1631878Y473711I0J-1501D01*
G01X1631850Y473687D01*
X1631783Y473662D01*
X1631447D01*
X1631380Y473687D01*
X1631352Y473711D01*
G03X1630365Y474081I-987J-1131D01*
G03X1630097Y474057I-1J-1502D01*
G02X1629931Y474102I-36J197D01*
G01X1629835Y474185D01*
G02X1629766Y474345I131J151D01*
G03X1629768Y474424I-1801J85D01*
G01Y477824D01*
G03X1629766Y477900I-1803J-9D01*
G02X1629835Y478060I200J9D01*
G01X1629931Y478143D01*
G02X1630097Y478188I130J-152D01*
G03X1630365Y478164I267J1478D01*
G03X1631352Y478534I0J1501D01*
G01X1631380Y478558D01*
X1631447Y478583D01*
X1631783D01*
X1631850Y478558D01*
X1631878Y478534D01*
G03X1632865Y478164I987J1131D01*
G03X1634349Y479432I0J1502D01*
G01X1634355Y479475D01*
X1634400Y479544D01*
X1634716Y479754D01*
X1634797Y479769D01*
X1634838Y479759D01*
G03X1635265Y479708I426J1751D01*
G03X1635691Y479759I0J1802D01*
G01X1635733Y479769D01*
X1635814Y479754D01*
X1636130Y479544D01*
X1636175Y479474D01*
X1636181Y479432D01*
G03X1637665Y478163I1484J233D01*
G03Y481167I0J1502D01*
G03X1637397Y481143I-1J-1502D01*
G02X1637231Y481188I-36J197D01*
G01X1637135Y481271D01*
G02X1637066Y481431I131J151D01*
G03X1637068Y481510I-1801J85D01*
G01Y484910D01*
G03X1637066Y484986I-1803J-9D01*
G02X1637135Y485146I200J9D01*
G01X1637231Y485229D01*
G02X1637397Y485274I130J-152D01*
G03X1637665Y485250I267J1478D01*
G03Y488254I0J1502D01*
G03X1636182Y486987I0J-1501D01*
G01X1636175Y486945D01*
X1636130Y486876D01*
X1635814Y486665D01*
X1635733Y486651D01*
X1635692Y486661D01*
G03X1635265Y486712I-426J-1751D01*
G03X1634838Y486661I-1J-1802D01*
G01X1634797Y486651D01*
X1634716Y486665D01*
X1634400Y486876D01*
X1634355Y486945D01*
X1634348Y486987D01*
G03X1632865Y488254I-1483J-234D01*
G03X1631878Y487884I0J-1501D01*
G01X1631850Y487860D01*
X1631783Y487835D01*
X1631447D01*
X1631380Y487860D01*
X1631352Y487884D01*
G03X1630365Y488254I-987J-1131D01*
G03X1630097Y488230I-1J-1502D01*
G02X1629931Y488275I-36J197D01*
G01X1629835Y488358D01*
G02X1629766Y488518I131J151D01*
G03X1629768Y488597I-1801J85D01*
G01Y491997D01*
G03X1629766Y492073I-1803J-9D01*
G02X1629835Y492233I200J9D01*
G01X1629931Y492316D01*
G02X1630097Y492361I130J-152D01*
G03X1630365Y492337I267J1478D01*
G03Y495341I0J1502D01*
G03X1628882Y494074I0J-1501D01*
G01X1628875Y494032D01*
X1628830Y493963D01*
X1628514Y493752D01*
X1628433Y493738D01*
X1628392Y493748D01*
G03X1627965Y493800I-430J-1751D01*
G03X1627538Y493748I3J-1803D01*
G01X1627497Y493738D01*
X1627416Y493752D01*
X1627100Y493963D01*
X1627055Y494032D01*
X1627048Y494074D01*
G03X1625565Y495341I-1483J-234D01*
G03Y492337I0J-1502D01*
G03X1625833Y492361I1J1502D01*
G02X1625999Y492316I36J-197D01*
G01X1626095Y492233D01*
G02X1626164Y492073I-131J-151D01*
G03X1626162Y491997I1801J-85D01*
G01Y488597D01*
G03X1626164Y488518I1803J6D01*
G02X1626095Y488358I-200J-9D01*
G01X1625999Y488275D01*
G02X1625833Y488230I-130J152D01*
G03X1625565Y488254I-267J-1478D01*
G03Y485250I0J-1502D01*
G03X1627049Y486519I0J1502D01*
G01X1627055Y486561D01*
X1627100Y486631D01*
X1627416Y486841D01*
X1627497Y486856D01*
X1627539Y486846D01*
G03X1627965Y486794I430J1751D01*
G03X1628391Y486846I-4J1803D01*
G01X1628433Y486856D01*
X1628514Y486841D01*
X1628830Y486631D01*
X1628875Y486561D01*
X1628881Y486519D01*
G03X1630365Y485250I1484J233D01*
G03X1631352Y485620I0J1501D01*
G01X1631380Y485644D01*
X1631447Y485669D01*
X1631783D01*
X1631850Y485644D01*
X1631878Y485620D01*
G03X1632865Y485250I987J1131D01*
G03X1633133Y485274I1J1502D01*
G02X1633299Y485229I36J-197D01*
G01X1633395Y485146D01*
G02X1633464Y484986I-131J-151D01*
G03X1633462Y484910I1801J-85D01*
G01Y481510D01*
G03X1633464Y481432I1803J7D01*
G02X1633395Y481272I-200J-9D01*
G01X1633299Y481189D01*
G02X1633133Y481144I-130J152D01*
G03X1632865Y481168I-267J-1478D01*
G03X1631878Y480798I0J-1501D01*
G01X1631850Y480774D01*
X1631783Y480749D01*
X1631447D01*
X1631380Y480774D01*
X1631352Y480798D01*
G03X1630365Y481168I-987J-1131D01*
G03X1628882Y479901I0J-1501D01*
G01X1628875Y479859D01*
X1628830Y479790D01*
X1628514Y479579D01*
X1628433Y479565D01*
X1628392Y479575D01*
G03X1627965Y479626I-426J-1751D01*
G03X1627538Y479575I-1J-1802D01*
G01X1627497Y479565D01*
X1627416Y479579D01*
X1627100Y479790D01*
X1627055Y479859D01*
X1627048Y479901D01*
G03X1625565Y481168I-1483J-234D01*
G03Y478164I0J-1502D01*
G03X1625833Y478188I1J1502D01*
G02X1625999Y478143I36J-197D01*
G01X1626095Y478060D01*
G02X1626164Y477900I-131J-151D01*
G03X1626162Y477824I1801J-85D01*
G01Y474424D01*
G03X1626164Y474345I1803J6D01*
G02X1626095Y474185I-200J-9D01*
G01X1625999Y474102D01*
G02X1625833Y474057I-130J152D01*
G03X1625565Y474081I-267J-1478D01*
G03Y471077I0J-1502D01*
G03X1627049Y472346I0J1502D01*
G01X1627055Y472388D01*
X1627100Y472458D01*
X1627416Y472668D01*
X1627497Y472683D01*
X1627539Y472673D01*
G03X1627965Y472622I426J1751D01*
G03X1628391Y472673I0J1802D01*
G01X1628433Y472683D01*
X1628514Y472668D01*
X1628830Y472458D01*
X1628875Y472388D01*
X1628881Y472346D01*
G03X1630365Y471077I1484J233D01*
G03X1631352Y471447I0J1501D01*
G01X1631380Y471471D01*
X1631447Y471496D01*
X1631783D01*
X1631850Y471471D01*
X1631878Y471447D01*
G03X1632865Y471077I987J1131D01*
G03X1633133Y471101I1J1502D01*
G02X1633299Y471056I36J-197D01*
G01X1633395Y470973D01*
G02X1633464Y470813I-131J-151D01*
G03X1633462Y470737I1801J-85D01*
G01Y467337D01*
G03X1633466Y467221I1803J4D01*
G01X1633467Y467214D01*
Y467208D01*
G02X1633267Y467008I-200J0D01*
G01X1630815D01*
G03X1630673Y466949I0J-200D01*
G01X1627944Y464220D01*
G03X1627885Y464078I141J-142D01*
G01Y455311D01*
G02X1627826Y455170I-200J1D01*
G01X1627043Y454386D01*
G03X1626380Y452787I1599J-1600D01*
G01Y451774D01*
G02X1626320Y451632I-200J1D01*
G01X1626086Y451403D01*
X1626013Y451374D01*
X1625972Y451375D01*
X1625938D01*
G03Y448371I0J-1502D01*
G01X1625972D01*
X1626013Y448372D01*
X1626086Y448343D01*
X1626320Y448114D01*
G02X1626380Y447972I-140J-143D01*
G01Y446005D01*
G02X1626322Y445863I-200J-1D01*
G01X1625735Y445276D01*
G02X1625593Y445218I-141J142D01*
G01X1623955D01*
G03X1622267Y444461I1J-2262D01*
G02X1622118Y444394I-149J133D01*
G01X1614734D01*
G03X1614592Y444335I0J-200D01*
G01X1608654Y438397D01*
G03X1608595Y438255I141J-142D01*
G01Y422511D01*
G03X1608654Y422369I200J0D01*
G01X1611718Y419305D01*
G03X1611860Y419246I142J141D01*
G01X1635113D01*
G02X1635266Y419175I0J-200D01*
G03X1638101Y417853I2835J2379D01*
G03X1641803Y421555I0J3702D01*
G03X1641778Y421983I-3702J-2D01*
G01X1641773Y422026D01*
X1641798Y422106D01*
X1642026Y422362D01*
G02X1642175Y422429I149J-133D01*
G01X1642896D01*
G02X1643045Y422362I0J-200D01*
G01X1643273Y422106D01*
X1643298Y422026D01*
X1643293Y421983D01*
G03X1643268Y421555I3677J-430D01*
G03X1646970Y417854I3701J0D01*
G01X1654270D01*
G03X1657972Y421555I0J3702D01*
G03X1657947Y421983I-3702J-2D01*
G01X1657942Y422026D01*
X1657967Y422106D01*
X1658195Y422362D01*
G02X1658344Y422429I149J-133D01*
G01X1663042D01*
G02X1663191Y422362I0J-200D01*
G01X1663419Y422106D01*
X1663444Y422026D01*
X1663439Y421983D01*
G03X1663414Y421555I3677J-430D01*
G03X1670818I3702J0D01*
G03X1670793Y421983I-3702J-2D01*
G01X1670788Y422026D01*
X1670813Y422106D01*
X1671041Y422362D01*
G02X1671190Y422429I149J-133D01*
G01X1690929D01*
G02X1691071Y422370I0J-200D01*
G01X1706532Y406909D01*
G02X1706591Y406767I-141J-142D01*
G01Y318988D01*
G02X1706532Y318846I-200J0D01*
G01X1698274Y310588D01*
G02X1698132Y310529I-142J141D01*
G01X1595445D01*
G02X1595303Y310588I0J200D01*
G01X1587045Y318846D01*
G02X1586986Y318988I141J142D01*
G01Y332917D01*
G02X1587045Y333059I200J0D01*
G01X1588427Y334441D01*
G02X1588569Y334500I142J-141D01*
G01X1596417D01*
G03X1596559Y334559I0J200D01*
G01X1597941Y335941D01*
G03X1598000Y336083I-141J142D01*
G01Y344917D01*
G03X1597941Y345059I-200J0D01*
G01X1597059Y345941D01*
G03X1596917Y346000I-142J-141D01*
G01X1588083D01*
G02X1587941Y346059I0J200D01*
G01X1587045Y346955D01*
G02X1586986Y347097I141J142D01*
G01Y387605D01*
X1587061Y387710D01*
X1587122Y387730D01*
G03Y390576I-483J1423D01*
G01X1587061Y390596D01*
X1586986Y390701D01*
Y394692D01*
X1587061Y394797D01*
X1587122Y394817D01*
G03Y397663I-483J1423D01*
G01X1587061Y397683D01*
X1586986Y397788D01*
Y401778D01*
X1587061Y401883D01*
X1587122Y401903D01*
G03Y404749I-483J1423D01*
G01X1587061Y404769D01*
X1586986Y404874D01*
Y408865D01*
X1587061Y408970D01*
X1587122Y408990D01*
G03Y411836I-483J1423D01*
G01X1587061Y411856D01*
X1586986Y411961D01*
Y415951D01*
X1587061Y416056D01*
X1587122Y416076D01*
G03Y418922I-483J1423D01*
G01X1587061Y418942D01*
X1586986Y419047D01*
Y423038D01*
X1587061Y423143D01*
X1587122Y423163D01*
G03Y426009I-483J1423D01*
G01X1587061Y426029D01*
X1586986Y426134D01*
Y430125D01*
X1587061Y430230D01*
X1587122Y430250D01*
G03Y433096I-483J1423D01*
G01X1587061Y433116D01*
X1586986Y433221D01*
Y437212D01*
X1587061Y437317D01*
X1587122Y437337D01*
G03Y440183I-483J1423D01*
G01X1587061Y440203D01*
X1586986Y440308D01*
Y465991D01*
X1587061Y466096D01*
X1587122Y466116D01*
G03Y468962I-483J1423D01*
G01X1587061Y468982D01*
X1586986Y469087D01*
Y473078D01*
X1587061Y473183D01*
X1587122Y473203D01*
G03Y476049I-483J1423D01*
G01X1587061Y476069D01*
X1586986Y476174D01*
Y480164D01*
X1587061Y480269D01*
X1587122Y480289D01*
G03Y483135I-483J1423D01*
G01X1587061Y483155D01*
X1586986Y483260D01*
Y487251D01*
X1587061Y487356D01*
X1587122Y487376D01*
G03X1588142Y488799I-483J1423D01*
G03X1587701Y489862I-1502J0D01*
G02Y490145I141J141D01*
G01X1612415Y514859D01*
G02X1612557Y514918I142J-141D01*
G01X1633262D01*
G02X1633462Y514718I0J-200D01*
G01Y511471D01*
G03X1633464Y511392I1803J6D01*
G02X1633395Y511232I-200J-9D01*
G01X1633299Y511149D01*
G02X1633133Y511104I-130J152D01*
G03X1632865Y511128I-267J-1478D01*
G03Y508124I0J-1502D01*
G03X1634349Y509393I0J1502D01*
G01X1634355Y509435D01*
X1634400Y509505D01*
X1634716Y509715D01*
X1634797Y509730D01*
X1634839Y509720D01*
G03X1635265Y509668I430J1751D01*
G03X1635691Y509720I-4J1803D01*
G01X1635733Y509730D01*
X1635814Y509715D01*
X1636130Y509505D01*
X1636175Y509435D01*
X1636181Y509393D01*
G03X1637665Y508124I1484J233D01*
G03Y511128I0J1502D01*
G03X1637397Y511104I-1J-1502D01*
G02X1637231Y511149I-36J197D01*
G01X1637135Y511232D01*
G02X1637066Y511392I131J151D01*
G03X1637068Y511471I-1801J85D01*
G01Y514718D01*
G02X1637268Y514918I200J0D01*
G01X1644258D01*
G02X1644396Y514863I0J-200D01*
G01X1644624Y514645D01*
X1644656Y514576D01*
X1644658Y514537D01*
G03X1647658I1500J71D01*
G01X1647660Y514576D01*
X1647692Y514645D01*
X1647920Y514863D01*
G02X1648058Y514918I138J-145D01*
G01X1688312D01*
G02X1688482Y514824I0J-200D01*
G03X1689757Y514115I1275J792D01*
G03X1689989Y514133I0J1502D01*
G01X1690032Y514140D01*
X1690116Y514116D01*
X1690381Y513890D01*
G02X1690450Y513738I-131J-151D01*
G01Y512540D01*
G02X1690381Y512388I-200J-1D01*
G01X1690116Y512162D01*
X1690032Y512138D01*
X1689989Y512145D01*
G03X1689757Y512163I-232J-1484D01*
G03Y509159I0J-1502D01*
G03X1690980Y509788I1J1502D01*
G02X1691099Y509867I163J-116D01*
G01X1691218Y509894D01*
G02X1691361Y509873I44J-195D01*
G03X1692253Y509636I893J1566D01*
G03X1693145Y509873I-1J1803D01*
G02X1693288Y509894I99J-174D01*
G01X1693407Y509867D01*
G02X1693526Y509788I-44J-195D01*
G03X1694749Y509159I1222J873D01*
G03Y512163I0J1502D01*
G03X1694517Y512145I0J-1502D01*
G01X1694474Y512138D01*
X1694390Y512162D01*
X1694125Y512388D01*
G02X1694056Y512540I131J151D01*
G01Y513738D01*
G02X1694125Y513890I200J1D01*
G01X1694390Y514116D01*
X1694474Y514140D01*
X1694517Y514133D01*
G03X1694749Y514115I232J1484D01*
G03X1696024Y514824I0J1501D01*
G02X1696194Y514918I170J-106D01*
G37*
G36*
G01X1600401Y203641D02*
X1611609D01*
X1612581Y202669D01*
Y195995D01*
X1611027Y194441D01*
X1599882D01*
X1599170Y195153D01*
Y202410D01*
X1600401Y203641D01*
G37*
G36*
G01X1658564Y174205D02*
X1662116D01*
G02X1662256Y174148I0J-200D01*
G01X1662257Y174147D01*
X1664459Y171945D01*
G02X1664461Y171943I-140J-142D01*
G02X1664518Y171803I-143J-140D01*
G01Y147990D01*
G02X1664408Y147811I-200J0D01*
G01X1664090Y147650D01*
G02X1663880Y147668I-90J178D01*
G03X1662986Y147963I-894J-1207D01*
G03Y144959I0J-1502D01*
G03X1663880Y145254I0J1502D01*
G02X1664090Y145272I120J-160D01*
G01X1664408Y145111D01*
G02X1664518Y144932I-90J-179D01*
G01Y138227D01*
X1664445Y138124D01*
X1664385Y138103D01*
G03X1663684Y137587I502J-1416D01*
G01X1663663Y137559D01*
X1663576Y137501D01*
G02X1663509Y137473I-109J168D01*
G01X1663390Y137446D01*
X1663316Y137457D01*
X1663283Y137475D01*
G03X1662982Y137612I-894J-1565D01*
G03X1662391Y137712I-592J-1703D01*
G03X1661800Y137612I1J-1803D01*
G03X1661499Y137475I593J-1702D01*
G01X1661466Y137457D01*
X1661392Y137446D01*
X1661273Y137473D01*
G02X1661206Y137501I42J196D01*
G01X1661118Y137560D01*
X1661098Y137588D01*
G03X1659895Y138189I-1202J-901D01*
G01X1659852D01*
X1659851Y138188D01*
G03X1658393Y136687I44J-1501D01*
G03X1659895Y135185I1502J0D01*
G03X1660127Y135203I0J1502D01*
G01X1660170Y135210D01*
X1660254Y135186D01*
X1660552Y134932D01*
X1660588Y134853D01*
Y133610D01*
Y133565D01*
X1660552Y133486D01*
X1660254Y133232D01*
X1660170Y133208D01*
X1660127Y133215D01*
G03X1659892Y133233I-232J-1484D01*
G01X1659891D01*
G03X1658393Y131731I4J-1502D01*
G03X1659895Y130229I1502J0D01*
G01X1659896D01*
G03X1661098Y130830I0J1502D01*
G01X1661118Y130858D01*
X1661206Y130917D01*
G02X1661273Y130945I109J-168D01*
G01X1661392Y130972D01*
X1661466Y130961D01*
X1661499Y130943D01*
G03X1661800Y130806I894J1565D01*
G03X1662391Y130706I592J1703D01*
G03X1662982Y130806I-1J1803D01*
G03X1663283Y130943I-593J1702D01*
G01X1663316Y130961D01*
X1663390Y130972D01*
X1663509Y130945D01*
G02X1663576Y130917I-42J-196D01*
G01X1663663Y130859D01*
X1663684Y130831D01*
G03X1664385Y130315I1203J900D01*
G01X1664445Y130294D01*
X1664518Y130191D01*
Y124053D01*
X1664445Y123950D01*
X1664385Y123929D01*
G03X1663684Y123413I502J-1416D01*
G01X1663663Y123385D01*
X1663576Y123327D01*
G02X1663509Y123299I-109J168D01*
G01X1663390Y123272D01*
X1663316Y123283D01*
X1663283Y123301D01*
G03X1662982Y123438I-894J-1565D01*
G03X1662391Y123538I-592J-1703D01*
G03X1661800Y123438I1J-1803D01*
G03X1661499Y123301I593J-1702D01*
G01X1661466Y123283D01*
X1661392Y123272D01*
X1661273Y123299D01*
G02X1661206Y123327I42J196D01*
G01X1661118Y123386D01*
X1661098Y123414D01*
G03X1659895Y124015I-1202J-901D01*
G01X1659852D01*
X1659851Y124014D01*
G03X1658393Y122513I44J-1501D01*
G03X1659895Y121011I1502J0D01*
G03X1660127Y121029I0J1502D01*
G01X1660170Y121036D01*
X1660254Y121012D01*
X1660552Y120758D01*
X1660588Y120679D01*
Y119436D01*
Y119391D01*
X1660552Y119312D01*
X1660254Y119058D01*
X1660170Y119034D01*
X1660127Y119041D01*
G03X1659892Y119059I-232J-1484D01*
G01X1659891D01*
G03X1658393Y117557I4J-1502D01*
G03X1659895Y116055I1502J0D01*
G01X1659896D01*
G03X1661098Y116656I0J1502D01*
G01X1661118Y116684D01*
X1661206Y116743D01*
G02X1661273Y116771I109J-168D01*
G01X1661392Y116798D01*
X1661466Y116787D01*
X1661499Y116769D01*
G03X1661800Y116632I894J1565D01*
G03X1662391Y116532I592J1703D01*
G03X1662982Y116632I-1J1803D01*
G03X1663283Y116769I-593J1702D01*
G01X1663316Y116787D01*
X1663390Y116798D01*
X1663509Y116771D01*
G02X1663576Y116743I-42J-196D01*
G01X1663663Y116685D01*
X1663684Y116657D01*
G03X1664385Y116141I1203J900D01*
G01X1664445Y116120D01*
X1664518Y116017D01*
Y78102D01*
G02X1664492Y78003I-200J0D01*
G01X1664432Y77899D01*
X1664400Y77865D01*
X1664379Y77851D01*
G03X1663941Y77421I811J-1264D01*
G01X1663940Y77420D01*
Y77419D01*
G02X1663806Y77334I-165J113D01*
G01X1663517Y77288D01*
G02X1663363Y77327I-32J197D01*
G03X1662442Y77642I-920J-1187D01*
G01X1662412D01*
G03X1660940Y76140I30J-1502D01*
G03X1662442Y74638I1502J0D01*
G01X1662458D01*
X1662518Y74639D01*
X1662621Y74572D01*
X1662788Y74174D01*
G02X1662745Y73955I-184J-78D01*
G01X1661291Y72501D01*
X1661263Y72472D01*
X1661189Y72442D01*
X1615076D01*
G02X1614934Y72501I0J200D01*
G01X1613618Y73817D01*
X1613589Y73845D01*
X1613559Y73919D01*
Y100421D01*
G02X1613618Y100563I200J0D01*
G01X1613820Y100763D01*
G02X1613961Y100821I141J-142D01*
G01X1613972D01*
G03Y103825I0J1502D01*
G01X1613961D01*
G02X1613820Y103883I0J200D01*
G01X1613618Y104083D01*
G02X1613559Y104225I141J142D01*
G01Y107508D01*
G02X1613618Y107650I200J0D01*
G01X1613820Y107850D01*
G02X1613961Y107908I141J-142D01*
G01X1613972D01*
G03Y110912I0J1502D01*
G01X1613961D01*
G02X1613820Y110970I0J200D01*
G01X1613618Y111170D01*
G02X1613559Y111312I141J142D01*
G01Y114594D01*
G02X1613618Y114736I200J0D01*
G01X1613820Y114936D01*
G02X1613961Y114994I141J-142D01*
G01X1613972D01*
G03Y117998I0J1502D01*
G01X1613961D01*
G02X1613820Y118056I0J200D01*
G01X1613618Y118256D01*
G02X1613559Y118398I141J142D01*
G01Y121681D01*
G02X1613618Y121823I200J0D01*
G01X1613820Y122023D01*
G02X1613961Y122081I141J-142D01*
G01X1613972D01*
G03Y125085I0J1502D01*
G01X1613961D01*
G02X1613820Y125143I0J200D01*
G01X1613618Y125343D01*
G02X1613559Y125485I141J142D01*
G01Y128768D01*
G02X1613618Y128910I200J0D01*
G01X1613820Y129110D01*
G02X1613961Y129168I141J-142D01*
G01X1613972D01*
G03Y132172I0J1502D01*
G01X1613961D01*
G02X1613820Y132230I0J200D01*
G01X1613618Y132430D01*
G02X1613559Y132572I141J142D01*
G01Y135854D01*
G02X1613618Y135996I200J0D01*
G01X1613820Y136196D01*
G02X1613961Y136254I141J-142D01*
G01X1613972D01*
G03Y139258I0J1502D01*
G01X1613961D01*
G02X1613820Y139316I0J200D01*
G01X1613618Y139516D01*
G02X1613559Y139658I141J142D01*
G01Y172123D01*
G02X1613616Y172263I200J0D01*
G01X1613617Y172264D01*
X1615499Y174146D01*
G02X1615501Y174148I142J-140D01*
G02X1615641Y174205I140J-143D01*
G01X1655570D01*
G02X1655756Y174078I0J-200D01*
G01X1655915Y173673D01*
X1655888Y173554D01*
X1655842Y173512D01*
G03X1655265Y172190I1226J-1322D01*
G03X1658869I1802J0D01*
G03X1658858Y172390I-1802J1D01*
G01X1658859D01*
G03X1658292Y173512I-1792J-201D01*
G01X1658247Y173555D01*
X1658219Y173674D01*
X1658378Y174078D01*
G02X1658564Y174205I186J-73D01*
G37*
G36*
G01X1650171Y1136005D02*
X1651797D01*
G02X1651871Y1135991I0J-200D01*
G01X1651970Y1135952D01*
X1651996Y1135929D01*
G03X1652737Y1135612I858J980D01*
G01X1652773Y1135609D01*
X1652836Y1135579D01*
X1654128Y1134287D01*
G03X1654270Y1134228I142J141D01*
G01X1655079D01*
G02X1655246Y1134138I0J-200D01*
G01X1655458Y1133815D01*
X1655466Y1133715D01*
X1655446Y1133668D01*
G03X1655342Y1133169I1148J-500D01*
G03X1657846I1252J0D01*
G03X1657742Y1133668I-1252J-1D01*
G01X1657722Y1133715D01*
X1657730Y1133815D01*
X1657942Y1134138D01*
G02X1658109Y1134228I167J-110D01*
G01X1658162D01*
G02X1658304Y1134169I0J-200D01*
G01X1658618Y1133855D01*
G02X1658677Y1133713I-141J-142D01*
G01Y1126997D01*
G02X1658477Y1126797I-200J0D01*
G01X1650735D01*
X1650661Y1126827D01*
X1650633Y1126856D01*
X1650162Y1127327D01*
X1650160D01*
X1649764Y1127724D01*
G02X1649707Y1127885I142J141D01*
G01X1649738Y1128193D01*
G02X1649827Y1128340I199J-20D01*
G01X1649828D01*
G03X1650416Y1129429I-714J1089D01*
G03X1647812I-1302J0D01*
G03X1648008Y1128742I1302J0D01*
G01X1648037Y1128695D01*
X1648040Y1128587D01*
X1647843Y1128233D01*
G02X1647668Y1128130I-175J97D01*
G01X1642985D01*
G02X1642785Y1128330I0J200D01*
G01Y1128821D01*
X1642805Y1128863D01*
G03Y1129995I-1171J566D01*
G01X1642785Y1130037D01*
Y1132561D01*
X1642805Y1132603D01*
G03Y1133735I-1171J566D01*
G01X1642785Y1133777D01*
Y1135292D01*
G02X1642844Y1135434I200J0D01*
G01X1643356Y1135946D01*
G02X1643498Y1136005I142J-141D01*
G01X1644317D01*
G02X1644391Y1135991I0J-200D01*
G01X1644491Y1135951D01*
X1644518Y1135929D01*
G03X1645842Y1135694I857J980D01*
G01X1645876Y1135708D01*
X1646794D01*
G03X1647060Y1135794I1J451D01*
G02X1647178Y1135833I119J-161D01*
G01X1647310D01*
G02X1647428Y1135794I-1J-200D01*
G03X1647694Y1135708I265J365D01*
G01X1648612D01*
X1648646Y1135694D01*
G03X1649970Y1135929I467J1215D01*
G01X1649997Y1135951D01*
X1650097Y1135991D01*
G02X1650171Y1136005I74J-186D01*
G37*
G36*
G01X1713642Y54588D02*
X1742687D01*
X1742830Y54445D01*
Y52734D01*
X1742687Y52591D01*
X1713642D01*
G03X1707705Y46654I0J-5937D01*
G01Y7874D01*
G02X1701831Y2000I-5874J0D01*
G01X1654587D01*
G02X1648713Y7874I0J5874D01*
G01Y46210D01*
X1650710D01*
Y7874D01*
G03X1654585Y3998I3876J0D01*
G01X1701831D01*
G03X1705708Y7874I0J3877D01*
G01Y46654D01*
G02X1713642Y54588I7934J0D01*
G37*
G36*
G01X1659898Y429263D02*
X1656103D01*
X1654662D01*
X1653423D01*
X1652564Y430122D01*
Y456169D01*
X1653073Y456678D01*
X1658497D01*
X1658924Y456251D01*
Y445974D01*
X1659898Y445000D01*
Y429263D01*
G37*
G36*
G01X1657771Y990823D02*
G03I-680J0D01*
G37*
G36*
G01X1652183Y1124859D02*
X1658347D01*
G02X1658489Y1124800I0J-200D01*
G01X1658978Y1124311D01*
G02X1659037Y1124169I-141J-142D01*
G01Y1122074D01*
G02X1659036Y1122058I-200J4D01*
G03X1659032Y1121949I1298J-102D01*
G01Y1121947D01*
G03X1659036Y1121838I1302J-7D01*
G02X1659037Y1121822I-199J-20D01*
G01Y1118334D01*
G02X1659036Y1118318I-200J4D01*
G03X1659032Y1118209I1298J-102D01*
G01Y1118207D01*
G03X1659036Y1118098I1302J-7D01*
G02X1659037Y1118082I-199J-20D01*
G01Y1117749D01*
Y1116548D01*
X1658586Y1116097D01*
X1653743D01*
X1652172D01*
G02X1651972Y1116297I0J200D01*
G01Y1122420D01*
Y1124648D01*
X1652183Y1124859D01*
G37*
G36*
G01X1652399Y1178697D02*
X1653300D01*
G02X1653442Y1178638I0J-200D01*
G01X1653576Y1178504D01*
G02X1653635Y1178362I-141J-142D01*
G01Y1151610D01*
G02X1653576Y1151468I-200J0D01*
G01X1653166Y1151058D01*
G02X1653024Y1150999I-142J141D01*
G01X1652092D01*
G02X1651950Y1151058I0J200D01*
G01X1651487Y1151521D01*
G02X1651428Y1151663I141J142D01*
G01Y1152427D01*
G02X1651487Y1152568I200J-1D01*
G01X1651501Y1152583D01*
X1651532Y1152656D01*
Y1177095D01*
G03X1651473Y1177236I-200J-1D01*
G01X1651460Y1177249D01*
X1651430Y1177322D01*
Y1177728D01*
G02X1651489Y1177870I200J0D01*
G01X1652257Y1178638D01*
G02X1652399Y1178697I142J-141D01*
G37*
G36*
G01X1659642Y1178766D02*
X1660982D01*
G02X1661124Y1178707I0J-200D01*
G01X1661177Y1178654D01*
G02X1661223Y1178582I-142J-141D01*
G03X1661270Y1178474I480J145D01*
G01X1661283Y1178451D01*
X1661297Y1178401D01*
Y1177793D01*
X1661273Y1177727D01*
X1661250Y1177700D01*
G03X1660802Y1176475I1454J-1226D01*
G01Y1175680D01*
G03X1661250Y1174455I1902J1D01*
G02X1661297Y1174326I-153J-129D01*
G01Y1151404D01*
G02X1661238Y1151262I-200J0D01*
G01X1661084Y1151108D01*
X1661056Y1151079D01*
X1660982Y1151049D01*
X1660045D01*
G02X1659903Y1151108I0J200D01*
G01X1659761Y1151250D01*
X1659760Y1151251D01*
G03X1659716Y1151295I-1296J-1252D01*
G02X1659714Y1151297I140J142D01*
G01X1658993Y1152018D01*
G02X1658934Y1152160I141J142D01*
G01Y1153675D01*
G02X1658993Y1153816I200J-1D01*
G01X1658997Y1153821D01*
X1659028Y1153894D01*
Y1175745D01*
G03X1658969Y1175886I-200J-1D01*
G01X1658964Y1175891D01*
X1658934Y1175964D01*
Y1178058D01*
G02X1658993Y1178200I200J0D01*
G01X1659500Y1178707D01*
G02X1659642Y1178766I142J-141D01*
G37*
G36*
G01X1649114Y1176749D02*
G03X1649804Y1176948I-2J1302D01*
G01X1649828Y1176963D01*
X1649882Y1176978D01*
X1650232D01*
G02X1650374Y1176919I0J-200D01*
G01X1650471Y1176822D01*
G02X1650530Y1176680I-141J-142D01*
G01Y1153111D01*
G02X1650471Y1152969I-200J0D01*
G01X1650341Y1152839D01*
X1650313Y1152810D01*
X1650239Y1152780D01*
X1650126D01*
G02X1650053Y1152794I0J200D01*
G01X1650019Y1152807D01*
X1649991Y1152832D01*
G03X1648237I-877J-961D01*
G02X1648102Y1152780I-135J148D01*
G01X1647531D01*
G02X1647389Y1152839I0J200D01*
G01X1646877Y1153351D01*
X1646848Y1153379D01*
X1646818Y1153453D01*
Y1176443D01*
G02X1646877Y1176585I200J0D01*
G01X1647211Y1176919D01*
G02X1647353Y1176978I142J-141D01*
G01X1648318D01*
G02X1648340Y1176977I2J-200D01*
G02X1648389Y1176965I-23J-199D01*
G02X1648424Y1176947I-73J-186D01*
G03X1649114Y1176749I690J1104D01*
G37*
G36*
G01X1657909Y1175530D02*
X1657967Y1175472D01*
G02X1658026Y1175330I-141J-142D01*
G01Y1154349D01*
G02X1657967Y1154207I-200J0D01*
G01X1657853Y1154093D01*
G02X1657711Y1154034I-142J141D01*
G01X1655014D01*
G02X1654872Y1154093I0J200D01*
G01X1654793Y1154172D01*
G02X1654734Y1154314I141J142D01*
G01Y1175221D01*
G02X1654793Y1175363I200J0D01*
G01X1654960Y1175530D01*
G02X1655102Y1175589I142J-141D01*
G01X1657767D01*
G02X1657909Y1175530I0J-200D01*
G37*
G36*
G01X1649813Y1461182D02*
G03I-491J0D01*
G37*
G36*
G01X1658474Y1460782D02*
G03I-491J0D01*
G37*
G36*
G01X1649813Y1456451D02*
G03I-491J0D01*
G37*
G36*
G01Y1465913D02*
G03I-491J0D01*
G37*
G36*
G01X1658474Y1465513D02*
G03I-491J0D01*
G37*
G36*
G01X1649813Y1476536D02*
G03I-491J0D01*
G37*
G36*
G01X1658474Y1476136D02*
G03I-491J0D01*
G37*
G36*
G01Y1470244D02*
G03I-491J0D01*
G37*
G36*
G01X1649813Y1471805D02*
G03I-491J0D01*
G37*
G36*
G01Y1481267D02*
G03I-491J0D01*
G37*
G36*
G01X1658474Y1480867D02*
G03I-491J0D01*
G37*
G36*
G01Y1491491D02*
G03I-491J0D01*
G37*
G36*
G01Y1485598D02*
G03I-491J0D01*
G37*
G36*
G01X1649813Y1487160D02*
G03I-491J0D01*
G37*
G36*
G01Y1496622D02*
G03I-491J0D01*
G37*
G36*
G01X1658474Y1496222D02*
G03I-491J0D01*
G37*
G36*
G01X1649813Y1491891D02*
G03I-491J0D01*
G37*
G36*
G01Y1511976D02*
G03I-491J0D01*
G37*
G36*
G01Y1507245D02*
G03I-491J0D01*
G37*
G36*
G01X1658474Y1506845D02*
G03I-491J0D01*
G37*
G36*
G01Y1500953D02*
G03I-491J0D01*
G37*
G36*
G01X1649813Y1502514D02*
G03I-491J0D01*
G37*
G36*
G01X1658474Y1511576D02*
G03I-491J0D01*
G37*
G36*
G01Y1516307D02*
G03I-491J0D01*
G37*
G36*
G01X1649813Y1558813D02*
G03I-491J0D01*
G37*
G36*
G01Y1578898D02*
G03I-491J0D01*
G37*
G36*
G01X1658474Y1578498D02*
G03I-491J0D01*
G37*
G36*
G01Y1572606D02*
G03I-491J0D01*
G37*
G36*
G01X1649813Y1574167D02*
G03I-491J0D01*
G37*
G36*
G01Y1563544D02*
G03I-491J0D01*
G37*
G36*
G01X1658474Y1563144D02*
G03I-491J0D01*
G37*
G36*
G01X1649813Y1568275D02*
G03I-491J0D01*
G37*
G36*
G01X1658474Y1567875D02*
G03I-491J0D01*
G37*
G36*
G01X1649813Y1583629D02*
G03I-491J0D01*
G37*
G36*
G01X1658474Y1583229D02*
G03I-491J0D01*
G37*
G36*
G01X1649813Y1594253D02*
G03I-491J0D01*
G37*
G36*
G01X1658474Y1593853D02*
G03I-491J0D01*
G37*
G36*
G01Y1587960D02*
G03I-491J0D01*
G37*
G36*
G01X1649813Y1589522D02*
G03I-491J0D01*
G37*
G36*
G01Y1609607D02*
G03I-491J0D01*
G37*
G36*
G01X1658474Y1609207D02*
G03I-491J0D01*
G37*
G36*
G01X1649813Y1598984D02*
G03I-491J0D01*
G37*
G36*
G01X1658474Y1598584D02*
G03I-491J0D01*
G37*
G36*
G01Y1603315D02*
G03I-491J0D01*
G37*
G36*
G01X1649813Y1604876D02*
G03I-491J0D01*
G37*
G36*
G01X1658474Y1618669D02*
G03I-491J0D01*
G37*
G36*
G01X1649813Y1614338D02*
G03I-491J0D01*
G37*
G36*
G01X1658474Y1613938D02*
G03I-491J0D01*
G37*
G36*
G01X1675379Y444701D02*
X1724461D01*
G02X1724603Y444642I0J-200D01*
G01X1726552Y442693D01*
G02X1726611Y442551I-141J-142D01*
G01Y411754D01*
G02X1726552Y411612I-200J0D01*
G01X1725904Y410964D01*
G02X1725762Y410905I-142J141D01*
G01X1706696D01*
G02X1706554Y410964I0J200D01*
G01X1692834Y424684D01*
G03X1692692Y424743I-142J-141D01*
G01X1676070D01*
G02X1675928Y424802I0J200D01*
G01X1671485Y429245D01*
G03X1671343Y429304I-142J-141D01*
G01X1661100D01*
G02X1660900Y429504I0J200D01*
G01Y444223D01*
G02X1660958Y444364I200J0D01*
G01X1661236Y444642D01*
G02X1661378Y444701I142J-141D01*
G01X1668206D01*
G02X1668355Y444635I0J-200D01*
G03X1669767Y444006I1413J1273D01*
G03X1671179Y444635I-1J1902D01*
G02X1671328Y444701I149J-134D01*
G01X1672055D01*
G02X1672213Y444623I0J-200D01*
G03X1673717Y443886I1503J1164D01*
G03X1675221Y444623I1J1901D01*
G02X1675379Y444701I158J-122D01*
G37*
G36*
G01X1668797Y1158830D02*
X1668414Y1158447D01*
X1668386Y1158418D01*
X1668312Y1158388D01*
X1663622D01*
G02X1663480Y1158447I0J200D01*
G01X1663192Y1158735D01*
X1663163Y1158763D01*
X1663133Y1158837D01*
Y1167436D01*
G02X1663192Y1167578I200J0D01*
G01X1663387Y1167773D01*
G02X1663529Y1167832I142J-141D01*
G01X1668429D01*
G02X1668571Y1167773I0J-200D01*
G01X1668797Y1167547D01*
G02X1668856Y1167405I-141J-142D01*
G01Y1158972D01*
G02X1668797Y1158830I-200J0D01*
G37*
G36*
G01X1680457Y1160430D02*
X1680068Y1160257D01*
X1679953Y1160276D01*
X1679908Y1160316D01*
G03X1679035Y1160652I-873J-966D01*
G03X1677733Y1159350I0J-1302D01*
G03X1677790Y1158966I1302J-3D01*
G01X1677804Y1158920D01*
X1677788Y1158827D01*
X1677569Y1158531D01*
G02X1677408Y1158450I-161J119D01*
G01X1673182D01*
G02X1673021Y1158531I0J200D01*
G01X1672830Y1158789D01*
G02X1672800Y1158966I161J118D01*
G03X1672857Y1159350I-1245J381D01*
G03X1671555Y1160652I-1302J0D01*
G01X1671554D01*
G03X1670618Y1160254I1J-1302D01*
G01X1670585Y1160219D01*
G03X1670576Y1160209I144J-139D01*
G01X1670562Y1160193D01*
G02X1670339Y1160134I-153J129D01*
G01X1669989Y1160264D01*
X1669929Y1160286D01*
X1669858Y1160388D01*
Y1165792D01*
X1669929Y1165894D01*
X1669989Y1165916D01*
X1670339Y1166046D01*
G02X1670562Y1165987I70J-188D01*
G01X1670580Y1165966D01*
X1670618Y1165926D01*
G03X1671555Y1165528I937J904D01*
G01X1671641D01*
G03X1671673Y1165531I-3J200D01*
G01X1671762Y1165545D01*
G03X1672845Y1166657I-207J1285D01*
G01X1672852Y1166707D01*
G03X1672751Y1167348I-1297J124D01*
G01X1672730Y1167394D01*
X1672739Y1167494D01*
X1672950Y1167816D01*
G02X1673117Y1167906I167J-110D01*
G01X1680024D01*
G02X1680057Y1167903I-2J-200D01*
G02X1680164Y1167849I-32J-197D01*
G01X1680517Y1167496D01*
G02X1680576Y1167354I-141J-142D01*
G01Y1160553D01*
X1680512Y1160454D01*
X1680457Y1160430D01*
G37*
G36*
G01X1667136Y1456451D02*
G03I-491J0D01*
G37*
G36*
G01Y1461182D02*
G03I-491J0D01*
G37*
G36*
G01X1675797Y1460782D02*
G03I-491J0D01*
G37*
G36*
G01X1667136Y1476536D02*
G03I-491J0D01*
G37*
G36*
G01Y1481267D02*
G03I-491J0D01*
G37*
G36*
G01X1675797Y1476136D02*
G03I-491J0D01*
G37*
G36*
G01Y1470244D02*
G03I-491J0D01*
G37*
G36*
G01Y1480867D02*
G03I-491J0D01*
G37*
G36*
G01X1667136Y1465913D02*
G03I-491J0D01*
G37*
G36*
G01X1675797Y1465513D02*
G03I-491J0D01*
G37*
G36*
G01X1667136Y1471805D02*
G03I-491J0D01*
G37*
G36*
G01Y1487160D02*
G03I-491J0D01*
G37*
G36*
G01Y1491891D02*
G03I-491J0D01*
G37*
G36*
G01Y1496622D02*
G03I-491J0D01*
G37*
G36*
G01X1675797Y1491491D02*
G03I-491J0D01*
G37*
G36*
G01Y1485598D02*
G03I-491J0D01*
G37*
G36*
G01Y1496222D02*
G03I-491J0D01*
G37*
G36*
G01Y1500953D02*
G03I-491J0D01*
G37*
G36*
G01Y1511576D02*
G03I-491J0D01*
G37*
G36*
G01X1667136Y1511976D02*
G03I-491J0D01*
G37*
G36*
G01Y1507245D02*
G03I-491J0D01*
G37*
G36*
G01Y1502514D02*
G03I-491J0D01*
G37*
G36*
G01X1675797Y1506845D02*
G03I-491J0D01*
G37*
G36*
G01Y1516307D02*
G03I-491J0D01*
G37*
G36*
G01X1667136Y1558813D02*
G03I-491J0D01*
G37*
G36*
G01X1675797Y1567875D02*
G03I-491J0D01*
G37*
G36*
G01X1667136Y1574167D02*
G03I-491J0D01*
G37*
G36*
G01X1675797Y1578498D02*
G03I-491J0D01*
G37*
G36*
G01Y1572606D02*
G03I-491J0D01*
G37*
G36*
G01X1667136Y1578898D02*
G03I-491J0D01*
G37*
G36*
G01Y1563544D02*
G03I-491J0D01*
G37*
G36*
G01X1675797Y1563144D02*
G03I-491J0D01*
G37*
G36*
G01X1667136Y1568275D02*
G03I-491J0D01*
G37*
G36*
G01X1675797Y1593853D02*
G03I-491J0D01*
G37*
G36*
G01Y1587960D02*
G03I-491J0D01*
G37*
G36*
G01X1667136Y1583629D02*
G03I-491J0D01*
G37*
G36*
G01X1675797Y1583229D02*
G03I-491J0D01*
G37*
G36*
G01X1667136Y1589522D02*
G03I-491J0D01*
G37*
G36*
G01Y1594253D02*
G03I-491J0D01*
G37*
G36*
G01Y1604876D02*
G03I-491J0D01*
G37*
G36*
G01Y1598984D02*
G03I-491J0D01*
G37*
G36*
G01X1675797Y1609207D02*
G03I-491J0D01*
G37*
G36*
G01Y1598584D02*
G03I-491J0D01*
G37*
G36*
G01Y1603315D02*
G03I-491J0D01*
G37*
G36*
G01X1667136Y1609607D02*
G03I-491J0D01*
G37*
G36*
G01X1675797Y1618669D02*
G03I-491J0D01*
G37*
G36*
G01X1667136Y1614338D02*
G03I-491J0D01*
G37*
G36*
G01X1675797Y1613938D02*
G03I-491J0D01*
G37*
G36*
G01X1681642Y1167234D02*
X1682087Y1167679D01*
G02X1682229Y1167738I142J-141D01*
G01X1687191D01*
G02X1687333Y1167679I0J-200D01*
G01X1687528Y1167484D01*
G02X1687587Y1167342I-141J-142D01*
G01Y1158940D01*
G02X1687528Y1158798I-200J0D01*
G01X1687271Y1158541D01*
G02X1687129Y1158482I-142J141D01*
G01X1682323D01*
G02X1682181Y1158541I0J200D01*
G01X1681642Y1159080D01*
G02X1681583Y1159222I141J142D01*
G01Y1167092D01*
G02X1681642Y1167234I200J0D01*
G37*
G36*
G01X1684459Y1456451D02*
G03I-491J0D01*
G37*
G36*
G01Y1461182D02*
G03I-491J0D01*
G37*
G36*
G01Y1465913D02*
G03I-491J0D01*
G37*
G36*
G01Y1471805D02*
G03I-491J0D01*
G37*
G36*
G01Y1476536D02*
G03I-491J0D01*
G37*
G36*
G01Y1481267D02*
G03I-491J0D01*
G37*
G36*
G01Y1487160D02*
G03I-491J0D01*
G37*
G36*
G01Y1491891D02*
G03I-491J0D01*
G37*
G36*
G01Y1496622D02*
G03I-491J0D01*
G37*
G36*
G01Y1507245D02*
G03I-491J0D01*
G37*
G36*
G01Y1502514D02*
G03I-491J0D01*
G37*
G36*
G01Y1511976D02*
G03I-491J0D01*
G37*
G36*
G01Y1558813D02*
G03I-491J0D01*
G37*
G36*
G01Y1578898D02*
G03I-491J0D01*
G37*
G36*
G01Y1563544D02*
G03I-491J0D01*
G37*
G36*
G01Y1568275D02*
G03I-491J0D01*
G37*
G36*
G01Y1574167D02*
G03I-491J0D01*
G37*
G36*
G01Y1583629D02*
G03I-491J0D01*
G37*
G36*
G01Y1589522D02*
G03I-491J0D01*
G37*
G36*
G01Y1594253D02*
G03I-491J0D01*
G37*
G36*
G01Y1609607D02*
G03I-491J0D01*
G37*
G36*
G01Y1604876D02*
G03I-491J0D01*
G37*
G36*
G01Y1598984D02*
G03I-491J0D01*
G37*
G36*
G01Y1614338D02*
G03I-491J0D01*
G37*
G36*
G01X1702763Y203641D02*
X1713971D01*
X1714943Y202669D01*
Y195995D01*
X1713389Y194441D01*
X1702244D01*
X1701532Y195153D01*
Y202410D01*
X1702763Y203641D01*
G37*
G36*
G01X1741912Y1066535D02*
G02I-17700J0D01*
G37*
G36*
G01Y1263386D02*
G02I-17700J0D01*
G37*
G36*
G01X1701781Y1456451D02*
G03I-491J0D01*
G37*
G36*
G01Y1461182D02*
G03I-491J0D01*
G37*
G36*
G01X1693120Y1460782D02*
G03I-491J0D01*
G37*
G36*
G01X1701781Y1465913D02*
G03I-491J0D01*
G37*
G36*
G01Y1471805D02*
G03I-491J0D01*
G37*
G36*
G01Y1476536D02*
G03I-491J0D01*
G37*
G36*
G01Y1481267D02*
G03I-491J0D01*
G37*
G36*
G01X1693120Y1465513D02*
G03I-491J0D01*
G37*
G36*
G01Y1476136D02*
G03I-491J0D01*
G37*
G36*
G01Y1470244D02*
G03I-491J0D01*
G37*
G36*
G01Y1480867D02*
G03I-491J0D01*
G37*
G36*
G01X1701781Y1487160D02*
G03I-491J0D01*
G37*
G36*
G01Y1491891D02*
G03I-491J0D01*
G37*
G36*
G01Y1496622D02*
G03I-491J0D01*
G37*
G36*
G01X1693120Y1491491D02*
G03I-491J0D01*
G37*
G36*
G01Y1485598D02*
G03I-491J0D01*
G37*
G36*
G01Y1496222D02*
G03I-491J0D01*
G37*
G36*
G01Y1511576D02*
G03I-491J0D01*
G37*
G36*
G01X1701781Y1507245D02*
G03I-491J0D01*
G37*
G36*
G01Y1502514D02*
G03I-491J0D01*
G37*
G36*
G01Y1511976D02*
G03I-491J0D01*
G37*
G36*
G01X1693120Y1506845D02*
G03I-491J0D01*
G37*
G36*
G01Y1500953D02*
G03I-491J0D01*
G37*
G36*
G01Y1516307D02*
G03I-491J0D01*
G37*
G36*
G01X1701781Y1558813D02*
G03I-491J0D01*
G37*
G36*
G01Y1578898D02*
G03I-491J0D01*
G37*
G36*
G01Y1563544D02*
G03I-491J0D01*
G37*
G36*
G01Y1568275D02*
G03I-491J0D01*
G37*
G36*
G01Y1574167D02*
G03I-491J0D01*
G37*
G36*
G01X1693120Y1563144D02*
G03I-491J0D01*
G37*
G36*
G01Y1572606D02*
G03I-491J0D01*
G37*
G36*
G01Y1567875D02*
G03I-491J0D01*
G37*
G36*
G01Y1578498D02*
G03I-491J0D01*
G37*
G36*
G01X1701781Y1583629D02*
G03I-491J0D01*
G37*
G36*
G01Y1589522D02*
G03I-491J0D01*
G37*
G36*
G01Y1594253D02*
G03I-491J0D01*
G37*
G36*
G01X1693120Y1583229D02*
G03I-491J0D01*
G37*
G36*
G01Y1593853D02*
G03I-491J0D01*
G37*
G36*
G01Y1587960D02*
G03I-491J0D01*
G37*
G36*
G01Y1603315D02*
G03I-491J0D01*
G37*
G36*
G01X1701781Y1609607D02*
G03I-491J0D01*
G37*
G36*
G01Y1604876D02*
G03I-491J0D01*
G37*
G36*
G01Y1598984D02*
G03I-491J0D01*
G37*
G36*
G01X1693120Y1609207D02*
G03I-491J0D01*
G37*
G36*
G01Y1598584D02*
G03I-491J0D01*
G37*
G36*
G01X1701781Y1614338D02*
G03I-491J0D01*
G37*
G36*
G01X1693120Y1613938D02*
G03I-491J0D01*
G37*
G36*
G01Y1618669D02*
G03I-491J0D01*
G37*
G36*
G01X1760926Y174205D02*
X1764478D01*
G02X1764618Y174148I0J-200D01*
G01X1764619Y174147D01*
X1766821Y171945D01*
G02X1766823Y171943I-140J-142D01*
G02X1766880Y171803I-143J-140D01*
G01Y138227D01*
X1766807Y138124D01*
X1766747Y138103D01*
G03X1766046Y137587I502J-1416D01*
G01X1766025Y137559D01*
X1765938Y137501D01*
G02X1765871Y137473I-109J168D01*
G01X1765752Y137446D01*
X1765678Y137457D01*
X1765645Y137475D01*
G03X1765344Y137612I-894J-1565D01*
G03X1764753Y137712I-592J-1703D01*
G03X1764162Y137612I1J-1803D01*
G03X1763861Y137475I593J-1702D01*
G01X1763828Y137457D01*
X1763754Y137446D01*
X1763635Y137473D01*
G02X1763568Y137501I42J196D01*
G01X1763480Y137560D01*
X1763460Y137588D01*
G03X1762257Y138189I-1202J-901D01*
G01X1762214D01*
X1762213Y138188D01*
G03X1760755Y136687I44J-1501D01*
G03X1762257Y135185I1502J0D01*
G03X1762489Y135203I0J1502D01*
G01X1762532Y135210D01*
X1762616Y135186D01*
X1762914Y134932D01*
X1762950Y134853D01*
Y133610D01*
Y133565D01*
X1762914Y133486D01*
X1762616Y133232D01*
X1762532Y133208D01*
X1762489Y133215D01*
G03X1762254Y133233I-232J-1484D01*
G01X1762253D01*
G03X1760755Y131731I4J-1502D01*
G03X1762257Y130229I1502J0D01*
G01X1762258D01*
G03X1763460Y130830I0J1502D01*
G01X1763480Y130858D01*
X1763568Y130917D01*
G02X1763635Y130945I109J-168D01*
G01X1763754Y130972D01*
X1763828Y130961D01*
X1763861Y130943D01*
G03X1764162Y130806I894J1565D01*
G03X1764753Y130706I592J1703D01*
G03X1765344Y130806I-1J1803D01*
G03X1765645Y130943I-593J1702D01*
G01X1765678Y130961D01*
X1765752Y130972D01*
X1765871Y130945D01*
G02X1765938Y130917I-42J-196D01*
G01X1766025Y130859D01*
X1766046Y130831D01*
G03X1766747Y130315I1203J900D01*
G01X1766807Y130294D01*
X1766880Y130191D01*
Y124053D01*
X1766807Y123950D01*
X1766747Y123929D01*
G03X1766046Y123413I502J-1416D01*
G01X1766025Y123385D01*
X1765938Y123327D01*
G02X1765871Y123299I-109J168D01*
G01X1765752Y123272D01*
X1765678Y123283D01*
X1765645Y123301D01*
G03X1765344Y123438I-894J-1565D01*
G03X1764753Y123538I-592J-1703D01*
G03X1764162Y123438I1J-1803D01*
G03X1763861Y123301I593J-1702D01*
G01X1763828Y123283D01*
X1763754Y123272D01*
X1763635Y123299D01*
G02X1763568Y123327I42J196D01*
G01X1763480Y123386D01*
X1763460Y123414D01*
G03X1762257Y124015I-1202J-901D01*
G01X1762214D01*
X1762213Y124014D01*
G03X1760755Y122513I44J-1501D01*
G03X1762257Y121011I1502J0D01*
G03X1762489Y121029I0J1502D01*
G01X1762532Y121036D01*
X1762616Y121012D01*
X1762914Y120758D01*
X1762950Y120679D01*
Y119436D01*
Y119391D01*
X1762914Y119312D01*
X1762616Y119058D01*
X1762532Y119034D01*
X1762489Y119041D01*
G03X1762254Y119059I-232J-1484D01*
G01X1762253D01*
G03X1760755Y117557I4J-1502D01*
G03X1762257Y116055I1502J0D01*
G01X1762258D01*
G03X1763460Y116656I0J1502D01*
G01X1763480Y116684D01*
X1763568Y116743D01*
G02X1763635Y116771I109J-168D01*
G01X1763754Y116798D01*
X1763828Y116787D01*
X1763861Y116769D01*
G03X1764162Y116632I894J1565D01*
G03X1764753Y116532I592J1703D01*
G03X1765344Y116632I-1J1803D01*
G03X1765645Y116769I-593J1702D01*
G01X1765678Y116787D01*
X1765752Y116798D01*
X1765871Y116771D01*
G02X1765938Y116743I-42J-196D01*
G01X1766025Y116685D01*
X1766046Y116657D01*
G03X1766747Y116141I1203J900D01*
G01X1766807Y116120D01*
X1766880Y116017D01*
Y78102D01*
G02X1766854Y78003I-200J0D01*
G01X1766794Y77899D01*
X1766762Y77865D01*
X1766741Y77851D01*
G03X1766303Y77421I811J-1264D01*
G01X1766302Y77420D01*
Y77419D01*
G02X1766168Y77334I-165J113D01*
G01X1765879Y77288D01*
G02X1765725Y77327I-32J197D01*
G03X1764804Y77642I-920J-1187D01*
G01X1764774D01*
G03X1763302Y76140I30J-1502D01*
G03X1764804Y74638I1502J0D01*
G01X1764820D01*
X1764880Y74639D01*
X1764983Y74572D01*
X1765150Y74174D01*
G02X1765107Y73955I-184J-78D01*
G01X1763653Y72501D01*
X1763625Y72472D01*
X1763551Y72442D01*
X1717438D01*
G02X1717296Y72501I0J200D01*
G01X1715980Y73817D01*
X1715951Y73845D01*
X1715921Y73919D01*
Y100421D01*
G02X1715980Y100563I200J0D01*
G01X1716182Y100763D01*
G02X1716323Y100821I141J-142D01*
G01X1716334D01*
G03Y103825I0J1502D01*
G01X1716323D01*
G02X1716182Y103883I0J200D01*
G01X1715980Y104083D01*
G02X1715921Y104225I141J142D01*
G01Y107508D01*
G02X1715980Y107650I200J0D01*
G01X1716182Y107850D01*
G02X1716323Y107908I141J-142D01*
G01X1716334D01*
G03Y110912I0J1502D01*
G01X1716323D01*
G02X1716182Y110970I0J200D01*
G01X1715980Y111170D01*
G02X1715921Y111312I141J142D01*
G01Y114594D01*
G02X1715980Y114736I200J0D01*
G01X1716182Y114936D01*
G02X1716323Y114994I141J-142D01*
G01X1716334D01*
G03Y117998I0J1502D01*
G01X1716323D01*
G02X1716182Y118056I0J200D01*
G01X1715980Y118256D01*
G02X1715921Y118398I141J142D01*
G01Y121681D01*
G02X1715980Y121823I200J0D01*
G01X1716182Y122023D01*
G02X1716323Y122081I141J-142D01*
G01X1716334D01*
G03Y125085I0J1502D01*
G01X1716323D01*
G02X1716182Y125143I0J200D01*
G01X1715980Y125343D01*
G02X1715921Y125485I141J142D01*
G01Y128768D01*
G02X1715980Y128910I200J0D01*
G01X1716182Y129110D01*
G02X1716323Y129168I141J-142D01*
G01X1716334D01*
G03Y132172I0J1502D01*
G01X1716323D01*
G02X1716182Y132230I0J200D01*
G01X1715980Y132430D01*
G02X1715921Y132572I141J142D01*
G01Y135854D01*
G02X1715980Y135996I200J0D01*
G01X1716182Y136196D01*
G02X1716323Y136254I141J-142D01*
G01X1716334D01*
G03Y139258I0J1502D01*
G01X1716323D01*
G02X1716182Y139316I0J200D01*
G01X1715980Y139516D01*
G02X1715921Y139658I141J142D01*
G01Y172123D01*
G02X1715978Y172263I200J0D01*
G01X1715979Y172264D01*
X1717861Y174146D01*
G02X1717863Y174148I142J-140D01*
G02X1718003Y174205I140J-143D01*
G01X1757932D01*
G02X1758118Y174078I0J-200D01*
G01X1758277Y173673D01*
X1758250Y173554D01*
X1758204Y173512D01*
G03X1757627Y172190I1226J-1322D01*
G03X1761231I1802J0D01*
G03X1761220Y172390I-1802J1D01*
G01X1761221D01*
G03X1760654Y173512I-1792J-201D01*
G01X1760609Y173555D01*
X1760581Y173674D01*
X1760740Y174078D01*
G02X1760926Y174205I186J-73D01*
G37*
G36*
G01X1788052Y448689D02*
X1789932D01*
G02X1790074Y448630I0J-200D01*
G01X1790810Y447894D01*
G02X1790869Y447752I-141J-142D01*
G01Y446641D01*
G03X1790928Y446499I200J0D01*
G01X1790936Y446491D01*
G02X1790995Y446349I-141J-142D01*
G01Y431892D01*
G02X1790936Y431750I-200J0D01*
G01X1790621Y431435D01*
G02X1790479Y431376I-142J141D01*
G01X1778975D01*
G03X1778833Y431317I0J-200D01*
G01X1778166Y430650D01*
G03X1778107Y430508I141J-142D01*
G01Y426996D01*
G02X1778048Y426854I-200J0D01*
G01X1777623Y426429D01*
G02X1777481Y426370I-142J141D01*
G01X1759780D01*
G03X1759638Y426311I0J-200D01*
G01X1759156Y425829D01*
G03X1759097Y425687I141J-142D01*
G01Y415233D01*
X1759093Y415229D01*
Y400761D01*
G03X1759152Y400619I200J0D01*
G01X1761159Y398612D01*
G02X1761218Y398470I-141J-142D01*
G01Y394678D01*
G02X1761159Y394536I-200J0D01*
G01X1761087Y394464D01*
G02X1760945Y394405I-142J141D01*
G01X1759949D01*
G03X1759807Y394346I0J-200D01*
G01X1755547Y390086D01*
G02X1755405Y390027I-142J141D01*
G01X1743303D01*
G02X1743128Y390129I-1J200D01*
G01X1742930Y390480D01*
X1742932Y390587D01*
X1742961Y390634D01*
G03X1743222Y391569I-1541J934D01*
G03X1739618I-1802J0D01*
G03X1739879Y390634I1802J-1D01*
G01X1739908Y390587D01*
X1739910Y390480D01*
X1739712Y390129D01*
G02X1739537Y390027I-174J98D01*
G01X1714731D01*
G02X1714589Y390086I0J200D01*
G01X1713092Y391583D01*
G02X1713033Y391725I141J142D01*
G01Y404332D01*
G02X1713092Y404474I200J0D01*
G01X1716938Y408320D01*
G02X1717080Y408379I142J-141D01*
G01X1726503D01*
G03X1726645Y408438I0J200D01*
G01X1727554Y409347D01*
G03X1727613Y409489I-141J142D01*
G01Y438319D01*
G02X1727733Y438503I200J1D01*
G01X1728123Y438674D01*
X1728240Y438654D01*
X1728284Y438614D01*
G03X1729302Y438216I1018J1103D01*
G03X1730804Y439718I0J1502D01*
G03X1730319Y440824I-1502J1D01*
G02X1730254Y440971I135J148D01*
G01Y441265D01*
G02X1730319Y441412I200J-1D01*
G03X1730804Y442518I-1017J1105D01*
G03X1729302Y444020I-1502J0D01*
G03X1727988Y443246I0J-1502D01*
G01X1727961Y443198D01*
X1727868Y443142D01*
X1727813D01*
G02X1727613Y443342I0J200D01*
G01Y443764D01*
G02X1727672Y443906I200J0D01*
G01X1729609Y445843D01*
X1729730Y445865D01*
X1729788Y445839D01*
G03X1730404Y445707I616J1371D01*
G03X1731906Y447209I0J1502D01*
G03X1731774Y447825I-1503J0D01*
G01X1731748Y447883D01*
X1731770Y448004D01*
X1732412Y448646D01*
X1732518Y448672D01*
X1732572Y448655D01*
G03X1733014Y448589I440J1436D01*
G03X1733521Y448677I0J1502D01*
G01X1733554Y448689D01*
X1735674D01*
X1735707Y448677D01*
G03X1736214Y448589I507J1414D01*
G03X1736721Y448677I0J1502D01*
G01X1736754Y448689D01*
X1737659D01*
X1737761Y448620D01*
X1737783Y448563D01*
G03X1738162Y448012I1396J555D01*
G02X1738227Y447865I-135J-148D01*
G01Y447571D01*
G02X1738162Y447424I-200J1D01*
G03X1737677Y446318I1017J-1105D01*
G03X1740681I1502J0D01*
G03X1740196Y447424I-1502J1D01*
G02X1740131Y447571I135J148D01*
G01Y447865D01*
G02X1740196Y448012I200J-1D01*
G03X1740575Y448563I-1017J1106D01*
G01X1740597Y448620D01*
X1740699Y448689D01*
X1745659D01*
X1745761Y448620D01*
X1745783Y448563D01*
G03X1746162Y448012I1396J555D01*
G02X1746227Y447865I-135J-148D01*
G01Y447571D01*
G02X1746162Y447424I-200J1D01*
G03X1745677Y446318I1017J-1105D01*
G03X1748681I1502J0D01*
G03X1748196Y447424I-1502J1D01*
G02X1748131Y447571I135J148D01*
G01Y447865D01*
G02X1748196Y448012I200J-1D01*
G03X1748575Y448563I-1017J1106D01*
G01X1748597Y448620D01*
X1748699Y448689D01*
X1756188D01*
X1756227Y448671D01*
G03X1756844Y448539I616J1370D01*
G03X1757461Y448671I1J1502D01*
G01X1757500Y448689D01*
X1766181D01*
X1766220Y448671D01*
G03X1766837Y448539I616J1370D01*
G03X1767454Y448671I1J1502D01*
G01X1767493Y448689D01*
X1784288D01*
X1784397Y448602D01*
X1784412Y448533D01*
G03X1787928I1758J399D01*
G01X1787943Y448602D01*
X1788052Y448689D01*
G37*
G36*
G01X1710443Y1460782D02*
G03I-491J0D01*
G37*
G36*
G01X1719104Y1456452D02*
G03I-491J0D01*
G37*
G36*
G01Y1461183D02*
G03I-491J0D01*
G37*
G36*
G01X1710443Y1476136D02*
G03I-491J0D01*
G37*
G36*
G01Y1470244D02*
G03I-491J0D01*
G37*
G36*
G01Y1480867D02*
G03I-491J0D01*
G37*
G36*
G01X1719104Y1476537D02*
G03I-491J0D01*
G37*
G36*
G01Y1471806D02*
G03I-491J0D01*
G37*
G36*
G01Y1481268D02*
G03I-491J0D01*
G37*
G36*
G01X1710443Y1465513D02*
G03I-491J0D01*
G37*
G36*
G01X1719104Y1465914D02*
G03I-491J0D01*
G37*
G36*
G01X1710443Y1491491D02*
G03I-491J0D01*
G37*
G36*
G01Y1485598D02*
G03I-491J0D01*
G37*
G36*
G01Y1496222D02*
G03I-491J0D01*
G37*
G36*
G01X1719104Y1491892D02*
G03I-491J0D01*
G37*
G36*
G01Y1487161D02*
G03I-491J0D01*
G37*
G36*
G01Y1496623D02*
G03I-491J0D01*
G37*
G36*
G01Y1511977D02*
G03I-491J0D01*
G37*
G36*
G01X1710443Y1506845D02*
G03I-491J0D01*
G37*
G36*
G01Y1500953D02*
G03I-491J0D01*
G37*
G36*
G01Y1511576D02*
G03I-491J0D01*
G37*
G36*
G01X1719104Y1507246D02*
G03I-491J0D01*
G37*
G36*
G01Y1502515D02*
G03I-491J0D01*
G37*
G36*
G01X1710443Y1516307D02*
G03I-491J0D01*
G37*
G36*
G01X1719104Y1558813D02*
G03I-491J0D01*
G37*
G36*
G01Y1578898D02*
G03I-491J0D01*
G37*
G36*
G01X1710443Y1563144D02*
G03I-491J0D01*
G37*
G36*
G01X1719104Y1563544D02*
G03I-491J0D01*
G37*
G36*
G01X1710443Y1567875D02*
G03I-491J0D01*
G37*
G36*
G01X1719104Y1568275D02*
G03I-491J0D01*
G37*
G36*
G01X1710443Y1578498D02*
G03I-491J0D01*
G37*
G36*
G01Y1572606D02*
G03I-491J0D01*
G37*
G36*
G01X1719104Y1574167D02*
G03I-491J0D01*
G37*
G36*
G01X1710443Y1583229D02*
G03I-491J0D01*
G37*
G36*
G01X1719104Y1583629D02*
G03I-491J0D01*
G37*
G36*
G01X1710443Y1593853D02*
G03I-491J0D01*
G37*
G36*
G01Y1587960D02*
G03I-491J0D01*
G37*
G36*
G01X1719104Y1594253D02*
G03I-491J0D01*
G37*
G36*
G01Y1589522D02*
G03I-491J0D01*
G37*
G36*
G01Y1598984D02*
G03I-491J0D01*
G37*
G36*
G01Y1604876D02*
G03I-491J0D01*
G37*
G36*
G01X1710443Y1609207D02*
G03I-491J0D01*
G37*
G36*
G01Y1598584D02*
G03I-491J0D01*
G37*
G36*
G01Y1603315D02*
G03I-491J0D01*
G37*
G36*
G01X1719104Y1609607D02*
G03I-491J0D01*
G37*
G36*
G01Y1614338D02*
G03I-491J0D01*
G37*
G36*
G01X1710443Y1613938D02*
G03I-491J0D01*
G37*
G36*
G01Y1618669D02*
G03I-491J0D01*
G37*
G36*
G01X1729817Y1159455D02*
G03I-610J0D01*
G37*
G36*
G01X1748761Y984379D02*
G03I-680J0D01*
G37*
G36*
G01X1795196Y446952D02*
X1797386D01*
X1797459Y446922D01*
X1797480Y446901D01*
X1803407D01*
G02X1803549Y446842I0J-200D01*
G01X1807616Y442775D01*
X1807643Y442670D01*
X1807628Y442617D01*
G03X1807556Y442114I1730J-504D01*
G03X1808914Y440367I1803J0D01*
G01X1808982Y440350D01*
X1809065Y440243D01*
Y437014D01*
X1808964Y436900D01*
X1808888Y436891D01*
G03Y433311I207J-1790D01*
G01X1808964Y433302D01*
X1809065Y433188D01*
Y378675D01*
G02X1809006Y378533I-200J0D01*
G01X1805116Y374643D01*
G02X1804974Y374584I-142J141D01*
G01X1758584D01*
G02X1758442Y374643I0J200D01*
G01X1757278Y375807D01*
G02X1757219Y375949I141J142D01*
G01Y378788D01*
X1757221Y378801D01*
G03X1757235Y379028I-1788J224D01*
G03X1757221Y379255I-1802J3D01*
G01X1757219Y379268D01*
Y386016D01*
G02X1757278Y386158I200J0D01*
G01X1761465Y390345D01*
G02X1761606Y390404I142J-141D01*
G01X1762603D01*
G03X1762744Y390462I0J200D01*
G01X1765161Y392879D01*
G03X1765220Y393020I-141J142D01*
G01Y393431D01*
G02X1765420Y393631I200J0D01*
G01X1791524D01*
G03X1791666Y393690I0J200D01*
G01X1792515Y394539D01*
G03X1792574Y394681I-141J142D01*
G01Y406127D01*
G03X1792515Y406269I-200J0D01*
G01X1789066Y409718D01*
G02X1789007Y409860I141J142D01*
G01Y426545D01*
G02X1789066Y426687I200J0D01*
G01X1789695Y427316D01*
G02X1789836Y427374I141J-142D01*
G01X1792137D01*
G03X1792278Y427433I-1J200D01*
G01X1794938Y430093D01*
G03X1794996Y430234I-142J141D01*
G01Y446752D01*
G02X1795196Y446952I200J0D01*
G37*
G36*
G01X1779979Y429961D02*
X1786802D01*
G02X1786944Y429902I0J-200D01*
G01X1787711Y429135D01*
G02X1787770Y428993I-141J-142D01*
G01Y428304D01*
G02X1787711Y428163I-200J1D01*
G01X1787064Y427516D01*
G03X1787006Y427374I142J-141D01*
G01Y409031D01*
G03X1787064Y408889I200J-1D01*
G01X1790514Y405440D01*
G02X1790572Y405298I-142J-141D01*
G01Y395832D01*
G02X1790372Y395632I-200J0D01*
G01X1763088D01*
G02X1762888Y395832I0J200D01*
G01Y398285D01*
G03X1762829Y398427I-200J0D01*
G01X1760174Y401082D01*
G02X1760115Y401224I141J142D01*
G01Y424378D01*
G02X1760174Y424520I200J0D01*
G01X1760922Y425268D01*
G02X1761064Y425327I142J-141D01*
G01X1778392D01*
G03X1778534Y425386I0J200D01*
G01X1779232Y426084D01*
G03X1779291Y426226I-141J142D01*
G01Y429273D01*
G02X1779350Y429415I200J0D01*
G01X1779837Y429902D01*
G02X1779979Y429961I142J-141D01*
G37*
G36*
G01X1802238Y1071494D02*
X1830271D01*
G02X1830413Y1071435I0J-200D01*
G01X1831493Y1070355D01*
G02X1831552Y1070213I-141J-142D01*
G01Y1002559D01*
G02X1831493Y1002417I-200J0D01*
G01X1830522Y1001446D01*
G02X1830380Y1001387I-142J141D01*
G01X1784935D01*
X1782396Y1003926D01*
X1782283D01*
X1782226Y1003983D01*
X1769864D01*
X1759697Y1014150D01*
Y1017087D01*
X1763111Y1020501D01*
Y1024186D01*
X1759657Y1027640D01*
Y1070178D01*
X1760695Y1071216D01*
G02X1760837Y1071275I142J-141D01*
G01X1772684D01*
G02X1772826Y1071216I0J-200D01*
G01X1772909Y1071133D01*
G02X1772966Y1071023I-141J-143D01*
G02X1772968Y1070991I-198J-28D01*
G01Y1031667D01*
G03X1773024Y1031529I200J1D01*
G01X1773026Y1031527D01*
X1773043Y1031508D01*
G02X1773095Y1031374I-148J-134D01*
G01Y1029844D01*
G03X1773154Y1029702I200J0D01*
G01X1774293Y1028563D01*
G03X1774435Y1028504I142J141D01*
G01X1799778D01*
G03X1799920Y1028563I0J200D01*
G01X1801877Y1030520D01*
G03X1801936Y1030662I-141J142D01*
G01Y1071192D01*
G02X1801995Y1071334I200J0D01*
G01X1802096Y1071435D01*
G02X1802238Y1071494I142J-141D01*
G37*
G36*
G01X1760479Y1104172D02*
X1768496D01*
G02X1768638Y1104113I0J-200D01*
G01X1770140Y1102611D01*
G02X1770199Y1102469I-141J-142D01*
G01Y1077841D01*
G03X1770258Y1077699I200J0D01*
G01X1770357Y1077600D01*
G02X1770416Y1077458I-141J-142D01*
G01Y1073033D01*
G02X1770357Y1072891I-200J0D01*
G01X1770335Y1072869D01*
X1761289D01*
G02X1761147Y1072928I0J200D01*
G01X1759716Y1074359D01*
G02X1759658Y1074500I142J141D01*
G01Y1103351D01*
G02X1759716Y1103492I200J0D01*
G01X1760337Y1104113D01*
G02X1760479Y1104172I142J-141D01*
G37*
G36*
G01X1792949Y1084428D02*
X1800402Y1076974D01*
X1802664D01*
X1804041Y1075597D01*
Y1073139D01*
X1803528Y1072626D01*
X1801541D01*
X1800461Y1071546D01*
Y1031592D01*
G02X1800402Y1031450I-200J0D01*
G01X1799799Y1030847D01*
G02X1799657Y1030788I-142J141D01*
G01X1775264D01*
G02X1775122Y1030847I0J200D01*
G01X1774155Y1031814D01*
G02X1774096Y1031955I141J142D01*
G01Y1071279D01*
G03X1774038Y1071420I-200J0D01*
G01X1774028Y1071431D01*
G02X1773969Y1071572I141J142D01*
G01Y1071704D01*
X1772664Y1073009D01*
X1771618D01*
X1771490Y1073137D01*
Y1102913D01*
X1772307Y1103730D01*
X1784740D01*
X1785270Y1103200D01*
Y1098852D01*
X1786134Y1097988D01*
X1789840D01*
X1790428Y1097400D01*
Y1086949D01*
X1791642Y1085735D01*
X1792808Y1084569D01*
X1792949Y1084428D01*
G37*
G36*
G01X1781250Y1156263D02*
X1809762D01*
G02X1809903Y1156204I-1J-200D01*
G01X1811095Y1155012D01*
G02X1811154Y1154871I-141J-142D01*
G01Y1106770D01*
G02X1811095Y1106628I-200J0D01*
G01X1811014Y1106547D01*
X1810906Y1106521D01*
X1810852Y1106537D01*
G03X1810310Y1106621I-544J-1718D01*
G03X1808812Y1105820I0J-1801D01*
G02X1808645Y1105731I-166J111D01*
G01X1769963D01*
G02X1769821Y1105790I0J200D01*
G01X1768246Y1107365D01*
G02X1768187Y1107507I141J142D01*
G01Y1115228D01*
G02X1768246Y1115370I200J0D01*
G01X1769682Y1116806D01*
G02X1769824Y1116865I142J-141D01*
G01X1775893D01*
G03X1776035Y1116924I0J200D01*
G01X1779728Y1120617D01*
G03X1779787Y1120759I-141J142D01*
G01Y1154800D01*
G02X1779846Y1154942I200J0D01*
G01X1781108Y1156204D01*
G02X1781250Y1156263I142J-141D01*
G37*
G36*
G01X1771580Y1266009D02*
X1821032D01*
G02X1821172Y1265952I0J-200D01*
G01X1821173Y1265951D01*
X1822477Y1264647D01*
G02X1822479Y1264645I-140J-142D01*
G02X1822536Y1264505I-143J-140D01*
G01Y1248239D01*
G02X1822408Y1248052I-200J0D01*
G03Y1223208I4757J-12422D01*
G02X1822536Y1223021I-72J-187D01*
G01Y1219767D01*
G02X1822477Y1219625I-200J0D01*
G01X1820532Y1217680D01*
G03X1820473Y1217538I141J-142D01*
G01Y1214698D01*
G02X1820273Y1214498I-200J0D01*
G01X1819906D01*
G03X1819014Y1214128I1J-1262D01*
G01X1818824Y1213938D01*
X1818720Y1213911D01*
X1818667Y1213926D01*
G03X1818421Y1213959I-240J-857D01*
G01Y1213958D01*
X1817243D01*
Y1213959D01*
G03X1816346Y1213069I-7J-890D01*
G01Y1212216D01*
G03X1816546Y1212016I200J0D01*
G01X1816582D01*
Y1210148D01*
G02X1816382Y1209948I-200J0D01*
G01X1816346D01*
Y1208895D01*
G03X1816440Y1208499I890J2D01*
G01X1816468Y1208441D01*
X1816448Y1208315D01*
X1816402Y1208269D01*
G02X1816119I-142J141D01*
G01X1814804Y1209584D01*
G02X1814746Y1209725I142J141D01*
G01Y1212222D01*
G03X1814376Y1213114I-1262J-1D01*
G01X1813237Y1214253D01*
G02X1813178Y1214394I141J142D01*
G01Y1215223D01*
G02X1813281Y1215398I200J0D01*
G01X1813635Y1215594D01*
X1813743Y1215591D01*
X1813790Y1215563D01*
G03X1814741Y1215291I952J1530D01*
G03Y1218895I0J1802D01*
G03X1813790Y1218623I1J-1802D01*
G01X1813743Y1218595D01*
X1813635Y1218592D01*
X1813281Y1218788D01*
G02X1813178Y1218963I97J175D01*
G01Y1221450D01*
G03X1812809Y1222342I-1261J1D01*
G01X1808514Y1226637D01*
G03X1807622Y1227006I-891J-892D01*
G01X1806494D01*
G02X1806358Y1227060I1J200D01*
G03X1805126Y1227547I-1232J-1315D01*
G03Y1223943I0J-1802D01*
G03X1806358Y1224430I0J1802D01*
G02X1806494Y1224484I137J-146D01*
G01X1807017D01*
G02X1807158Y1224425I-1J-200D01*
G01X1810597Y1220986D01*
G02X1810656Y1220845I-141J-142D01*
G01Y1213789D01*
G03X1811025Y1212897I1261J-1D01*
G01X1812164Y1211758D01*
G02X1812222Y1211617I-142J-141D01*
G01Y1209120D01*
G03X1812592Y1208228I1262J1D01*
G01X1816237Y1204583D01*
G03X1816428Y1204426I893J891D01*
G02X1816516Y1204260I-112J-166D01*
G01Y1203889D01*
G03X1816509Y1203883I1299J-1522D01*
G02X1816384Y1203838I-126J155D01*
G01X1814031D01*
G02X1813858Y1203939I1J200D01*
G01X1813659Y1204286D01*
Y1204394D01*
X1813686Y1204440D01*
G03X1813932Y1205349I-1556J909D01*
G03X1810328I-1802J0D01*
G03X1810574Y1204440I1802J0D01*
G01X1810601Y1204394D01*
Y1204286D01*
X1810402Y1203939D01*
G02X1810229Y1203838I-174J99D01*
G01X1809382D01*
G02X1809240Y1203897I0J200D01*
G01X1806292Y1206845D01*
G02X1806257Y1206893I142J141D01*
G03X1804489Y1207956I-1768J-939D01*
G01X1786375D01*
G02X1786233Y1208015I0J200D01*
G01X1784693Y1209555D01*
G03X1783278Y1210142I-1416J-1415D01*
G03X1781276Y1208140I0J-2002D01*
G03X1781863Y1206725I2002J1D01*
G01X1784048Y1204540D01*
G03X1785463Y1203954I1415J1415D01*
G01X1803440D01*
G02X1803582Y1203895I0J-200D01*
G01X1807055Y1200422D01*
G03X1808470Y1199836I1415J1415D01*
G01X1817278D01*
G03X1818693Y1200422I0J2001D01*
G01X1819181Y1200910D01*
G03X1819768Y1202325I-1415J1416D01*
G03X1819084Y1203831I-2002J-1D01*
G02X1819016Y1203982I132J150D01*
G01Y1204734D01*
G02X1819216Y1204934I200J0D01*
G01X1819252D01*
Y1205987D01*
G03X1819122Y1206448I-890J-2D01*
G01X1819108Y1206472D01*
X1819094Y1206524D01*
Y1208234D01*
G02X1819135Y1208355I200J0D01*
G03X1819318Y1208895I-707J541D01*
G01Y1209748D01*
G03X1819118Y1209948I-200J0D01*
G01X1819082D01*
Y1211016D01*
G02X1819137Y1211155I200J1D01*
G01X1819220Y1211241D01*
G02X1819346Y1211301I144J-139D01*
G03X1820119Y1211665I-119J1256D01*
G01X1820132Y1211678D01*
G02X1820350Y1211721I141J-142D01*
G01X1820406Y1211698D01*
X1820473Y1211598D01*
Y1208579D01*
G03X1820532Y1208437I200J0D01*
G01X1822477Y1206492D01*
G02X1822536Y1206350I-141J-142D01*
G01Y1170174D01*
G03X1822595Y1170032I200J0D01*
G01X1828198Y1164429D01*
G02X1828257Y1164287I-141J-142D01*
G01Y1097580D01*
X1828158Y1097468D01*
X1828082Y1097458D01*
G03Y1094478I190J-1490D01*
G01X1828158Y1094468D01*
X1828257Y1094356D01*
Y1075774D01*
G02X1828198Y1075632I-200J0D01*
G01X1825737Y1073171D01*
G02X1825595Y1073112I-142J141D01*
G01X1806663D01*
G02X1806521Y1073171I0J200D01*
G01X1806504Y1073188D01*
G02X1806445Y1073330I141J142D01*
G01Y1076837D01*
G03X1806386Y1076979I-200J0D01*
G01X1805212Y1078153D01*
G03X1805070Y1078212I-142J-141D01*
G01X1802498D01*
G02X1802356Y1078271I0J200D01*
G01X1801374Y1079253D01*
G02X1801336Y1079484I141J142D01*
G01X1801534Y1079882D01*
X1801647Y1079941D01*
X1801712Y1079932D01*
G03X1801961Y1079915I247J1785D01*
G03X1800159Y1081717I0J1802D01*
G03X1800176Y1081468I1802J-2D01*
G01X1800185Y1081403D01*
X1800126Y1081290D01*
X1799728Y1081092D01*
G02X1799497Y1081130I-89J179D01*
G01X1791488Y1089139D01*
G02X1791430Y1089280I142J141D01*
G01Y1097732D01*
G03X1791371Y1097873I-200J-1D01*
G01X1791190Y1098055D01*
G02X1791131Y1098196I141J142D01*
G01Y1099064D01*
G03X1791072Y1099206I-200J0D01*
G01X1790783Y1099495D01*
G03X1790641Y1099554I-142J-141D01*
G01X1788026D01*
G02X1787884Y1099613I0J200D01*
G01X1787516Y1099981D01*
G02X1787457Y1100123I141J142D01*
G01Y1103739D01*
G02X1787516Y1103881I200J0D01*
G01X1787709Y1104074D01*
G02X1787851Y1104133I142J-141D01*
G01X1798974D01*
G02X1799133Y1104055I1J-200D01*
G01X1799355Y1103766D01*
X1799373Y1103676D01*
X1799361Y1103631D01*
G03X1799311Y1103246I1452J-384D01*
G03X1802315I1502J0D01*
G03X1802265Y1103631I-1502J1D01*
G01X1802253Y1103676D01*
X1802271Y1103766D01*
X1802493Y1104055D01*
G02X1802652Y1104133I158J-122D01*
G01X1808515D01*
G02X1808694Y1104022I0J-200D01*
G03X1810310Y1103017I1616J797D01*
G03X1812112Y1104819I0J1802D01*
G01Y1104842D01*
X1812111Y1104883D01*
X1812141Y1104956D01*
X1812282Y1105097D01*
G03X1812341Y1105239I-141J142D01*
G01Y1109091D01*
G02X1812400Y1109233I200J0D01*
G01X1812409Y1109242D01*
X1812395Y1109256D01*
G02X1812336Y1109398I141J142D01*
G01Y1155105D01*
G03X1812277Y1155247I-200J0D01*
G01X1809683Y1157841D01*
G03X1809541Y1157900I-142J-141D01*
G01X1779027D01*
G03X1778885Y1157841I0J-200D01*
G01X1778557Y1157513D01*
G03X1778498Y1157371I141J-142D01*
G01Y1123421D01*
G02X1778439Y1123279I-200J0D01*
G01X1774773Y1119613D01*
G02X1774631Y1119554I-142J141D01*
G01X1760152D01*
G02X1759952Y1119754I0J200D01*
G01Y1162722D01*
G02X1760011Y1162864I200J0D01*
G01X1767052Y1169905D01*
G03X1767111Y1170047I-141J142D01*
G01Y1202700D01*
G02X1767143Y1202808I200J0D01*
G01X1767211Y1202915D01*
X1767253Y1202952D01*
X1767279Y1202964D01*
G03Y1227036I-5666J12036D01*
G01X1767253Y1227048D01*
X1767211Y1227085D01*
X1767143Y1227192D01*
G02X1767111Y1227300I168J108D01*
G01Y1261540D01*
G02X1767170Y1261682I200J0D01*
G01X1771438Y1265950D01*
G02X1771580Y1266009I142J-141D01*
G37*
G36*
G01X1786463Y980300D02*
Y979060D01*
X1787463Y978060D01*
X1791163D01*
X1791463Y977760D01*
Y973560D01*
X1791263Y973360D01*
X1778663D01*
X1778363Y973660D01*
Y980147D01*
X1778919Y980703D01*
X1786060D01*
X1786463Y980300D01*
G37*
G36*
G01X1800563Y976160D02*
X1805463D01*
X1808563D01*
X1810463D01*
X1811263Y975360D01*
Y962360D01*
X1810563Y961660D01*
X1808963D01*
X1800863D01*
X1800263Y962260D01*
Y975860D01*
X1800563Y976160D01*
G37*
G36*
G01X1827173Y1567323D02*
G02I-9850J0D01*
G37*
%LPC*%
G75*
G36*
G01X75317Y213859D02*
G02X78321I1502J0D01*
G02X77951Y212872I-1501J0D01*
G01Y212871D01*
X77950D01*
G03X77902Y212741I152J-130D01*
G01Y212477D01*
G03X77950Y212347I200J0D01*
G01X77951Y212346D01*
G02X78321Y211359I-1131J-987D01*
G02X75317I-1502J0D01*
G02X75687Y212346I1501J0D01*
G01Y212347D01*
X75688D01*
G03X75736Y212477I-152J130D01*
G01Y212741D01*
G03X75688Y212871I-200J0D01*
G01X75687Y212872D01*
G02X75317Y213859I1131J987D01*
G37*
G36*
G01X177679D02*
G02X180683I1502J0D01*
G02X180313Y212872I-1501J0D01*
G01Y212871D01*
X180312D01*
G03X180264Y212741I152J-130D01*
G01Y212477D01*
G03X180312Y212347I200J0D01*
G01X180313Y212346D01*
G02X180683Y211359I-1131J-987D01*
G02X177679I-1502J0D01*
G02X178049Y212346I1501J0D01*
G01Y212347D01*
X178050D01*
G03X178098Y212477I-152J130D01*
G01Y212741D01*
G03X178050Y212871I-200J0D01*
G01X178049Y212872D01*
G02X177679Y213859I1131J987D01*
G37*
G36*
G01X280041D02*
G02X283045I1502J0D01*
G02X282675Y212872I-1501J0D01*
G01Y212871D01*
X282674D01*
G03X282626Y212741I152J-130D01*
G01Y212477D01*
G03X282674Y212347I200J0D01*
G01X282675Y212346D01*
G02X283045Y211359I-1131J-987D01*
G02X280041I-1502J0D01*
G02X280411Y212346I1501J0D01*
G01Y212347D01*
X280412D01*
G03X280460Y212477I-152J130D01*
G01Y212741D01*
G03X280412Y212871I-200J0D01*
G01X280411Y212872D01*
G02X280041Y213859I1131J987D01*
G37*
G36*
G01X382403D02*
G02X385407I1502J0D01*
G02X385037Y212872I-1501J0D01*
G01Y212871D01*
X385036D01*
G03X384988Y212741I152J-130D01*
G01Y212477D01*
G03X385036Y212347I200J0D01*
G01X385037Y212346D01*
G02X385407Y211359I-1131J-987D01*
G02X382403I-1502J0D01*
G02X382773Y212346I1501J0D01*
G01Y212347D01*
X382774D01*
G03X382822Y212477I-152J130D01*
G01Y212741D01*
G03X382774Y212871I-200J0D01*
G01X382773Y212872D01*
G02X382403Y213859I1131J987D01*
G37*
G36*
G01X532404D02*
G02X535408I1502J0D01*
G02X535038Y212872I-1501J0D01*
G01Y212871D01*
X535037D01*
G03X534989Y212741I152J-130D01*
G01Y212477D01*
G03X535037Y212347I200J0D01*
G01X535038Y212346D01*
G02X535408Y211359I-1131J-987D01*
G02X532404I-1502J0D01*
G02X532774Y212346I1501J0D01*
G01Y212347D01*
X532775D01*
G03X532823Y212477I-152J130D01*
G01Y212741D01*
G03X532775Y212871I-200J0D01*
G01X532774Y212872D01*
G02X532404Y213859I1131J987D01*
G37*
G36*
G01X634766D02*
G02X637770I1502J0D01*
G02X637400Y212872I-1501J0D01*
G01Y212871D01*
X637399D01*
G03X637351Y212741I152J-130D01*
G01Y212477D01*
G03X637399Y212347I200J0D01*
G01X637400Y212346D01*
G02X637770Y211359I-1131J-987D01*
G02X634766I-1502J0D01*
G02X635136Y212346I1501J0D01*
G01Y212347D01*
X635137D01*
G03X635185Y212477I-152J130D01*
G01Y212741D01*
G03X635137Y212871I-200J0D01*
G01X635136Y212872D01*
G02X634766Y213859I1131J987D01*
G37*
G36*
G01X737128D02*
G02X740132I1502J0D01*
G02X739762Y212872I-1501J0D01*
G01Y212871D01*
X739761D01*
G03X739713Y212741I152J-130D01*
G01Y212477D01*
G03X739761Y212347I200J0D01*
G01X739762Y212346D01*
G02X740132Y211359I-1131J-987D01*
G02X737128I-1502J0D01*
G02X737498Y212346I1501J0D01*
G01Y212347D01*
X737499D01*
G03X737547Y212477I-152J130D01*
G01Y212741D01*
G03X737499Y212871I-200J0D01*
G01X737498Y212872D01*
G02X737128Y213859I1131J987D01*
G37*
G36*
G01X839490D02*
G02X842494I1502J0D01*
G02X842124Y212872I-1501J0D01*
G01Y212871D01*
X842123D01*
G03X842075Y212741I152J-130D01*
G01Y212477D01*
G03X842123Y212347I200J0D01*
G01X842124Y212346D01*
G02X842494Y211359I-1131J-987D01*
G02X839490I-1502J0D01*
G02X839860Y212346I1501J0D01*
G01Y212347D01*
X839861D01*
G03X839909Y212477I-152J130D01*
G01Y212741D01*
G03X839861Y212871I-200J0D01*
G01X839860Y212872D01*
G02X839490Y213859I1131J987D01*
G37*
G36*
G01X989490D02*
G02X992494I1502J0D01*
G02X992124Y212872I-1501J0D01*
G01Y212871D01*
X992123D01*
G03X992075Y212741I152J-130D01*
G01Y212477D01*
G03X992123Y212347I200J0D01*
G01X992124Y212346D01*
G02X992494Y211359I-1131J-987D01*
G02X989490I-1502J0D01*
G02X989860Y212346I1501J0D01*
G01Y212347D01*
X989861D01*
G03X989909Y212477I-152J130D01*
G01Y212741D01*
G03X989861Y212871I-200J0D01*
G01X989860Y212872D01*
G02X989490Y213859I1131J987D01*
G37*
G36*
G01X1091852D02*
G02X1094856I1502J0D01*
G02X1094486Y212872I-1501J0D01*
G01Y212871D01*
X1094485D01*
G03X1094437Y212741I152J-130D01*
G01Y212477D01*
G03X1094485Y212347I200J0D01*
G01X1094486Y212346D01*
G02X1094856Y211359I-1131J-987D01*
G02X1091852I-1502J0D01*
G02X1092222Y212346I1501J0D01*
G01Y212347D01*
X1092223D01*
G03X1092271Y212477I-152J130D01*
G01Y212741D01*
G03X1092223Y212871I-200J0D01*
G01X1092222Y212872D01*
G02X1091852Y213859I1131J987D01*
G37*
G36*
G01X1194214D02*
G02X1197218I1502J0D01*
G02X1196848Y212872I-1501J0D01*
G01Y212871D01*
X1196847D01*
G03X1196799Y212741I152J-130D01*
G01Y212477D01*
G03X1196847Y212347I200J0D01*
G01X1196848Y212346D01*
G02X1197218Y211359I-1131J-987D01*
G02X1194214I-1502J0D01*
G02X1194584Y212346I1501J0D01*
G01Y212347D01*
X1194585D01*
G03X1194633Y212477I-152J130D01*
G01Y212741D01*
G03X1194585Y212871I-200J0D01*
G01X1194584Y212872D01*
G02X1194214Y213859I1131J987D01*
G37*
G36*
G01X1296576D02*
G02X1299580I1502J0D01*
G02X1299210Y212872I-1501J0D01*
G01Y212871D01*
X1299209D01*
G03X1299161Y212741I152J-130D01*
G01Y212477D01*
G03X1299209Y212347I200J0D01*
G01X1299210Y212346D01*
G02X1299580Y211359I-1131J-987D01*
G02X1296576I-1502J0D01*
G02X1296946Y212346I1501J0D01*
G01Y212347D01*
X1296947D01*
G03X1296995Y212477I-152J130D01*
G01Y212741D01*
G03X1296947Y212871I-200J0D01*
G01X1296946Y212872D01*
G02X1296576Y213859I1131J987D01*
G37*
G36*
G01X1446577D02*
G02X1449581I1502J0D01*
G02X1449211Y212872I-1501J0D01*
G01Y212871D01*
X1449210D01*
G03X1449162Y212741I152J-130D01*
G01Y212477D01*
G03X1449210Y212347I200J0D01*
G01X1449211Y212346D01*
G02X1449581Y211359I-1131J-987D01*
G02X1446577I-1502J0D01*
G02X1446947Y212346I1501J0D01*
G01Y212347D01*
X1446948D01*
G03X1446996Y212477I-152J130D01*
G01Y212741D01*
G03X1446948Y212871I-200J0D01*
G01X1446947Y212872D01*
G02X1446577Y213859I1131J987D01*
G37*
G36*
G01X1548939D02*
G02X1551943I1502J0D01*
G02X1551573Y212872I-1501J0D01*
G01Y212871D01*
X1551572D01*
G03X1551524Y212741I152J-130D01*
G01Y212477D01*
G03X1551572Y212347I200J0D01*
G01X1551573Y212346D01*
G02X1551943Y211359I-1131J-987D01*
G02X1548939I-1502J0D01*
G02X1549309Y212346I1501J0D01*
G01Y212347D01*
X1549310D01*
G03X1549358Y212477I-152J130D01*
G01Y212741D01*
G03X1549310Y212871I-200J0D01*
G01X1549309Y212872D01*
G02X1548939Y213859I1131J987D01*
G37*
G36*
G01X1651301D02*
G02X1654305I1502J0D01*
G02X1653935Y212872I-1501J0D01*
G01Y212871D01*
X1653934D01*
G03X1653886Y212741I152J-130D01*
G01Y212477D01*
G03X1653934Y212347I200J0D01*
G01X1653935Y212346D01*
G02X1654305Y211359I-1131J-987D01*
G02X1651301I-1502J0D01*
G02X1651671Y212346I1501J0D01*
G01Y212347D01*
X1651672D01*
G03X1651720Y212477I-152J130D01*
G01Y212741D01*
G03X1651672Y212871I-200J0D01*
G01X1651671Y212872D01*
G02X1651301Y213859I1131J987D01*
G37*
G36*
G01X1753663D02*
G02X1756667I1502J0D01*
G02X1756297Y212872I-1501J0D01*
G01Y212871D01*
X1756296D01*
G03X1756248Y212741I152J-130D01*
G01Y212477D01*
G03X1756296Y212347I200J0D01*
G01X1756297Y212346D01*
G02X1756667Y211359I-1131J-987D01*
G02X1753663I-1502J0D01*
G02X1754033Y212346I1501J0D01*
G01Y212347D01*
X1754034D01*
G03X1754082Y212477I-152J130D01*
G01Y212741D01*
G03X1754034Y212871I-200J0D01*
G01X1754033Y212872D01*
G02X1753663Y213859I1131J987D01*
G37*
G36*
G01X79020Y215632D02*
G02X82024I1502J0D01*
G02X81654Y214645I-1501J0D01*
G01Y214644D01*
X81653D01*
G03X81605Y214514I152J-130D01*
G01Y214250D01*
G03X81653Y214120I200J0D01*
G01X81654Y214119D01*
G02X82024Y213132I-1131J-987D01*
G02X79020I-1502J0D01*
G02X79390Y214119I1501J0D01*
G01Y214120D01*
X79391D01*
G03X79439Y214250I-152J130D01*
G01Y214514D01*
G03X79391Y214644I-200J0D01*
G01X79390Y214645D01*
G02X79020Y215632I1131J987D01*
G37*
G36*
G01X181382D02*
G02X184386I1502J0D01*
G02X184016Y214645I-1501J0D01*
G01Y214644D01*
X184015D01*
G03X183967Y214514I152J-130D01*
G01Y214250D01*
G03X184015Y214120I200J0D01*
G01X184016Y214119D01*
G02X184386Y213132I-1131J-987D01*
G02X181382I-1502J0D01*
G02X181752Y214119I1501J0D01*
G01Y214120D01*
X181753D01*
G03X181801Y214250I-152J130D01*
G01Y214514D01*
G03X181753Y214644I-200J0D01*
G01X181752Y214645D01*
G02X181382Y215632I1131J987D01*
G37*
G36*
G01X283744D02*
G02X286748I1502J0D01*
G02X286378Y214645I-1501J0D01*
G01Y214644D01*
X286377D01*
G03X286329Y214514I152J-130D01*
G01Y214250D01*
G03X286377Y214120I200J0D01*
G01X286378Y214119D01*
G02X286748Y213132I-1131J-987D01*
G02X283744I-1502J0D01*
G02X284114Y214119I1501J0D01*
G01Y214120D01*
X284115D01*
G03X284163Y214250I-152J130D01*
G01Y214514D01*
G03X284115Y214644I-200J0D01*
G01X284114Y214645D01*
G02X283744Y215632I1131J987D01*
G37*
G36*
G01X386106D02*
G02X389110I1502J0D01*
G02X388740Y214645I-1501J0D01*
G01Y214644D01*
X388739D01*
G03X388691Y214514I152J-130D01*
G01Y214250D01*
G03X388739Y214120I200J0D01*
G01X388740Y214119D01*
G02X389110Y213132I-1131J-987D01*
G02X386106I-1502J0D01*
G02X386476Y214119I1501J0D01*
G01Y214120D01*
X386477D01*
G03X386525Y214250I-152J130D01*
G01Y214514D01*
G03X386477Y214644I-200J0D01*
G01X386476Y214645D01*
G02X386106Y215632I1131J987D01*
G37*
G36*
G01X536107D02*
G02X539111I1502J0D01*
G02X538741Y214645I-1501J0D01*
G01Y214644D01*
X538740D01*
G03X538692Y214514I152J-130D01*
G01Y214250D01*
G03X538740Y214120I200J0D01*
G01X538741Y214119D01*
G02X539111Y213132I-1131J-987D01*
G02X536107I-1502J0D01*
G02X536477Y214119I1501J0D01*
G01Y214120D01*
X536478D01*
G03X536526Y214250I-152J130D01*
G01Y214514D01*
G03X536478Y214644I-200J0D01*
G01X536477Y214645D01*
G02X536107Y215632I1131J987D01*
G37*
G36*
G01X638469D02*
G02X641473I1502J0D01*
G02X641103Y214645I-1501J0D01*
G01Y214644D01*
X641102D01*
G03X641054Y214514I152J-130D01*
G01Y214250D01*
G03X641102Y214120I200J0D01*
G01X641103Y214119D01*
G02X641473Y213132I-1131J-987D01*
G02X638469I-1502J0D01*
G02X638839Y214119I1501J0D01*
G01Y214120D01*
X638840D01*
G03X638888Y214250I-152J130D01*
G01Y214514D01*
G03X638840Y214644I-200J0D01*
G01X638839Y214645D01*
G02X638469Y215632I1131J987D01*
G37*
G36*
G01X740831D02*
G02X743835I1502J0D01*
G02X743465Y214645I-1501J0D01*
G01Y214644D01*
X743464D01*
G03X743416Y214514I152J-130D01*
G01Y214250D01*
G03X743464Y214120I200J0D01*
G01X743465Y214119D01*
G02X743835Y213132I-1131J-987D01*
G02X740831I-1502J0D01*
G02X741201Y214119I1501J0D01*
G01Y214120D01*
X741202D01*
G03X741250Y214250I-152J130D01*
G01Y214514D01*
G03X741202Y214644I-200J0D01*
G01X741201Y214645D01*
G02X740831Y215632I1131J987D01*
G37*
G36*
G01X843193D02*
G02X846197I1502J0D01*
G02X845827Y214645I-1501J0D01*
G01Y214644D01*
X845826D01*
G03X845778Y214514I152J-130D01*
G01Y214250D01*
G03X845826Y214120I200J0D01*
G01X845827Y214119D01*
G02X846197Y213132I-1131J-987D01*
G02X843193I-1502J0D01*
G02X843563Y214119I1501J0D01*
G01Y214120D01*
X843564D01*
G03X843612Y214250I-152J130D01*
G01Y214514D01*
G03X843564Y214644I-200J0D01*
G01X843563Y214645D01*
G02X843193Y215632I1131J987D01*
G37*
G36*
G01X993193D02*
G02X996197I1502J0D01*
G02X995827Y214645I-1501J0D01*
G01Y214644D01*
X995826D01*
G03X995778Y214514I152J-130D01*
G01Y214250D01*
G03X995826Y214120I200J0D01*
G01X995827Y214119D01*
G02X996197Y213132I-1131J-987D01*
G02X993193I-1502J0D01*
G02X993563Y214119I1501J0D01*
G01Y214120D01*
X993564D01*
G03X993612Y214250I-152J130D01*
G01Y214514D01*
G03X993564Y214644I-200J0D01*
G01X993563Y214645D01*
G02X993193Y215632I1131J987D01*
G37*
G36*
G01X1095555D02*
G02X1098559I1502J0D01*
G02X1098189Y214645I-1501J0D01*
G01Y214644D01*
X1098188D01*
G03X1098140Y214514I152J-130D01*
G01Y214250D01*
G03X1098188Y214120I200J0D01*
G01X1098189Y214119D01*
G02X1098559Y213132I-1131J-987D01*
G02X1095555I-1502J0D01*
G02X1095925Y214119I1501J0D01*
G01Y214120D01*
X1095926D01*
G03X1095974Y214250I-152J130D01*
G01Y214514D01*
G03X1095926Y214644I-200J0D01*
G01X1095925Y214645D01*
G02X1095555Y215632I1131J987D01*
G37*
G36*
G01X1197917D02*
G02X1200921I1502J0D01*
G02X1200551Y214645I-1501J0D01*
G01Y214644D01*
X1200550D01*
G03X1200502Y214514I152J-130D01*
G01Y214250D01*
G03X1200550Y214120I200J0D01*
G01X1200551Y214119D01*
G02X1200921Y213132I-1131J-987D01*
G02X1197917I-1502J0D01*
G02X1198287Y214119I1501J0D01*
G01Y214120D01*
X1198288D01*
G03X1198336Y214250I-152J130D01*
G01Y214514D01*
G03X1198288Y214644I-200J0D01*
G01X1198287Y214645D01*
G02X1197917Y215632I1131J987D01*
G37*
G36*
G01X1300279D02*
G02X1303283I1502J0D01*
G02X1302913Y214645I-1501J0D01*
G01Y214644D01*
X1302912D01*
G03X1302864Y214514I152J-130D01*
G01Y214250D01*
G03X1302912Y214120I200J0D01*
G01X1302913Y214119D01*
G02X1303283Y213132I-1131J-987D01*
G02X1300279I-1502J0D01*
G02X1300649Y214119I1501J0D01*
G01Y214120D01*
X1300650D01*
G03X1300698Y214250I-152J130D01*
G01Y214514D01*
G03X1300650Y214644I-200J0D01*
G01X1300649Y214645D01*
G02X1300279Y215632I1131J987D01*
G37*
G36*
G01X1450280D02*
G02X1453284I1502J0D01*
G02X1452914Y214645I-1501J0D01*
G01Y214644D01*
X1452913D01*
G03X1452865Y214514I152J-130D01*
G01Y214250D01*
G03X1452913Y214120I200J0D01*
G01X1452914Y214119D01*
G02X1453284Y213132I-1131J-987D01*
G02X1450280I-1502J0D01*
G02X1450650Y214119I1501J0D01*
G01Y214120D01*
X1450651D01*
G03X1450699Y214250I-152J130D01*
G01Y214514D01*
G03X1450651Y214644I-200J0D01*
G01X1450650Y214645D01*
G02X1450280Y215632I1131J987D01*
G37*
G36*
G01X1552642D02*
G02X1555646I1502J0D01*
G02X1555276Y214645I-1501J0D01*
G01Y214644D01*
X1555275D01*
G03X1555227Y214514I152J-130D01*
G01Y214250D01*
G03X1555275Y214120I200J0D01*
G01X1555276Y214119D01*
G02X1555646Y213132I-1131J-987D01*
G02X1552642I-1502J0D01*
G02X1553012Y214119I1501J0D01*
G01Y214120D01*
X1553013D01*
G03X1553061Y214250I-152J130D01*
G01Y214514D01*
G03X1553013Y214644I-200J0D01*
G01X1553012Y214645D01*
G02X1552642Y215632I1131J987D01*
G37*
G36*
G01X1655004D02*
G02X1658008I1502J0D01*
G02X1657638Y214645I-1501J0D01*
G01Y214644D01*
X1657637D01*
G03X1657589Y214514I152J-130D01*
G01Y214250D01*
G03X1657637Y214120I200J0D01*
G01X1657638Y214119D01*
G02X1658008Y213132I-1131J-987D01*
G02X1655004I-1502J0D01*
G02X1655374Y214119I1501J0D01*
G01Y214120D01*
X1655375D01*
G03X1655423Y214250I-152J130D01*
G01Y214514D01*
G03X1655375Y214644I-200J0D01*
G01X1655374Y214645D01*
G02X1655004Y215632I1131J987D01*
G37*
G36*
G01X1757366D02*
G02X1760370I1502J0D01*
G02X1760000Y214645I-1501J0D01*
G01Y214644D01*
X1759999D01*
G03X1759951Y214514I152J-130D01*
G01Y214250D01*
G03X1759999Y214120I200J0D01*
G01X1760000Y214119D01*
G02X1760370Y213132I-1131J-987D01*
G02X1757366I-1502J0D01*
G02X1757736Y214119I1501J0D01*
G01Y214120D01*
X1757737D01*
G03X1757785Y214250I-152J130D01*
G01Y214514D01*
G03X1757737Y214644I-200J0D01*
G01X1757736Y214645D01*
G02X1757366Y215632I1131J987D01*
G37*
G36*
G01X114168Y217133D02*
X113874D01*
G03X113727Y217068I1J-200D01*
G02X112621Y216583I-1106J1019D01*
G02Y219587I0J1502D01*
G02X113727Y219102I0J-1504D01*
G03X113874Y219037I148J135D01*
G01X114168D01*
G03X114315Y219102I-1J200D01*
G02X115421Y219587I1106J-1019D01*
G02Y216583I0J-1502D01*
G02X114315Y217068I0J1504D01*
G03X114168Y217133I-148J-135D01*
G37*
G36*
G01X318892D02*
X318598D01*
G03X318451Y217068I1J-200D01*
G02X317345Y216583I-1106J1019D01*
G02Y219587I0J1502D01*
G02X318451Y219102I0J-1504D01*
G03X318598Y219037I148J135D01*
G01X318892D01*
G03X319039Y219102I-1J200D01*
G02X320145Y219587I1106J-1019D01*
G02Y216583I0J-1502D01*
G02X319039Y217068I0J1504D01*
G03X318892Y217133I-148J-135D01*
G37*
G36*
G01X468893D02*
X468599D01*
G03X468452Y217068I1J-200D01*
G02X467346Y216583I-1106J1019D01*
G02Y219587I0J1502D01*
G02X468452Y219102I0J-1504D01*
G03X468599Y219037I148J135D01*
G01X468893D01*
G03X469040Y219102I-1J200D01*
G02X470146Y219587I1106J-1019D01*
G02Y216583I0J-1502D01*
G02X469040Y217068I0J1504D01*
G03X468893Y217133I-148J-135D01*
G37*
G36*
G01X571255D02*
X570961D01*
G03X570814Y217068I1J-200D01*
G02X569708Y216583I-1106J1019D01*
G02Y219587I0J1502D01*
G02X570814Y219102I0J-1504D01*
G03X570961Y219037I148J135D01*
G01X571255D01*
G03X571402Y219102I-1J200D01*
G02X572508Y219587I1106J-1019D01*
G02Y216583I0J-1502D01*
G02X571402Y217068I0J1504D01*
G03X571255Y217133I-148J-135D01*
G37*
G36*
G01X673617D02*
X673323D01*
G03X673176Y217068I1J-200D01*
G02X672070Y216583I-1106J1019D01*
G02Y219587I0J1502D01*
G02X673176Y219102I0J-1504D01*
G03X673323Y219037I148J135D01*
G01X673617D01*
G03X673764Y219102I-1J200D01*
G02X674870Y219587I1106J-1019D01*
G02Y216583I0J-1502D01*
G02X673764Y217068I0J1504D01*
G03X673617Y217133I-148J-135D01*
G37*
G36*
G01X1028341D02*
X1028047D01*
G03X1027900Y217068I1J-200D01*
G02X1026794Y216583I-1106J1019D01*
G02Y219587I0J1502D01*
G02X1027900Y219102I0J-1504D01*
G03X1028047Y219037I148J135D01*
G01X1028341D01*
G03X1028488Y219102I-1J200D01*
G02X1029594Y219587I1106J-1019D01*
G02Y216583I0J-1502D01*
G02X1028488Y217068I0J1504D01*
G03X1028341Y217133I-148J-135D01*
G37*
G36*
G01X1130703D02*
X1130409D01*
G03X1130262Y217068I1J-200D01*
G02X1129156Y216583I-1106J1019D01*
G02Y219587I0J1502D01*
G02X1130262Y219102I0J-1504D01*
G03X1130409Y219037I148J135D01*
G01X1130703D01*
G03X1130850Y219102I-1J200D01*
G02X1131956Y219587I1106J-1019D01*
G02Y216583I0J-1502D01*
G02X1130850Y217068I0J1504D01*
G03X1130703Y217133I-148J-135D01*
G37*
G36*
G01X1233065D02*
X1232771D01*
G03X1232624Y217068I1J-200D01*
G02X1231518Y216583I-1106J1019D01*
G02Y219587I0J1502D01*
G02X1232624Y219102I0J-1504D01*
G03X1232771Y219037I148J135D01*
G01X1233065D01*
G03X1233212Y219102I-1J200D01*
G02X1234318Y219587I1106J-1019D01*
G02Y216583I0J-1502D01*
G02X1233212Y217068I0J1504D01*
G03X1233065Y217133I-148J-135D01*
G37*
G36*
G01X1485428D02*
X1485134D01*
G03X1484987Y217068I1J-200D01*
G02X1483881Y216583I-1106J1019D01*
G02Y219587I0J1502D01*
G02X1484987Y219102I0J-1504D01*
G03X1485134Y219037I148J135D01*
G01X1485428D01*
G03X1485575Y219102I-1J200D01*
G02X1486681Y219587I1106J-1019D01*
G02Y216583I0J-1502D01*
G02X1485575Y217068I0J1504D01*
G03X1485428Y217133I-148J-135D01*
G37*
G36*
G01X1587790D02*
X1587496D01*
G03X1587349Y217068I1J-200D01*
G02X1586243Y216583I-1106J1019D01*
G02Y219587I0J1502D01*
G02X1587349Y219102I0J-1504D01*
G03X1587496Y219037I148J135D01*
G01X1587790D01*
G03X1587937Y219102I-1J200D01*
G02X1589043Y219587I1106J-1019D01*
G02Y216583I0J-1502D01*
G02X1587937Y217068I0J1504D01*
G03X1587790Y217133I-148J-135D01*
G37*
G36*
G01X1690152D02*
X1689858D01*
G03X1689711Y217068I1J-200D01*
G02X1688605Y216583I-1106J1019D01*
G02Y219587I0J1502D01*
G02X1689711Y219102I0J-1504D01*
G03X1689858Y219037I148J135D01*
G01X1690152D01*
G03X1690299Y219102I-1J200D01*
G02X1691405Y219587I1106J-1019D01*
G02Y216583I0J-1502D01*
G02X1690299Y217068I0J1504D01*
G03X1690152Y217133I-148J-135D01*
G37*
G36*
G01X214983Y216283D02*
G02Y219887I0J1802D01*
G01X214984D01*
G02X216309Y219306I0J-1802D01*
G01X216335Y219278D01*
X216402Y219245D01*
X216711Y219220D01*
G03X216851Y219263I15J199D01*
G02X217783Y219587I932J-1178D01*
G02Y216583I0J-1502D01*
G02X216851Y216907I0J1502D01*
G03X216711Y216950I-125J-156D01*
G01X216402Y216925D01*
X216335Y216892D01*
X216309Y216864D01*
G02X214984Y216283I-1325J1221D01*
G01X214983D01*
G37*
G36*
G01X774432D02*
G02Y219887I0J1802D01*
G01X774433D01*
G02X775758Y219306I0J-1802D01*
G01X775784Y219278D01*
X775851Y219245D01*
X776160Y219220D01*
G03X776300Y219263I15J199D01*
G02X777232Y219587I932J-1178D01*
G02Y216583I0J-1502D01*
G02X776300Y216907I0J1502D01*
G03X776160Y216950I-125J-156D01*
G01X775851Y216925D01*
X775784Y216892D01*
X775758Y216864D01*
G02X774433Y216283I-1325J1221D01*
G01X774432D01*
G37*
G36*
G01X1381519D02*
G02Y219887I0J1802D01*
G01X1381520D01*
G02X1382845Y219306I0J-1802D01*
G01X1382871Y219278D01*
X1382938Y219245D01*
X1383247Y219220D01*
G03X1383387Y219263I15J199D01*
G02X1384319Y219587I932J-1178D01*
G02Y216583I0J-1502D01*
G02X1383387Y216907I0J1502D01*
G03X1383247Y216950I-125J-156D01*
G01X1382938Y216925D01*
X1382871Y216892D01*
X1382845Y216864D01*
G02X1381520Y216283I-1325J1221D01*
G01X1381519D01*
G37*
G36*
G01X18070Y221970D02*
G02X21074I1502J0D01*
G02X20704Y220983I-1501J0D01*
G01Y220982D01*
X20703D01*
G03X20655Y220852I152J-130D01*
G01Y220588D01*
G03X20703Y220458I200J0D01*
G01X20704Y220457D01*
G02Y218483I-1131J-987D01*
G01Y218482D01*
X20703D01*
G03X20655Y218352I152J-130D01*
G01Y218088D01*
G03X20703Y217958I200J0D01*
G01X20704Y217957D01*
G02X21074Y216970I-1131J-987D01*
G02X19572Y215468I-1502J0D01*
G02X18717Y215735I0J1502D01*
G01X18683Y215758D01*
X18602Y215775D01*
X18235Y215695D01*
X18168Y215647D01*
X18147Y215612D01*
G02X16859Y214883I-1288J773D01*
G02Y217887I0J1502D01*
G02X17714Y217620I0J-1502D01*
G01X17748Y217597D01*
X17829Y217580D01*
X18196Y217660D01*
X18263Y217708D01*
X18284Y217743D01*
G02X18440Y217956I1285J-777D01*
G03X18441Y217958I-173J88D01*
G03X18489Y218088I-152J130D01*
G01Y218352D01*
G03X18441Y218482I-200J0D01*
G01X18440Y218483D01*
G02Y220457I1131J987D01*
G01Y220458D01*
X18441D01*
G03X18489Y220588I-152J130D01*
G01Y220852D01*
G03X18441Y220982I-200J0D01*
G01X18440Y220983D01*
G02X18070Y221970I1131J987D01*
G37*
G36*
G01X120432D02*
G02X123436I1502J0D01*
G02X123066Y220983I-1501J0D01*
G01Y220982D01*
X123065D01*
G03X123017Y220852I152J-130D01*
G01Y220588D01*
G03X123065Y220458I200J0D01*
G01X123066Y220457D01*
G02Y218483I-1131J-987D01*
G01Y218482D01*
X123065D01*
G03X123017Y218352I152J-130D01*
G01Y218088D01*
G03X123065Y217958I200J0D01*
G01X123066Y217957D01*
G02X123436Y216970I-1131J-987D01*
G02X121934Y215468I-1502J0D01*
G02X121079Y215735I0J1502D01*
G01X121045Y215758D01*
X120964Y215775D01*
X120597Y215695D01*
X120530Y215647D01*
X120509Y215612D01*
G02X119221Y214883I-1288J773D01*
G02Y217887I0J1502D01*
G02X120076Y217620I0J-1502D01*
G01X120110Y217597D01*
X120191Y217580D01*
X120558Y217660D01*
X120625Y217708D01*
X120646Y217743D01*
G02X120802Y217956I1285J-777D01*
G03X120803Y217958I-173J88D01*
G03X120851Y218088I-152J130D01*
G01Y218352D01*
G03X120803Y218482I-200J0D01*
G01X120802Y218483D01*
G02Y220457I1131J987D01*
G01Y220458D01*
X120803D01*
G03X120851Y220588I-152J130D01*
G01Y220852D01*
G03X120803Y220982I-200J0D01*
G01X120802Y220983D01*
G02X120432Y221970I1131J987D01*
G37*
G36*
G01X222794D02*
G02X225798I1502J0D01*
G02X225428Y220983I-1501J0D01*
G01Y220982D01*
X225427D01*
G03X225379Y220852I152J-130D01*
G01Y220588D01*
G03X225427Y220458I200J0D01*
G01X225428Y220457D01*
G02Y218483I-1131J-987D01*
G01Y218482D01*
X225427D01*
G03X225379Y218352I152J-130D01*
G01Y218088D01*
G03X225427Y217958I200J0D01*
G01X225428Y217957D01*
G02X225798Y216970I-1131J-987D01*
G02X224296Y215468I-1502J0D01*
G02X223441Y215735I0J1502D01*
G01X223407Y215758D01*
X223326Y215775D01*
X222959Y215695D01*
X222892Y215647D01*
X222871Y215612D01*
G02X221583Y214883I-1288J773D01*
G02Y217887I0J1502D01*
G02X222438Y217620I0J-1502D01*
G01X222472Y217597D01*
X222553Y217580D01*
X222920Y217660D01*
X222987Y217708D01*
X223008Y217743D01*
G02X223164Y217956I1285J-777D01*
G03X223165Y217958I-173J88D01*
G03X223213Y218088I-152J130D01*
G01Y218352D01*
G03X223165Y218482I-200J0D01*
G01X223164Y218483D01*
G02Y220457I1131J987D01*
G01Y220458D01*
X223165D01*
G03X223213Y220588I-152J130D01*
G01Y220852D01*
G03X223165Y220982I-200J0D01*
G01X223164Y220983D01*
G02X222794Y221970I1131J987D01*
G37*
G36*
G01X325156D02*
G02X328160I1502J0D01*
G02X327790Y220983I-1501J0D01*
G01Y220982D01*
X327789D01*
G03X327741Y220852I152J-130D01*
G01Y220588D01*
G03X327789Y220458I200J0D01*
G01X327790Y220457D01*
G02Y218483I-1131J-987D01*
G01Y218482D01*
X327789D01*
G03X327741Y218352I152J-130D01*
G01Y218088D01*
G03X327789Y217958I200J0D01*
G01X327790Y217957D01*
G02X328160Y216970I-1131J-987D01*
G02X326658Y215468I-1502J0D01*
G02X325803Y215735I0J1502D01*
G01X325769Y215758D01*
X325688Y215775D01*
X325321Y215695D01*
X325254Y215647D01*
X325233Y215612D01*
G02X323945Y214883I-1288J773D01*
G02Y217887I0J1502D01*
G02X324800Y217620I0J-1502D01*
G01X324834Y217597D01*
X324915Y217580D01*
X325282Y217660D01*
X325349Y217708D01*
X325370Y217743D01*
G02X325526Y217956I1285J-777D01*
G03X325527Y217958I-173J88D01*
G03X325575Y218088I-152J130D01*
G01Y218352D01*
G03X325527Y218482I-200J0D01*
G01X325526Y218483D01*
G02Y220457I1131J987D01*
G01Y220458D01*
X325527D01*
G03X325575Y220588I-152J130D01*
G01Y220852D01*
G03X325527Y220982I-200J0D01*
G01X325526Y220983D01*
G02X325156Y221970I1131J987D01*
G37*
G36*
G01X475157D02*
G02X478161I1502J0D01*
G02X477791Y220983I-1501J0D01*
G01Y220982D01*
X477790D01*
G03X477742Y220852I152J-130D01*
G01Y220588D01*
G03X477790Y220458I200J0D01*
G01X477791Y220457D01*
G02Y218483I-1131J-987D01*
G01Y218482D01*
X477790D01*
G03X477742Y218352I152J-130D01*
G01Y218088D01*
G03X477790Y217958I200J0D01*
G01X477791Y217957D01*
G02X478161Y216970I-1131J-987D01*
G02X476659Y215468I-1502J0D01*
G02X475804Y215735I0J1502D01*
G01X475770Y215758D01*
X475689Y215775D01*
X475322Y215695D01*
X475255Y215647D01*
X475234Y215612D01*
G02X473946Y214883I-1288J773D01*
G02Y217887I0J1502D01*
G02X474801Y217620I0J-1502D01*
G01X474835Y217597D01*
X474916Y217580D01*
X475283Y217660D01*
X475350Y217708D01*
X475371Y217743D01*
G02X475527Y217956I1285J-777D01*
G03X475528Y217958I-173J88D01*
G03X475576Y218088I-152J130D01*
G01Y218352D01*
G03X475528Y218482I-200J0D01*
G01X475527Y218483D01*
G02Y220457I1131J987D01*
G01Y220458D01*
X475528D01*
G03X475576Y220588I-152J130D01*
G01Y220852D01*
G03X475528Y220982I-200J0D01*
G01X475527Y220983D01*
G02X475157Y221970I1131J987D01*
G37*
G36*
G01X577519D02*
G02X580523I1502J0D01*
G02X580153Y220983I-1501J0D01*
G01Y220982D01*
X580152D01*
G03X580104Y220852I152J-130D01*
G01Y220588D01*
G03X580152Y220458I200J0D01*
G01X580153Y220457D01*
G02Y218483I-1131J-987D01*
G01Y218482D01*
X580152D01*
G03X580104Y218352I152J-130D01*
G01Y218088D01*
G03X580152Y217958I200J0D01*
G01X580153Y217957D01*
G02X580523Y216970I-1131J-987D01*
G02X579021Y215468I-1502J0D01*
G02X578166Y215735I0J1502D01*
G01X578132Y215758D01*
X578051Y215775D01*
X577684Y215695D01*
X577617Y215647D01*
X577596Y215612D01*
G02X576308Y214883I-1288J773D01*
G02Y217887I0J1502D01*
G02X577163Y217620I0J-1502D01*
G01X577197Y217597D01*
X577278Y217580D01*
X577645Y217660D01*
X577712Y217708D01*
X577733Y217743D01*
G02X577889Y217956I1285J-777D01*
G03X577890Y217958I-173J88D01*
G03X577938Y218088I-152J130D01*
G01Y218352D01*
G03X577890Y218482I-200J0D01*
G01X577889Y218483D01*
G02Y220457I1131J987D01*
G01Y220458D01*
X577890D01*
G03X577938Y220588I-152J130D01*
G01Y220852D01*
G03X577890Y220982I-200J0D01*
G01X577889Y220983D01*
G02X577519Y221970I1131J987D01*
G37*
G36*
G01X679881D02*
G02X682885I1502J0D01*
G02X682515Y220983I-1501J0D01*
G01Y220982D01*
X682514D01*
G03X682466Y220852I152J-130D01*
G01Y220588D01*
G03X682514Y220458I200J0D01*
G01X682515Y220457D01*
G02Y218483I-1131J-987D01*
G01Y218482D01*
X682514D01*
G03X682466Y218352I152J-130D01*
G01Y218088D01*
G03X682514Y217958I200J0D01*
G01X682515Y217957D01*
G02X682885Y216970I-1131J-987D01*
G02X681383Y215468I-1502J0D01*
G02X680528Y215735I0J1502D01*
G01X680494Y215758D01*
X680413Y215775D01*
X680046Y215695D01*
X679979Y215647D01*
X679958Y215612D01*
G02X678670Y214883I-1288J773D01*
G02Y217887I0J1502D01*
G02X679525Y217620I0J-1502D01*
G01X679559Y217597D01*
X679640Y217580D01*
X680007Y217660D01*
X680074Y217708D01*
X680095Y217743D01*
G02X680251Y217956I1285J-777D01*
G03X680252Y217958I-173J88D01*
G03X680300Y218088I-152J130D01*
G01Y218352D01*
G03X680252Y218482I-200J0D01*
G01X680251Y218483D01*
G02Y220457I1131J987D01*
G01Y220458D01*
X680252D01*
G03X680300Y220588I-152J130D01*
G01Y220852D01*
G03X680252Y220982I-200J0D01*
G01X680251Y220983D01*
G02X679881Y221970I1131J987D01*
G37*
G36*
G01X782243D02*
G02X785247I1502J0D01*
G02X784877Y220983I-1501J0D01*
G01Y220982D01*
X784876D01*
G03X784828Y220852I152J-130D01*
G01Y220588D01*
G03X784876Y220458I200J0D01*
G01X784877Y220457D01*
G02Y218483I-1131J-987D01*
G01Y218482D01*
X784876D01*
G03X784828Y218352I152J-130D01*
G01Y218088D01*
G03X784876Y217958I200J0D01*
G01X784877Y217957D01*
G02X785247Y216970I-1131J-987D01*
G02X783745Y215468I-1502J0D01*
G02X782890Y215735I0J1502D01*
G01X782856Y215758D01*
X782775Y215775D01*
X782408Y215695D01*
X782341Y215647D01*
X782320Y215612D01*
G02X781032Y214883I-1288J773D01*
G02Y217887I0J1502D01*
G02X781887Y217620I0J-1502D01*
G01X781921Y217597D01*
X782002Y217580D01*
X782369Y217660D01*
X782436Y217708D01*
X782457Y217743D01*
G02X782613Y217956I1285J-777D01*
G03X782614Y217958I-173J88D01*
G03X782662Y218088I-152J130D01*
G01Y218352D01*
G03X782614Y218482I-200J0D01*
G01X782613Y218483D01*
G02Y220457I1131J987D01*
G01Y220458D01*
X782614D01*
G03X782662Y220588I-152J130D01*
G01Y220852D01*
G03X782614Y220982I-200J0D01*
G01X782613Y220983D01*
G02X782243Y221970I1131J987D01*
G37*
G36*
G01X1034605D02*
G02X1037609I1502J0D01*
G02X1037239Y220983I-1501J0D01*
G01Y220982D01*
X1037238D01*
G03X1037190Y220852I152J-130D01*
G01Y220588D01*
G03X1037238Y220458I200J0D01*
G01X1037239Y220457D01*
G02Y218483I-1131J-987D01*
G01Y218482D01*
X1037238D01*
G03X1037190Y218352I152J-130D01*
G01Y218088D01*
G03X1037238Y217958I200J0D01*
G01X1037239Y217957D01*
G02X1037609Y216970I-1131J-987D01*
G02X1036107Y215468I-1502J0D01*
G02X1035252Y215735I0J1502D01*
G01X1035218Y215758D01*
X1035137Y215775D01*
X1034770Y215695D01*
X1034703Y215647D01*
X1034682Y215612D01*
G02X1033394Y214883I-1288J773D01*
G02Y217887I0J1502D01*
G02X1034249Y217620I0J-1502D01*
G01X1034283Y217597D01*
X1034364Y217580D01*
X1034731Y217660D01*
X1034798Y217708D01*
X1034819Y217743D01*
G02X1034975Y217956I1285J-777D01*
G03X1034976Y217958I-173J88D01*
G03X1035024Y218088I-152J130D01*
G01Y218352D01*
G03X1034976Y218482I-200J0D01*
G01X1034975Y218483D01*
G02Y220457I1131J987D01*
G01Y220458D01*
X1034976D01*
G03X1035024Y220588I-152J130D01*
G01Y220852D01*
G03X1034976Y220982I-200J0D01*
G01X1034975Y220983D01*
G02X1034605Y221970I1131J987D01*
G37*
G36*
G01X1136967D02*
G02X1139971I1502J0D01*
G02X1139601Y220983I-1501J0D01*
G01Y220982D01*
X1139600D01*
G03X1139552Y220852I152J-130D01*
G01Y220588D01*
G03X1139600Y220458I200J0D01*
G01X1139601Y220457D01*
G02Y218483I-1131J-987D01*
G01Y218482D01*
X1139600D01*
G03X1139552Y218352I152J-130D01*
G01Y218088D01*
G03X1139600Y217958I200J0D01*
G01X1139601Y217957D01*
G02X1139971Y216970I-1131J-987D01*
G02X1138469Y215468I-1502J0D01*
G02X1137614Y215735I0J1502D01*
G01X1137580Y215758D01*
X1137499Y215775D01*
X1137132Y215695D01*
X1137065Y215647D01*
X1137044Y215612D01*
G02X1135756Y214883I-1288J773D01*
G02Y217887I0J1502D01*
G02X1136611Y217620I0J-1502D01*
G01X1136645Y217597D01*
X1136726Y217580D01*
X1137093Y217660D01*
X1137160Y217708D01*
X1137181Y217743D01*
G02X1137337Y217956I1285J-777D01*
G03X1137338Y217958I-173J88D01*
G03X1137386Y218088I-152J130D01*
G01Y218352D01*
G03X1137338Y218482I-200J0D01*
G01X1137337Y218483D01*
G02Y220457I1131J987D01*
G01Y220458D01*
X1137338D01*
G03X1137386Y220588I-152J130D01*
G01Y220852D01*
G03X1137338Y220982I-200J0D01*
G01X1137337Y220983D01*
G02X1136967Y221970I1131J987D01*
G37*
G36*
G01X1239329D02*
G02X1242333I1502J0D01*
G02X1241963Y220983I-1501J0D01*
G01Y220982D01*
X1241962D01*
G03X1241914Y220852I152J-130D01*
G01Y220588D01*
G03X1241962Y220458I200J0D01*
G01X1241963Y220457D01*
G02Y218483I-1131J-987D01*
G01Y218482D01*
X1241962D01*
G03X1241914Y218352I152J-130D01*
G01Y218088D01*
G03X1241962Y217958I200J0D01*
G01X1241963Y217957D01*
G02X1242333Y216970I-1131J-987D01*
G02X1240831Y215468I-1502J0D01*
G02X1239976Y215735I0J1502D01*
G01X1239942Y215758D01*
X1239861Y215775D01*
X1239494Y215695D01*
X1239427Y215647D01*
X1239406Y215612D01*
G02X1238118Y214883I-1288J773D01*
G02Y217887I0J1502D01*
G02X1238973Y217620I0J-1502D01*
G01X1239007Y217597D01*
X1239088Y217580D01*
X1239455Y217660D01*
X1239522Y217708D01*
X1239543Y217743D01*
G02X1239699Y217956I1285J-777D01*
G03X1239700Y217958I-173J88D01*
G03X1239748Y218088I-152J130D01*
G01Y218352D01*
G03X1239700Y218482I-200J0D01*
G01X1239699Y218483D01*
G02Y220457I1131J987D01*
G01Y220458D01*
X1239700D01*
G03X1239748Y220588I-152J130D01*
G01Y220852D01*
G03X1239700Y220982I-200J0D01*
G01X1239699Y220983D01*
G02X1239329Y221970I1131J987D01*
G37*
G36*
G01X1389330D02*
G02X1392334I1502J0D01*
G02X1391964Y220983I-1501J0D01*
G01Y220982D01*
X1391963D01*
G03X1391915Y220852I152J-130D01*
G01Y220588D01*
G03X1391963Y220458I200J0D01*
G01X1391964Y220457D01*
G02Y218483I-1131J-987D01*
G01Y218482D01*
X1391963D01*
G03X1391915Y218352I152J-130D01*
G01Y218088D01*
G03X1391963Y217958I200J0D01*
G01X1391964Y217957D01*
G02X1392334Y216970I-1131J-987D01*
G02X1390832Y215468I-1502J0D01*
G02X1389977Y215735I0J1502D01*
G01X1389943Y215758D01*
X1389862Y215775D01*
X1389495Y215695D01*
X1389428Y215647D01*
X1389407Y215612D01*
G02X1388119Y214883I-1288J773D01*
G02Y217887I0J1502D01*
G02X1388974Y217620I0J-1502D01*
G01X1389008Y217597D01*
X1389089Y217580D01*
X1389456Y217660D01*
X1389523Y217708D01*
X1389544Y217743D01*
G02X1389700Y217956I1285J-777D01*
G03X1389701Y217958I-173J88D01*
G03X1389749Y218088I-152J130D01*
G01Y218352D01*
G03X1389701Y218482I-200J0D01*
G01X1389700Y218483D01*
G02Y220457I1131J987D01*
G01Y220458D01*
X1389701D01*
G03X1389749Y220588I-152J130D01*
G01Y220852D01*
G03X1389701Y220982I-200J0D01*
G01X1389700Y220983D01*
G02X1389330Y221970I1131J987D01*
G37*
G36*
G01X1491692D02*
G02X1494696I1502J0D01*
G02X1494326Y220983I-1501J0D01*
G01Y220982D01*
X1494325D01*
G03X1494277Y220852I152J-130D01*
G01Y220588D01*
G03X1494325Y220458I200J0D01*
G01X1494326Y220457D01*
G02Y218483I-1131J-987D01*
G01Y218482D01*
X1494325D01*
G03X1494277Y218352I152J-130D01*
G01Y218088D01*
G03X1494325Y217958I200J0D01*
G01X1494326Y217957D01*
G02X1494696Y216970I-1131J-987D01*
G02X1493194Y215468I-1502J0D01*
G02X1492339Y215735I0J1502D01*
G01X1492305Y215758D01*
X1492224Y215775D01*
X1491857Y215695D01*
X1491790Y215647D01*
X1491769Y215612D01*
G02X1490481Y214883I-1288J773D01*
G02Y217887I0J1502D01*
G02X1491336Y217620I0J-1502D01*
G01X1491370Y217597D01*
X1491451Y217580D01*
X1491818Y217660D01*
X1491885Y217708D01*
X1491906Y217743D01*
G02X1492062Y217956I1285J-777D01*
G03X1492063Y217958I-173J88D01*
G03X1492111Y218088I-152J130D01*
G01Y218352D01*
G03X1492063Y218482I-200J0D01*
G01X1492062Y218483D01*
G02Y220457I1131J987D01*
G01Y220458D01*
X1492063D01*
G03X1492111Y220588I-152J130D01*
G01Y220852D01*
G03X1492063Y220982I-200J0D01*
G01X1492062Y220983D01*
G02X1491692Y221970I1131J987D01*
G37*
G36*
G01X1594054D02*
G02X1597058I1502J0D01*
G02X1596688Y220983I-1501J0D01*
G01Y220982D01*
X1596687D01*
G03X1596639Y220852I152J-130D01*
G01Y220588D01*
G03X1596687Y220458I200J0D01*
G01X1596688Y220457D01*
G02Y218483I-1131J-987D01*
G01Y218482D01*
X1596687D01*
G03X1596639Y218352I152J-130D01*
G01Y218088D01*
G03X1596687Y217958I200J0D01*
G01X1596688Y217957D01*
G02X1597058Y216970I-1131J-987D01*
G02X1595556Y215468I-1502J0D01*
G02X1594701Y215735I0J1502D01*
G01X1594667Y215758D01*
X1594586Y215775D01*
X1594219Y215695D01*
X1594152Y215647D01*
X1594131Y215612D01*
G02X1592843Y214883I-1288J773D01*
G02Y217887I0J1502D01*
G02X1593698Y217620I0J-1502D01*
G01X1593732Y217597D01*
X1593813Y217580D01*
X1594180Y217660D01*
X1594247Y217708D01*
X1594268Y217743D01*
G02X1594424Y217956I1285J-777D01*
G03X1594425Y217958I-173J88D01*
G03X1594473Y218088I-152J130D01*
G01Y218352D01*
G03X1594425Y218482I-200J0D01*
G01X1594424Y218483D01*
G02Y220457I1131J987D01*
G01Y220458D01*
X1594425D01*
G03X1594473Y220588I-152J130D01*
G01Y220852D01*
G03X1594425Y220982I-200J0D01*
G01X1594424Y220983D01*
G02X1594054Y221970I1131J987D01*
G37*
G36*
G01X1696416D02*
G02X1699420I1502J0D01*
G02X1699050Y220983I-1501J0D01*
G01Y220982D01*
X1699049D01*
G03X1699001Y220852I152J-130D01*
G01Y220588D01*
G03X1699049Y220458I200J0D01*
G01X1699050Y220457D01*
G02Y218483I-1131J-987D01*
G01Y218482D01*
X1699049D01*
G03X1699001Y218352I152J-130D01*
G01Y218088D01*
G03X1699049Y217958I200J0D01*
G01X1699050Y217957D01*
G02X1699420Y216970I-1131J-987D01*
G02X1697918Y215468I-1502J0D01*
G02X1697063Y215735I0J1502D01*
G01X1697029Y215758D01*
X1696948Y215775D01*
X1696581Y215695D01*
X1696514Y215647D01*
X1696493Y215612D01*
G02X1695205Y214883I-1288J773D01*
G02Y217887I0J1502D01*
G02X1696060Y217620I0J-1502D01*
G01X1696094Y217597D01*
X1696175Y217580D01*
X1696542Y217660D01*
X1696609Y217708D01*
X1696630Y217743D01*
G02X1696786Y217956I1285J-777D01*
G03X1696787Y217958I-173J88D01*
G03X1696835Y218088I-152J130D01*
G01Y218352D01*
G03X1696787Y218482I-200J0D01*
G01X1696786Y218483D01*
G02Y220457I1131J987D01*
G01Y220458D01*
X1696787D01*
G03X1696835Y220588I-152J130D01*
G01Y220852D01*
G03X1696787Y220982I-200J0D01*
G01X1696786Y220983D01*
G02X1696416Y221970I1131J987D01*
G37*
G36*
G01X84896Y224421D02*
G02X87900I1502J0D01*
G02X87633Y223566I-1502J0D01*
G01X87610Y223532D01*
X87593Y223451D01*
X87673Y223084D01*
X87721Y223017D01*
X87756Y222996D01*
G02X87969Y222840I-777J-1285D01*
G03X87971Y222839I88J173D01*
G03X88101Y222791I130J152D01*
G01X88365D01*
G03X88495Y222839I0J200D01*
G01X88496Y222840D01*
G02X90470I987J-1131D01*
G01X90471D01*
Y222839D01*
G03X90601Y222791I130J152D01*
G01X90865D01*
G03X90995Y222839I0J200D01*
G01X90996Y222840D01*
G02X91983Y223210I987J-1131D01*
G02Y220206I0J-1502D01*
G02X90996Y220576I0J1501D01*
G01X90995D01*
Y220577D01*
G03X90865Y220625I-130J-152D01*
G01X90601D01*
G03X90471Y220577I0J-200D01*
G01X90470Y220576D01*
G02X88496I-987J1131D01*
G01X88495D01*
Y220577D01*
G03X88365Y220625I-130J-152D01*
G01X88101D01*
G03X87971Y220577I0J-200D01*
G01X87970Y220576D01*
G02X86983Y220206I-987J1131D01*
G02X85481Y221708I0J1502D01*
G02X85748Y222563I1502J0D01*
G01X85771Y222597D01*
X85788Y222678D01*
X85708Y223045D01*
X85660Y223112D01*
X85625Y223133D01*
G02X84896Y224421I773J1288D01*
G37*
G36*
G01X187258D02*
G02X190262I1502J0D01*
G02X189995Y223566I-1502J0D01*
G01X189972Y223532D01*
X189955Y223451D01*
X190035Y223084D01*
X190083Y223017D01*
X190118Y222996D01*
G02X190331Y222840I-777J-1285D01*
G03X190333Y222839I88J173D01*
G03X190463Y222791I130J152D01*
G01X190727D01*
G03X190857Y222839I0J200D01*
G01X190858Y222840D01*
G02X192832I987J-1131D01*
G01X192833D01*
Y222839D01*
G03X192963Y222791I130J152D01*
G01X193227D01*
G03X193357Y222839I0J200D01*
G01X193358Y222840D01*
G02X194345Y223210I987J-1131D01*
G02Y220206I0J-1502D01*
G02X193358Y220576I0J1501D01*
G01X193357D01*
Y220577D01*
G03X193227Y220625I-130J-152D01*
G01X192963D01*
G03X192833Y220577I0J-200D01*
G01X192832Y220576D01*
G02X190858I-987J1131D01*
G01X190857D01*
Y220577D01*
G03X190727Y220625I-130J-152D01*
G01X190463D01*
G03X190333Y220577I0J-200D01*
G01X190332Y220576D01*
G02X189345Y220206I-987J1131D01*
G02X187843Y221708I0J1502D01*
G02X188110Y222563I1502J0D01*
G01X188133Y222597D01*
X188150Y222678D01*
X188070Y223045D01*
X188022Y223112D01*
X187987Y223133D01*
G02X187258Y224421I773J1288D01*
G37*
G36*
G01X289620D02*
G02X292624I1502J0D01*
G02X292357Y223566I-1502J0D01*
G01X292334Y223532D01*
X292317Y223451D01*
X292397Y223084D01*
X292445Y223017D01*
X292480Y222996D01*
G02X292693Y222840I-777J-1285D01*
G03X292695Y222839I88J173D01*
G03X292825Y222791I130J152D01*
G01X293089D01*
G03X293219Y222839I0J200D01*
G01X293220Y222840D01*
G02X295194I987J-1131D01*
G01X295195D01*
Y222839D01*
G03X295325Y222791I130J152D01*
G01X295589D01*
G03X295719Y222839I0J200D01*
G01X295720Y222840D01*
G02X296707Y223210I987J-1131D01*
G02Y220206I0J-1502D01*
G02X295720Y220576I0J1501D01*
G01X295719D01*
Y220577D01*
G03X295589Y220625I-130J-152D01*
G01X295325D01*
G03X295195Y220577I0J-200D01*
G01X295194Y220576D01*
G02X293220I-987J1131D01*
G01X293219D01*
Y220577D01*
G03X293089Y220625I-130J-152D01*
G01X292825D01*
G03X292695Y220577I0J-200D01*
G01X292694Y220576D01*
G02X291707Y220206I-987J1131D01*
G02X290205Y221708I0J1502D01*
G02X290472Y222563I1502J0D01*
G01X290495Y222597D01*
X290512Y222678D01*
X290432Y223045D01*
X290384Y223112D01*
X290349Y223133D01*
G02X289620Y224421I773J1288D01*
G37*
G36*
G01X391982D02*
G02X394986I1502J0D01*
G02X394719Y223566I-1502J0D01*
G01X394696Y223532D01*
X394679Y223451D01*
X394759Y223084D01*
X394807Y223017D01*
X394842Y222996D01*
G02X395055Y222840I-777J-1285D01*
G03X395057Y222839I88J173D01*
G03X395187Y222791I130J152D01*
G01X395451D01*
G03X395581Y222839I0J200D01*
G01X395582Y222840D01*
G02X397556I987J-1131D01*
G01X397557D01*
Y222839D01*
G03X397687Y222791I130J152D01*
G01X397951D01*
G03X398081Y222839I0J200D01*
G01X398082Y222840D01*
G02X399069Y223210I987J-1131D01*
G02Y220206I0J-1502D01*
G02X398082Y220576I0J1501D01*
G01X398081D01*
Y220577D01*
G03X397951Y220625I-130J-152D01*
G01X397687D01*
G03X397557Y220577I0J-200D01*
G01X397556Y220576D01*
G02X395582I-987J1131D01*
G01X395581D01*
Y220577D01*
G03X395451Y220625I-130J-152D01*
G01X395187D01*
G03X395057Y220577I0J-200D01*
G01X395056Y220576D01*
G02X394069Y220206I-987J1131D01*
G02X392567Y221708I0J1502D01*
G02X392834Y222563I1502J0D01*
G01X392857Y222597D01*
X392874Y222678D01*
X392794Y223045D01*
X392746Y223112D01*
X392711Y223133D01*
G02X391982Y224421I773J1288D01*
G37*
G36*
G01X541983D02*
G02X544987I1502J0D01*
G02X544720Y223566I-1502J0D01*
G01X544697Y223532D01*
X544680Y223451D01*
X544760Y223084D01*
X544808Y223017D01*
X544843Y222996D01*
G02X545056Y222840I-777J-1285D01*
G03X545058Y222839I88J173D01*
G03X545188Y222791I130J152D01*
G01X545452D01*
G03X545582Y222839I0J200D01*
G01X545583Y222840D01*
G02X547557I987J-1131D01*
G01X547558D01*
Y222839D01*
G03X547688Y222791I130J152D01*
G01X547952D01*
G03X548082Y222839I0J200D01*
G01X548083Y222840D01*
G02X549070Y223210I987J-1131D01*
G02Y220206I0J-1502D01*
G02X548083Y220576I0J1501D01*
G01X548082D01*
Y220577D01*
G03X547952Y220625I-130J-152D01*
G01X547688D01*
G03X547558Y220577I0J-200D01*
G01X547557Y220576D01*
G02X545583I-987J1131D01*
G01X545582D01*
Y220577D01*
G03X545452Y220625I-130J-152D01*
G01X545188D01*
G03X545058Y220577I0J-200D01*
G01X545057Y220576D01*
G02X544070Y220206I-987J1131D01*
G02X542568Y221708I0J1502D01*
G02X542835Y222563I1502J0D01*
G01X542858Y222597D01*
X542875Y222678D01*
X542795Y223045D01*
X542747Y223112D01*
X542712Y223133D01*
G02X541983Y224421I773J1288D01*
G37*
G36*
G01X644345D02*
G02X647349I1502J0D01*
G02X647082Y223566I-1502J0D01*
G01X647059Y223532D01*
X647042Y223451D01*
X647122Y223084D01*
X647170Y223017D01*
X647205Y222996D01*
G02X647418Y222840I-777J-1285D01*
G03X647420Y222839I88J173D01*
G03X647550Y222791I130J152D01*
G01X647814D01*
G03X647944Y222839I0J200D01*
G01X647945Y222840D01*
G02X649919I987J-1131D01*
G01X649920D01*
Y222839D01*
G03X650050Y222791I130J152D01*
G01X650314D01*
G03X650444Y222839I0J200D01*
G01X650445Y222840D01*
G02X651432Y223210I987J-1131D01*
G02Y220206I0J-1502D01*
G02X650445Y220576I0J1501D01*
G01X650444D01*
Y220577D01*
G03X650314Y220625I-130J-152D01*
G01X650050D01*
G03X649920Y220577I0J-200D01*
G01X649919Y220576D01*
G02X647945I-987J1131D01*
G01X647944D01*
Y220577D01*
G03X647814Y220625I-130J-152D01*
G01X647550D01*
G03X647420Y220577I0J-200D01*
G01X647419Y220576D01*
G02X646432Y220206I-987J1131D01*
G02X644930Y221708I0J1502D01*
G02X645197Y222563I1502J0D01*
G01X645220Y222597D01*
X645237Y222678D01*
X645157Y223045D01*
X645109Y223112D01*
X645074Y223133D01*
G02X644345Y224421I773J1288D01*
G37*
G36*
G01X746707D02*
G02X749711I1502J0D01*
G02X749444Y223566I-1502J0D01*
G01X749421Y223532D01*
X749404Y223451D01*
X749484Y223084D01*
X749532Y223017D01*
X749567Y222996D01*
G02X749780Y222840I-777J-1285D01*
G03X749782Y222839I88J173D01*
G03X749912Y222791I130J152D01*
G01X750176D01*
G03X750306Y222839I0J200D01*
G01X750307Y222840D01*
G02X752281I987J-1131D01*
G01X752282D01*
Y222839D01*
G03X752412Y222791I130J152D01*
G01X752676D01*
G03X752806Y222839I0J200D01*
G01X752807Y222840D01*
G02X753794Y223210I987J-1131D01*
G02Y220206I0J-1502D01*
G02X752807Y220576I0J1501D01*
G01X752806D01*
Y220577D01*
G03X752676Y220625I-130J-152D01*
G01X752412D01*
G03X752282Y220577I0J-200D01*
G01X752281Y220576D01*
G02X750307I-987J1131D01*
G01X750306D01*
Y220577D01*
G03X750176Y220625I-130J-152D01*
G01X749912D01*
G03X749782Y220577I0J-200D01*
G01X749781Y220576D01*
G02X748794Y220206I-987J1131D01*
G02X747292Y221708I0J1502D01*
G02X747559Y222563I1502J0D01*
G01X747582Y222597D01*
X747599Y222678D01*
X747519Y223045D01*
X747471Y223112D01*
X747436Y223133D01*
G02X746707Y224421I773J1288D01*
G37*
G36*
G01X849069D02*
G02X852073I1502J0D01*
G02X851806Y223566I-1502J0D01*
G01X851783Y223532D01*
X851766Y223451D01*
X851846Y223084D01*
X851894Y223017D01*
X851929Y222996D01*
G02X852142Y222840I-777J-1285D01*
G03X852144Y222839I88J173D01*
G03X852274Y222791I130J152D01*
G01X852538D01*
G03X852668Y222839I0J200D01*
G01X852669Y222840D01*
G02X854643I987J-1131D01*
G01X854644D01*
Y222839D01*
G03X854774Y222791I130J152D01*
G01X855038D01*
G03X855168Y222839I0J200D01*
G01X855169Y222840D01*
G02X856156Y223210I987J-1131D01*
G02Y220206I0J-1502D01*
G02X855169Y220576I0J1501D01*
G01X855168D01*
Y220577D01*
G03X855038Y220625I-130J-152D01*
G01X854774D01*
G03X854644Y220577I0J-200D01*
G01X854643Y220576D01*
G02X852669I-987J1131D01*
G01X852668D01*
Y220577D01*
G03X852538Y220625I-130J-152D01*
G01X852274D01*
G03X852144Y220577I0J-200D01*
G01X852143Y220576D01*
G02X851156Y220206I-987J1131D01*
G02X849654Y221708I0J1502D01*
G02X849921Y222563I1502J0D01*
G01X849944Y222597D01*
X849961Y222678D01*
X849881Y223045D01*
X849833Y223112D01*
X849798Y223133D01*
G02X849069Y224421I773J1288D01*
G37*
G36*
G01X999069D02*
G02X1002073I1502J0D01*
G02X1001806Y223566I-1502J0D01*
G01X1001783Y223532D01*
X1001766Y223451D01*
X1001846Y223084D01*
X1001894Y223017D01*
X1001929Y222996D01*
G02X1002142Y222840I-777J-1285D01*
G03X1002144Y222839I88J173D01*
G03X1002274Y222791I130J152D01*
G01X1002538D01*
G03X1002668Y222839I0J200D01*
G01X1002669Y222840D01*
G02X1004643I987J-1131D01*
G01X1004644D01*
Y222839D01*
G03X1004774Y222791I130J152D01*
G01X1005038D01*
G03X1005168Y222839I0J200D01*
G01X1005169Y222840D01*
G02X1006156Y223210I987J-1131D01*
G02Y220206I0J-1502D01*
G02X1005169Y220576I0J1501D01*
G01X1005168D01*
Y220577D01*
G03X1005038Y220625I-130J-152D01*
G01X1004774D01*
G03X1004644Y220577I0J-200D01*
G01X1004643Y220576D01*
G02X1002669I-987J1131D01*
G01X1002668D01*
Y220577D01*
G03X1002538Y220625I-130J-152D01*
G01X1002274D01*
G03X1002144Y220577I0J-200D01*
G01X1002143Y220576D01*
G02X1001156Y220206I-987J1131D01*
G02X999654Y221708I0J1502D01*
G02X999921Y222563I1502J0D01*
G01X999944Y222597D01*
X999961Y222678D01*
X999881Y223045D01*
X999833Y223112D01*
X999798Y223133D01*
G02X999069Y224421I773J1288D01*
G37*
G36*
G01X1101431D02*
G02X1104435I1502J0D01*
G02X1104168Y223566I-1502J0D01*
G01X1104145Y223532D01*
X1104128Y223451D01*
X1104208Y223084D01*
X1104256Y223017D01*
X1104291Y222996D01*
G02X1104504Y222840I-777J-1285D01*
G03X1104506Y222839I88J173D01*
G03X1104636Y222791I130J152D01*
G01X1104900D01*
G03X1105030Y222839I0J200D01*
G01X1105031Y222840D01*
G02X1107005I987J-1131D01*
G01X1107006D01*
Y222839D01*
G03X1107136Y222791I130J152D01*
G01X1107400D01*
G03X1107530Y222839I0J200D01*
G01X1107531Y222840D01*
G02X1108518Y223210I987J-1131D01*
G02Y220206I0J-1502D01*
G02X1107531Y220576I0J1501D01*
G01X1107530D01*
Y220577D01*
G03X1107400Y220625I-130J-152D01*
G01X1107136D01*
G03X1107006Y220577I0J-200D01*
G01X1107005Y220576D01*
G02X1105031I-987J1131D01*
G01X1105030D01*
Y220577D01*
G03X1104900Y220625I-130J-152D01*
G01X1104636D01*
G03X1104506Y220577I0J-200D01*
G01X1104505Y220576D01*
G02X1103518Y220206I-987J1131D01*
G02X1102016Y221708I0J1502D01*
G02X1102283Y222563I1502J0D01*
G01X1102306Y222597D01*
X1102323Y222678D01*
X1102243Y223045D01*
X1102195Y223112D01*
X1102160Y223133D01*
G02X1101431Y224421I773J1288D01*
G37*
G36*
G01X1203793D02*
G02X1206797I1502J0D01*
G02X1206530Y223566I-1502J0D01*
G01X1206507Y223532D01*
X1206490Y223451D01*
X1206570Y223084D01*
X1206618Y223017D01*
X1206653Y222996D01*
G02X1206866Y222840I-777J-1285D01*
G03X1206868Y222839I88J173D01*
G03X1206998Y222791I130J152D01*
G01X1207262D01*
G03X1207392Y222839I0J200D01*
G01X1207393Y222840D01*
G02X1209367I987J-1131D01*
G01X1209368D01*
Y222839D01*
G03X1209498Y222791I130J152D01*
G01X1209762D01*
G03X1209892Y222839I0J200D01*
G01X1209893Y222840D01*
G02X1210880Y223210I987J-1131D01*
G02Y220206I0J-1502D01*
G02X1209893Y220576I0J1501D01*
G01X1209892D01*
Y220577D01*
G03X1209762Y220625I-130J-152D01*
G01X1209498D01*
G03X1209368Y220577I0J-200D01*
G01X1209367Y220576D01*
G02X1207393I-987J1131D01*
G01X1207392D01*
Y220577D01*
G03X1207262Y220625I-130J-152D01*
G01X1206998D01*
G03X1206868Y220577I0J-200D01*
G01X1206867Y220576D01*
G02X1205880Y220206I-987J1131D01*
G02X1204378Y221708I0J1502D01*
G02X1204645Y222563I1502J0D01*
G01X1204668Y222597D01*
X1204685Y222678D01*
X1204605Y223045D01*
X1204557Y223112D01*
X1204522Y223133D01*
G02X1203793Y224421I773J1288D01*
G37*
G36*
G01X1306155D02*
G02X1309159I1502J0D01*
G02X1308892Y223566I-1502J0D01*
G01X1308869Y223532D01*
X1308852Y223451D01*
X1308932Y223084D01*
X1308980Y223017D01*
X1309015Y222996D01*
G02X1309228Y222840I-777J-1285D01*
G03X1309230Y222839I88J173D01*
G03X1309360Y222791I130J152D01*
G01X1309624D01*
G03X1309754Y222839I0J200D01*
G01X1309755Y222840D01*
G02X1311729I987J-1131D01*
G01X1311730D01*
Y222839D01*
G03X1311860Y222791I130J152D01*
G01X1312124D01*
G03X1312254Y222839I0J200D01*
G01X1312255Y222840D01*
G02X1313242Y223210I987J-1131D01*
G02Y220206I0J-1502D01*
G02X1312255Y220576I0J1501D01*
G01X1312254D01*
Y220577D01*
G03X1312124Y220625I-130J-152D01*
G01X1311860D01*
G03X1311730Y220577I0J-200D01*
G01X1311729Y220576D01*
G02X1309755I-987J1131D01*
G01X1309754D01*
Y220577D01*
G03X1309624Y220625I-130J-152D01*
G01X1309360D01*
G03X1309230Y220577I0J-200D01*
G01X1309229Y220576D01*
G02X1308242Y220206I-987J1131D01*
G02X1306740Y221708I0J1502D01*
G02X1307007Y222563I1502J0D01*
G01X1307030Y222597D01*
X1307047Y222678D01*
X1306967Y223045D01*
X1306919Y223112D01*
X1306884Y223133D01*
G02X1306155Y224421I773J1288D01*
G37*
G36*
G01X1456156D02*
G02X1459160I1502J0D01*
G02X1458893Y223566I-1502J0D01*
G01X1458870Y223532D01*
X1458853Y223451D01*
X1458933Y223084D01*
X1458981Y223017D01*
X1459016Y222996D01*
G02X1459229Y222840I-777J-1285D01*
G03X1459231Y222839I88J173D01*
G03X1459361Y222791I130J152D01*
G01X1459625D01*
G03X1459755Y222839I0J200D01*
G01X1459756Y222840D01*
G02X1461730I987J-1131D01*
G01X1461731D01*
Y222839D01*
G03X1461861Y222791I130J152D01*
G01X1462125D01*
G03X1462255Y222839I0J200D01*
G01X1462256Y222840D01*
G02X1463243Y223210I987J-1131D01*
G02Y220206I0J-1502D01*
G02X1462256Y220576I0J1501D01*
G01X1462255D01*
Y220577D01*
G03X1462125Y220625I-130J-152D01*
G01X1461861D01*
G03X1461731Y220577I0J-200D01*
G01X1461730Y220576D01*
G02X1459756I-987J1131D01*
G01X1459755D01*
Y220577D01*
G03X1459625Y220625I-130J-152D01*
G01X1459361D01*
G03X1459231Y220577I0J-200D01*
G01X1459230Y220576D01*
G02X1458243Y220206I-987J1131D01*
G02X1456741Y221708I0J1502D01*
G02X1457008Y222563I1502J0D01*
G01X1457031Y222597D01*
X1457048Y222678D01*
X1456968Y223045D01*
X1456920Y223112D01*
X1456885Y223133D01*
G02X1456156Y224421I773J1288D01*
G37*
G36*
G01X1558518D02*
G02X1561522I1502J0D01*
G02X1561255Y223566I-1502J0D01*
G01X1561232Y223532D01*
X1561215Y223451D01*
X1561295Y223084D01*
X1561343Y223017D01*
X1561378Y222996D01*
G02X1561591Y222840I-777J-1285D01*
G03X1561593Y222839I88J173D01*
G03X1561723Y222791I130J152D01*
G01X1561987D01*
G03X1562117Y222839I0J200D01*
G01X1562118Y222840D01*
G02X1564092I987J-1131D01*
G01X1564093D01*
Y222839D01*
G03X1564223Y222791I130J152D01*
G01X1564487D01*
G03X1564617Y222839I0J200D01*
G01X1564618Y222840D01*
G02X1565605Y223210I987J-1131D01*
G02Y220206I0J-1502D01*
G02X1564618Y220576I0J1501D01*
G01X1564617D01*
Y220577D01*
G03X1564487Y220625I-130J-152D01*
G01X1564223D01*
G03X1564093Y220577I0J-200D01*
G01X1564092Y220576D01*
G02X1562118I-987J1131D01*
G01X1562117D01*
Y220577D01*
G03X1561987Y220625I-130J-152D01*
G01X1561723D01*
G03X1561593Y220577I0J-200D01*
G01X1561592Y220576D01*
G02X1560605Y220206I-987J1131D01*
G02X1559103Y221708I0J1502D01*
G02X1559370Y222563I1502J0D01*
G01X1559393Y222597D01*
X1559410Y222678D01*
X1559330Y223045D01*
X1559282Y223112D01*
X1559247Y223133D01*
G02X1558518Y224421I773J1288D01*
G37*
G36*
G01X1660880D02*
G02X1663884I1502J0D01*
G02X1663617Y223566I-1502J0D01*
G01X1663594Y223532D01*
X1663577Y223451D01*
X1663657Y223084D01*
X1663705Y223017D01*
X1663740Y222996D01*
G02X1663953Y222840I-777J-1285D01*
G03X1663955Y222839I88J173D01*
G03X1664085Y222791I130J152D01*
G01X1664349D01*
G03X1664479Y222839I0J200D01*
G01X1664480Y222840D01*
G02X1666454I987J-1131D01*
G01X1666455D01*
Y222839D01*
G03X1666585Y222791I130J152D01*
G01X1666849D01*
G03X1666979Y222839I0J200D01*
G01X1666980Y222840D01*
G02X1667967Y223210I987J-1131D01*
G02Y220206I0J-1502D01*
G02X1666980Y220576I0J1501D01*
G01X1666979D01*
Y220577D01*
G03X1666849Y220625I-130J-152D01*
G01X1666585D01*
G03X1666455Y220577I0J-200D01*
G01X1666454Y220576D01*
G02X1664480I-987J1131D01*
G01X1664479D01*
Y220577D01*
G03X1664349Y220625I-130J-152D01*
G01X1664085D01*
G03X1663955Y220577I0J-200D01*
G01X1663954Y220576D01*
G02X1662967Y220206I-987J1131D01*
G02X1661465Y221708I0J1502D01*
G02X1661732Y222563I1502J0D01*
G01X1661755Y222597D01*
X1661772Y222678D01*
X1661692Y223045D01*
X1661644Y223112D01*
X1661609Y223133D01*
G02X1660880Y224421I773J1288D01*
G37*
G36*
G01X1763242D02*
G02X1766246I1502J0D01*
G02X1765979Y223566I-1502J0D01*
G01X1765956Y223532D01*
X1765939Y223451D01*
X1766019Y223084D01*
X1766067Y223017D01*
X1766102Y222996D01*
G02X1766315Y222840I-777J-1285D01*
G03X1766317Y222839I88J173D01*
G03X1766447Y222791I130J152D01*
G01X1766711D01*
G03X1766841Y222839I0J200D01*
G01X1766842Y222840D01*
G02X1768816I987J-1131D01*
G01X1768817D01*
Y222839D01*
G03X1768947Y222791I130J152D01*
G01X1769211D01*
G03X1769341Y222839I0J200D01*
G01X1769342Y222840D01*
G02X1770329Y223210I987J-1131D01*
G02Y220206I0J-1502D01*
G02X1769342Y220576I0J1501D01*
G01X1769341D01*
Y220577D01*
G03X1769211Y220625I-130J-152D01*
G01X1768947D01*
G03X1768817Y220577I0J-200D01*
G01X1768816Y220576D01*
G02X1766842I-987J1131D01*
G01X1766841D01*
Y220577D01*
G03X1766711Y220625I-130J-152D01*
G01X1766447D01*
G03X1766317Y220577I0J-200D01*
G01X1766316Y220576D01*
G02X1765329Y220206I-987J1131D01*
G02X1763827Y221708I0J1502D01*
G02X1764094Y222563I1502J0D01*
G01X1764117Y222597D01*
X1764134Y222678D01*
X1764054Y223045D01*
X1764006Y223112D01*
X1763971Y223133D01*
G02X1763242Y224421I773J1288D01*
G37*
G36*
G01X75349Y224712D02*
G02X78353I1502J0D01*
G02X77983Y223725I-1501J0D01*
G01Y223724D01*
X77982D01*
G03X77934Y223594I152J-130D01*
G01Y223330D01*
G03X77982Y223200I200J0D01*
G01X77983Y223199D01*
G02X78353Y222212I-1131J-987D01*
G02X75349I-1502J0D01*
G02X75719Y223199I1501J0D01*
G01Y223200D01*
X75720D01*
G03X75768Y223330I-152J130D01*
G01Y223594D01*
G03X75720Y223724I-200J0D01*
G01X75719Y223725D01*
G02X75349Y224712I1131J987D01*
G37*
G36*
G01X177711D02*
G02X180715I1502J0D01*
G02X180345Y223725I-1501J0D01*
G01Y223724D01*
X180344D01*
G03X180296Y223594I152J-130D01*
G01Y223330D01*
G03X180344Y223200I200J0D01*
G01X180345Y223199D01*
G02X180715Y222212I-1131J-987D01*
G02X177711I-1502J0D01*
G02X178081Y223199I1501J0D01*
G01Y223200D01*
X178082D01*
G03X178130Y223330I-152J130D01*
G01Y223594D01*
G03X178082Y223724I-200J0D01*
G01X178081Y223725D01*
G02X177711Y224712I1131J987D01*
G37*
G36*
G01X280073D02*
G02X283077I1502J0D01*
G02X282707Y223725I-1501J0D01*
G01Y223724D01*
X282706D01*
G03X282658Y223594I152J-130D01*
G01Y223330D01*
G03X282706Y223200I200J0D01*
G01X282707Y223199D01*
G02X283077Y222212I-1131J-987D01*
G02X280073I-1502J0D01*
G02X280443Y223199I1501J0D01*
G01Y223200D01*
X280444D01*
G03X280492Y223330I-152J130D01*
G01Y223594D01*
G03X280444Y223724I-200J0D01*
G01X280443Y223725D01*
G02X280073Y224712I1131J987D01*
G37*
G36*
G01X382435D02*
G02X385439I1502J0D01*
G02X385069Y223725I-1501J0D01*
G01Y223724D01*
X385068D01*
G03X385020Y223594I152J-130D01*
G01Y223330D01*
G03X385068Y223200I200J0D01*
G01X385069Y223199D01*
G02X385439Y222212I-1131J-987D01*
G02X382435I-1502J0D01*
G02X382805Y223199I1501J0D01*
G01Y223200D01*
X382806D01*
G03X382854Y223330I-152J130D01*
G01Y223594D01*
G03X382806Y223724I-200J0D01*
G01X382805Y223725D01*
G02X382435Y224712I1131J987D01*
G37*
G36*
G01X532436D02*
G02X535440I1502J0D01*
G02X535070Y223725I-1501J0D01*
G01Y223724D01*
X535069D01*
G03X535021Y223594I152J-130D01*
G01Y223330D01*
G03X535069Y223200I200J0D01*
G01X535070Y223199D01*
G02X535440Y222212I-1131J-987D01*
G02X532436I-1502J0D01*
G02X532806Y223199I1501J0D01*
G01Y223200D01*
X532807D01*
G03X532855Y223330I-152J130D01*
G01Y223594D01*
G03X532807Y223724I-200J0D01*
G01X532806Y223725D01*
G02X532436Y224712I1131J987D01*
G37*
G36*
G01X634798D02*
G02X637802I1502J0D01*
G02X637432Y223725I-1501J0D01*
G01Y223724D01*
X637431D01*
G03X637383Y223594I152J-130D01*
G01Y223330D01*
G03X637431Y223200I200J0D01*
G01X637432Y223199D01*
G02X637802Y222212I-1131J-987D01*
G02X634798I-1502J0D01*
G02X635168Y223199I1501J0D01*
G01Y223200D01*
X635169D01*
G03X635217Y223330I-152J130D01*
G01Y223594D01*
G03X635169Y223724I-200J0D01*
G01X635168Y223725D01*
G02X634798Y224712I1131J987D01*
G37*
G36*
G01X737160D02*
G02X740164I1502J0D01*
G02X739794Y223725I-1501J0D01*
G01Y223724D01*
X739793D01*
G03X739745Y223594I152J-130D01*
G01Y223330D01*
G03X739793Y223200I200J0D01*
G01X739794Y223199D01*
G02X740164Y222212I-1131J-987D01*
G02X737160I-1502J0D01*
G02X737530Y223199I1501J0D01*
G01Y223200D01*
X737531D01*
G03X737579Y223330I-152J130D01*
G01Y223594D01*
G03X737531Y223724I-200J0D01*
G01X737530Y223725D01*
G02X737160Y224712I1131J987D01*
G37*
G36*
G01X839522D02*
G02X842526I1502J0D01*
G02X842156Y223725I-1501J0D01*
G01Y223724D01*
X842155D01*
G03X842107Y223594I152J-130D01*
G01Y223330D01*
G03X842155Y223200I200J0D01*
G01X842156Y223199D01*
G02X842526Y222212I-1131J-987D01*
G02X839522I-1502J0D01*
G02X839892Y223199I1501J0D01*
G01Y223200D01*
X839893D01*
G03X839941Y223330I-152J130D01*
G01Y223594D01*
G03X839893Y223724I-200J0D01*
G01X839892Y223725D01*
G02X839522Y224712I1131J987D01*
G37*
G36*
G01X989522D02*
G02X992526I1502J0D01*
G02X992156Y223725I-1501J0D01*
G01Y223724D01*
X992155D01*
G03X992107Y223594I152J-130D01*
G01Y223330D01*
G03X992155Y223200I200J0D01*
G01X992156Y223199D01*
G02X992526Y222212I-1131J-987D01*
G02X989522I-1502J0D01*
G02X989892Y223199I1501J0D01*
G01Y223200D01*
X989893D01*
G03X989941Y223330I-152J130D01*
G01Y223594D01*
G03X989893Y223724I-200J0D01*
G01X989892Y223725D01*
G02X989522Y224712I1131J987D01*
G37*
G36*
G01X1091884D02*
G02X1094888I1502J0D01*
G02X1094518Y223725I-1501J0D01*
G01Y223724D01*
X1094517D01*
G03X1094469Y223594I152J-130D01*
G01Y223330D01*
G03X1094517Y223200I200J0D01*
G01X1094518Y223199D01*
G02X1094888Y222212I-1131J-987D01*
G02X1091884I-1502J0D01*
G02X1092254Y223199I1501J0D01*
G01Y223200D01*
X1092255D01*
G03X1092303Y223330I-152J130D01*
G01Y223594D01*
G03X1092255Y223724I-200J0D01*
G01X1092254Y223725D01*
G02X1091884Y224712I1131J987D01*
G37*
G36*
G01X1194246D02*
G02X1197250I1502J0D01*
G02X1196880Y223725I-1501J0D01*
G01Y223724D01*
X1196879D01*
G03X1196831Y223594I152J-130D01*
G01Y223330D01*
G03X1196879Y223200I200J0D01*
G01X1196880Y223199D01*
G02X1197250Y222212I-1131J-987D01*
G02X1194246I-1502J0D01*
G02X1194616Y223199I1501J0D01*
G01Y223200D01*
X1194617D01*
G03X1194665Y223330I-152J130D01*
G01Y223594D01*
G03X1194617Y223724I-200J0D01*
G01X1194616Y223725D01*
G02X1194246Y224712I1131J987D01*
G37*
G36*
G01X1296608D02*
G02X1299612I1502J0D01*
G02X1299242Y223725I-1501J0D01*
G01Y223724D01*
X1299241D01*
G03X1299193Y223594I152J-130D01*
G01Y223330D01*
G03X1299241Y223200I200J0D01*
G01X1299242Y223199D01*
G02X1299612Y222212I-1131J-987D01*
G02X1296608I-1502J0D01*
G02X1296978Y223199I1501J0D01*
G01Y223200D01*
X1296979D01*
G03X1297027Y223330I-152J130D01*
G01Y223594D01*
G03X1296979Y223724I-200J0D01*
G01X1296978Y223725D01*
G02X1296608Y224712I1131J987D01*
G37*
G36*
G01X1446609D02*
G02X1449613I1502J0D01*
G02X1449243Y223725I-1501J0D01*
G01Y223724D01*
X1449242D01*
G03X1449194Y223594I152J-130D01*
G01Y223330D01*
G03X1449242Y223200I200J0D01*
G01X1449243Y223199D01*
G02X1449613Y222212I-1131J-987D01*
G02X1446609I-1502J0D01*
G02X1446979Y223199I1501J0D01*
G01Y223200D01*
X1446980D01*
G03X1447028Y223330I-152J130D01*
G01Y223594D01*
G03X1446980Y223724I-200J0D01*
G01X1446979Y223725D01*
G02X1446609Y224712I1131J987D01*
G37*
G36*
G01X1548971D02*
G02X1551975I1502J0D01*
G02X1551605Y223725I-1501J0D01*
G01Y223724D01*
X1551604D01*
G03X1551556Y223594I152J-130D01*
G01Y223330D01*
G03X1551604Y223200I200J0D01*
G01X1551605Y223199D01*
G02X1551975Y222212I-1131J-987D01*
G02X1548971I-1502J0D01*
G02X1549341Y223199I1501J0D01*
G01Y223200D01*
X1549342D01*
G03X1549390Y223330I-152J130D01*
G01Y223594D01*
G03X1549342Y223724I-200J0D01*
G01X1549341Y223725D01*
G02X1548971Y224712I1131J987D01*
G37*
G36*
G01X1651333D02*
G02X1654337I1502J0D01*
G02X1653967Y223725I-1501J0D01*
G01Y223724D01*
X1653966D01*
G03X1653918Y223594I152J-130D01*
G01Y223330D01*
G03X1653966Y223200I200J0D01*
G01X1653967Y223199D01*
G02X1654337Y222212I-1131J-987D01*
G02X1651333I-1502J0D01*
G02X1651703Y223199I1501J0D01*
G01Y223200D01*
X1651704D01*
G03X1651752Y223330I-152J130D01*
G01Y223594D01*
G03X1651704Y223724I-200J0D01*
G01X1651703Y223725D01*
G02X1651333Y224712I1131J987D01*
G37*
G36*
G01X1753695D02*
G02X1756699I1502J0D01*
G02X1756329Y223725I-1501J0D01*
G01Y223724D01*
X1756328D01*
G03X1756280Y223594I152J-130D01*
G01Y223330D01*
G03X1756328Y223200I200J0D01*
G01X1756329Y223199D01*
G02X1756699Y222212I-1131J-987D01*
G02X1753695I-1502J0D01*
G02X1754065Y223199I1501J0D01*
G01Y223200D01*
X1754066D01*
G03X1754114Y223330I-152J130D01*
G01Y223594D01*
G03X1754066Y223724I-200J0D01*
G01X1754065Y223725D01*
G02X1753695Y224712I1131J987D01*
G37*
G36*
G01X189508Y229474D02*
Y229768D01*
G03X189443Y229915I-200J-1D01*
G02X188958Y231021I1019J1106D01*
G02X191962I1502J0D01*
G02X191477Y229915I-1504J0D01*
G03X191412Y229768I135J-148D01*
G01Y229474D01*
G03X191477Y229327I200J1D01*
G02X191962Y228221I-1019J-1106D01*
G02X188958I-1502J0D01*
G02X189443Y229327I1504J0D01*
G03X189508Y229474I-135J148D01*
G37*
G36*
G01X291870D02*
Y229768D01*
G03X291805Y229915I-200J-1D01*
G02X291320Y231021I1019J1106D01*
G02X294324I1502J0D01*
G02X293839Y229915I-1504J0D01*
G03X293774Y229768I135J-148D01*
G01Y229474D01*
G03X293839Y229327I200J1D01*
G02X294324Y228221I-1019J-1106D01*
G02X291320I-1502J0D01*
G02X291805Y229327I1504J0D01*
G03X291870Y229474I-135J148D01*
G37*
G36*
G01X394232D02*
Y229768D01*
G03X394167Y229915I-200J-1D01*
G02X393682Y231021I1019J1106D01*
G02X396686I1502J0D01*
G02X396201Y229915I-1504J0D01*
G03X396136Y229768I135J-148D01*
G01Y229474D01*
G03X396201Y229327I200J1D01*
G02X396686Y228221I-1019J-1106D01*
G02X393682I-1502J0D01*
G02X394167Y229327I1504J0D01*
G03X394232Y229474I-135J148D01*
G37*
G36*
G01X544233D02*
Y229768D01*
G03X544168Y229915I-200J-1D01*
G02X543683Y231021I1019J1106D01*
G02X546687I1502J0D01*
G02X546202Y229915I-1504J0D01*
G03X546137Y229768I135J-148D01*
G01Y229474D01*
G03X546202Y229327I200J1D01*
G02X546687Y228221I-1019J-1106D01*
G02X543683I-1502J0D01*
G02X544168Y229327I1504J0D01*
G03X544233Y229474I-135J148D01*
G37*
G36*
G01X748957D02*
Y229768D01*
G03X748892Y229915I-200J-1D01*
G02X748407Y231021I1019J1106D01*
G02X751411I1502J0D01*
G02X750926Y229915I-1504J0D01*
G03X750861Y229768I135J-148D01*
G01Y229474D01*
G03X750926Y229327I200J1D01*
G02X751411Y228221I-1019J-1106D01*
G02X748407I-1502J0D01*
G02X748892Y229327I1504J0D01*
G03X748957Y229474I-135J148D01*
G37*
G36*
G01X1001319D02*
Y229768D01*
G03X1001254Y229915I-200J-1D01*
G02X1000769Y231021I1019J1106D01*
G02X1003773I1502J0D01*
G02X1003288Y229915I-1504J0D01*
G03X1003223Y229768I135J-148D01*
G01Y229474D01*
G03X1003288Y229327I200J1D01*
G02X1003773Y228221I-1019J-1106D01*
G02X1000769I-1502J0D01*
G02X1001254Y229327I1504J0D01*
G03X1001319Y229474I-135J148D01*
G37*
G36*
G01X1103681D02*
Y229768D01*
G03X1103616Y229915I-200J-1D01*
G02X1103131Y231021I1019J1106D01*
G02X1106135I1502J0D01*
G02X1105650Y229915I-1504J0D01*
G03X1105585Y229768I135J-148D01*
G01Y229474D01*
G03X1105650Y229327I200J1D01*
G02X1106135Y228221I-1019J-1106D01*
G02X1103131I-1502J0D01*
G02X1103616Y229327I1504J0D01*
G03X1103681Y229474I-135J148D01*
G37*
G36*
G01X1206043D02*
Y229768D01*
G03X1205978Y229915I-200J-1D01*
G02X1205493Y231021I1019J1106D01*
G02X1208497I1502J0D01*
G02X1208012Y229915I-1504J0D01*
G03X1207947Y229768I135J-148D01*
G01Y229474D01*
G03X1208012Y229327I200J1D01*
G02X1208497Y228221I-1019J-1106D01*
G02X1205493I-1502J0D01*
G02X1205978Y229327I1504J0D01*
G03X1206043Y229474I-135J148D01*
G37*
G36*
G01X1458406D02*
Y229768D01*
G03X1458341Y229915I-200J-1D01*
G02X1457856Y231021I1019J1106D01*
G02X1460860I1502J0D01*
G02X1460375Y229915I-1504J0D01*
G03X1460310Y229768I135J-148D01*
G01Y229474D01*
G03X1460375Y229327I200J1D01*
G02X1460860Y228221I-1019J-1106D01*
G02X1457856I-1502J0D01*
G02X1458341Y229327I1504J0D01*
G03X1458406Y229474I-135J148D01*
G37*
G36*
G01X1560768D02*
Y229768D01*
G03X1560703Y229915I-200J-1D01*
G02X1560218Y231021I1019J1106D01*
G02X1563222I1502J0D01*
G02X1562737Y229915I-1504J0D01*
G03X1562672Y229768I135J-148D01*
G01Y229474D01*
G03X1562737Y229327I200J1D01*
G02X1563222Y228221I-1019J-1106D01*
G02X1560218I-1502J0D01*
G02X1560703Y229327I1504J0D01*
G03X1560768Y229474I-135J148D01*
G37*
G36*
G01X1765492D02*
Y229768D01*
G03X1765427Y229915I-200J-1D01*
G02X1764942Y231021I1019J1106D01*
G02X1767946I1502J0D01*
G02X1767461Y229915I-1504J0D01*
G03X1767396Y229768I135J-148D01*
G01Y229474D01*
G03X1767461Y229327I200J1D01*
G02X1767946Y228221I-1019J-1106D01*
G02X1764942I-1502J0D01*
G02X1765427Y229327I1504J0D01*
G03X1765492Y229474I-135J148D01*
G37*
G36*
G01X53231Y231226D02*
G02X56235I1502J0D01*
G02X55865Y230239I-1501J0D01*
G01Y230238D01*
X55864D01*
G03X55816Y230108I152J-130D01*
G01Y229844D01*
G03X55864Y229714I200J0D01*
G01X55865Y229713D01*
G02Y227739I-1131J-987D01*
G01Y227738D01*
X55864D01*
G03X55816Y227608I152J-130D01*
G01Y227344D01*
G03X55864Y227214I200J0D01*
G01X55865Y227213D01*
G02Y225239I-1131J-987D01*
G01Y225238D01*
X55864D01*
G03X55816Y225108I152J-130D01*
G01Y224844D01*
G03X55864Y224714I200J0D01*
G01X55865Y224713D01*
G02X56235Y223726I-1131J-987D01*
G02X53231I-1502J0D01*
G02X53601Y224713I1501J0D01*
G01Y224714D01*
X53602D01*
G03X53650Y224844I-152J130D01*
G01Y225108D01*
G03X53602Y225238I-200J0D01*
G01X53601Y225239D01*
G02Y227213I1131J987D01*
G01Y227214D01*
X53602D01*
G03X53650Y227344I-152J130D01*
G01Y227608D01*
G03X53602Y227738I-200J0D01*
G01X53601Y227739D01*
G02Y229713I1131J987D01*
G01Y229714D01*
X53602D01*
G03X53650Y229844I-152J130D01*
G01Y230108D01*
G03X53602Y230238I-200J0D01*
G01X53601Y230239D01*
G02X53231Y231226I1131J987D01*
G37*
G36*
G01X155593D02*
G02X158597I1502J0D01*
G02X158227Y230239I-1501J0D01*
G01Y230238D01*
X158226D01*
G03X158178Y230108I152J-130D01*
G01Y229844D01*
G03X158226Y229714I200J0D01*
G01X158227Y229713D01*
G02Y227739I-1131J-987D01*
G01Y227738D01*
X158226D01*
G03X158178Y227608I152J-130D01*
G01Y227344D01*
G03X158226Y227214I200J0D01*
G01X158227Y227213D01*
G02Y225239I-1131J-987D01*
G01Y225238D01*
X158226D01*
G03X158178Y225108I152J-130D01*
G01Y224844D01*
G03X158226Y224714I200J0D01*
G01X158227Y224713D01*
G02X158597Y223726I-1131J-987D01*
G02X155593I-1502J0D01*
G02X155963Y224713I1501J0D01*
G01Y224714D01*
X155964D01*
G03X156012Y224844I-152J130D01*
G01Y225108D01*
G03X155964Y225238I-200J0D01*
G01X155963Y225239D01*
G02Y227213I1131J987D01*
G01Y227214D01*
X155964D01*
G03X156012Y227344I-152J130D01*
G01Y227608D01*
G03X155964Y227738I-200J0D01*
G01X155963Y227739D01*
G02Y229713I1131J987D01*
G01Y229714D01*
X155964D01*
G03X156012Y229844I-152J130D01*
G01Y230108D01*
G03X155964Y230238I-200J0D01*
G01X155963Y230239D01*
G02X155593Y231226I1131J987D01*
G37*
G36*
G01X257955D02*
G02X260959I1502J0D01*
G02X260589Y230239I-1501J0D01*
G01Y230238D01*
X260588D01*
G03X260540Y230108I152J-130D01*
G01Y229844D01*
G03X260588Y229714I200J0D01*
G01X260589Y229713D01*
G02Y227739I-1131J-987D01*
G01Y227738D01*
X260588D01*
G03X260540Y227608I152J-130D01*
G01Y227344D01*
G03X260588Y227214I200J0D01*
G01X260589Y227213D01*
G02Y225239I-1131J-987D01*
G01Y225238D01*
X260588D01*
G03X260540Y225108I152J-130D01*
G01Y224844D01*
G03X260588Y224714I200J0D01*
G01X260589Y224713D01*
G02X260959Y223726I-1131J-987D01*
G02X257955I-1502J0D01*
G02X258325Y224713I1501J0D01*
G01Y224714D01*
X258326D01*
G03X258374Y224844I-152J130D01*
G01Y225108D01*
G03X258326Y225238I-200J0D01*
G01X258325Y225239D01*
G02Y227213I1131J987D01*
G01Y227214D01*
X258326D01*
G03X258374Y227344I-152J130D01*
G01Y227608D01*
G03X258326Y227738I-200J0D01*
G01X258325Y227739D01*
G02Y229713I1131J987D01*
G01Y229714D01*
X258326D01*
G03X258374Y229844I-152J130D01*
G01Y230108D01*
G03X258326Y230238I-200J0D01*
G01X258325Y230239D01*
G02X257955Y231226I1131J987D01*
G37*
G36*
G01X360317D02*
G02X363321I1502J0D01*
G02X362951Y230239I-1501J0D01*
G01Y230238D01*
X362950D01*
G03X362902Y230108I152J-130D01*
G01Y229844D01*
G03X362950Y229714I200J0D01*
G01X362951Y229713D01*
G02Y227739I-1131J-987D01*
G01Y227738D01*
X362950D01*
G03X362902Y227608I152J-130D01*
G01Y227344D01*
G03X362950Y227214I200J0D01*
G01X362951Y227213D01*
G02Y225239I-1131J-987D01*
G01Y225238D01*
X362950D01*
G03X362902Y225108I152J-130D01*
G01Y224844D01*
G03X362950Y224714I200J0D01*
G01X362951Y224713D01*
G02X363321Y223726I-1131J-987D01*
G02X360317I-1502J0D01*
G02X360687Y224713I1501J0D01*
G01Y224714D01*
X360688D01*
G03X360736Y224844I-152J130D01*
G01Y225108D01*
G03X360688Y225238I-200J0D01*
G01X360687Y225239D01*
G02Y227213I1131J987D01*
G01Y227214D01*
X360688D01*
G03X360736Y227344I-152J130D01*
G01Y227608D01*
G03X360688Y227738I-200J0D01*
G01X360687Y227739D01*
G02Y229713I1131J987D01*
G01Y229714D01*
X360688D01*
G03X360736Y229844I-152J130D01*
G01Y230108D01*
G03X360688Y230238I-200J0D01*
G01X360687Y230239D01*
G02X360317Y231226I1131J987D01*
G37*
G36*
G01X510318D02*
G02X513322I1502J0D01*
G02X512952Y230239I-1501J0D01*
G01Y230238D01*
X512951D01*
G03X512903Y230108I152J-130D01*
G01Y229844D01*
G03X512951Y229714I200J0D01*
G01X512952Y229713D01*
G02Y227739I-1131J-987D01*
G01Y227738D01*
X512951D01*
G03X512903Y227608I152J-130D01*
G01Y227344D01*
G03X512951Y227214I200J0D01*
G01X512952Y227213D01*
G02Y225239I-1131J-987D01*
G01Y225238D01*
X512951D01*
G03X512903Y225108I152J-130D01*
G01Y224844D01*
G03X512951Y224714I200J0D01*
G01X512952Y224713D01*
G02X513322Y223726I-1131J-987D01*
G02X510318I-1502J0D01*
G02X510688Y224713I1501J0D01*
G01Y224714D01*
X510689D01*
G03X510737Y224844I-152J130D01*
G01Y225108D01*
G03X510689Y225238I-200J0D01*
G01X510688Y225239D01*
G02Y227213I1131J987D01*
G01Y227214D01*
X510689D01*
G03X510737Y227344I-152J130D01*
G01Y227608D01*
G03X510689Y227738I-200J0D01*
G01X510688Y227739D01*
G02Y229713I1131J987D01*
G01Y229714D01*
X510689D01*
G03X510737Y229844I-152J130D01*
G01Y230108D01*
G03X510689Y230238I-200J0D01*
G01X510688Y230239D01*
G02X510318Y231226I1131J987D01*
G37*
G36*
G01X612680D02*
G02X615684I1502J0D01*
G02X615314Y230239I-1501J0D01*
G01Y230238D01*
X615313D01*
G03X615265Y230108I152J-130D01*
G01Y229844D01*
G03X615313Y229714I200J0D01*
G01X615314Y229713D01*
G02Y227739I-1131J-987D01*
G01Y227738D01*
X615313D01*
G03X615265Y227608I152J-130D01*
G01Y227344D01*
G03X615313Y227214I200J0D01*
G01X615314Y227213D01*
G02Y225239I-1131J-987D01*
G01Y225238D01*
X615313D01*
G03X615265Y225108I152J-130D01*
G01Y224844D01*
G03X615313Y224714I200J0D01*
G01X615314Y224713D01*
G02X615684Y223726I-1131J-987D01*
G02X612680I-1502J0D01*
G02X613050Y224713I1501J0D01*
G01Y224714D01*
X613051D01*
G03X613099Y224844I-152J130D01*
G01Y225108D01*
G03X613051Y225238I-200J0D01*
G01X613050Y225239D01*
G02Y227213I1131J987D01*
G01Y227214D01*
X613051D01*
G03X613099Y227344I-152J130D01*
G01Y227608D01*
G03X613051Y227738I-200J0D01*
G01X613050Y227739D01*
G02Y229713I1131J987D01*
G01Y229714D01*
X613051D01*
G03X613099Y229844I-152J130D01*
G01Y230108D01*
G03X613051Y230238I-200J0D01*
G01X613050Y230239D01*
G02X612680Y231226I1131J987D01*
G37*
G36*
G01X715042D02*
G02X718046I1502J0D01*
G02X717676Y230239I-1501J0D01*
G01Y230238D01*
X717675D01*
G03X717627Y230108I152J-130D01*
G01Y229844D01*
G03X717675Y229714I200J0D01*
G01X717676Y229713D01*
G02Y227739I-1131J-987D01*
G01Y227738D01*
X717675D01*
G03X717627Y227608I152J-130D01*
G01Y227344D01*
G03X717675Y227214I200J0D01*
G01X717676Y227213D01*
G02Y225239I-1131J-987D01*
G01Y225238D01*
X717675D01*
G03X717627Y225108I152J-130D01*
G01Y224844D01*
G03X717675Y224714I200J0D01*
G01X717676Y224713D01*
G02X718046Y223726I-1131J-987D01*
G02X715042I-1502J0D01*
G02X715412Y224713I1501J0D01*
G01Y224714D01*
X715413D01*
G03X715461Y224844I-152J130D01*
G01Y225108D01*
G03X715413Y225238I-200J0D01*
G01X715412Y225239D01*
G02Y227213I1131J987D01*
G01Y227214D01*
X715413D01*
G03X715461Y227344I-152J130D01*
G01Y227608D01*
G03X715413Y227738I-200J0D01*
G01X715412Y227739D01*
G02Y229713I1131J987D01*
G01Y229714D01*
X715413D01*
G03X715461Y229844I-152J130D01*
G01Y230108D01*
G03X715413Y230238I-200J0D01*
G01X715412Y230239D01*
G02X715042Y231226I1131J987D01*
G37*
G36*
G01X817404D02*
G02X820408I1502J0D01*
G02X820038Y230239I-1501J0D01*
G01Y230238D01*
X820037D01*
G03X819989Y230108I152J-130D01*
G01Y229844D01*
G03X820037Y229714I200J0D01*
G01X820038Y229713D01*
G02Y227739I-1131J-987D01*
G01Y227738D01*
X820037D01*
G03X819989Y227608I152J-130D01*
G01Y227344D01*
G03X820037Y227214I200J0D01*
G01X820038Y227213D01*
G02Y225239I-1131J-987D01*
G01Y225238D01*
X820037D01*
G03X819989Y225108I152J-130D01*
G01Y224844D01*
G03X820037Y224714I200J0D01*
G01X820038Y224713D01*
G02X820408Y223726I-1131J-987D01*
G02X817404I-1502J0D01*
G02X817774Y224713I1501J0D01*
G01Y224714D01*
X817775D01*
G03X817823Y224844I-152J130D01*
G01Y225108D01*
G03X817775Y225238I-200J0D01*
G01X817774Y225239D01*
G02Y227213I1131J987D01*
G01Y227214D01*
X817775D01*
G03X817823Y227344I-152J130D01*
G01Y227608D01*
G03X817775Y227738I-200J0D01*
G01X817774Y227739D01*
G02Y229713I1131J987D01*
G01Y229714D01*
X817775D01*
G03X817823Y229844I-152J130D01*
G01Y230108D01*
G03X817775Y230238I-200J0D01*
G01X817774Y230239D01*
G02X817404Y231226I1131J987D01*
G37*
G36*
G01X967404D02*
G02X970408I1502J0D01*
G02X970038Y230239I-1501J0D01*
G01Y230238D01*
X970037D01*
G03X969989Y230108I152J-130D01*
G01Y229844D01*
G03X970037Y229714I200J0D01*
G01X970038Y229713D01*
G02Y227739I-1131J-987D01*
G01Y227738D01*
X970037D01*
G03X969989Y227608I152J-130D01*
G01Y227344D01*
G03X970037Y227214I200J0D01*
G01X970038Y227213D01*
G02Y225239I-1131J-987D01*
G01Y225238D01*
X970037D01*
G03X969989Y225108I152J-130D01*
G01Y224844D01*
G03X970037Y224714I200J0D01*
G01X970038Y224713D01*
G02X970408Y223726I-1131J-987D01*
G02X967404I-1502J0D01*
G02X967774Y224713I1501J0D01*
G01Y224714D01*
X967775D01*
G03X967823Y224844I-152J130D01*
G01Y225108D01*
G03X967775Y225238I-200J0D01*
G01X967774Y225239D01*
G02Y227213I1131J987D01*
G01Y227214D01*
X967775D01*
G03X967823Y227344I-152J130D01*
G01Y227608D01*
G03X967775Y227738I-200J0D01*
G01X967774Y227739D01*
G02Y229713I1131J987D01*
G01Y229714D01*
X967775D01*
G03X967823Y229844I-152J130D01*
G01Y230108D01*
G03X967775Y230238I-200J0D01*
G01X967774Y230239D01*
G02X967404Y231226I1131J987D01*
G37*
G36*
G01X1069766D02*
G02X1072770I1502J0D01*
G02X1072400Y230239I-1501J0D01*
G01Y230238D01*
X1072399D01*
G03X1072351Y230108I152J-130D01*
G01Y229844D01*
G03X1072399Y229714I200J0D01*
G01X1072400Y229713D01*
G02Y227739I-1131J-987D01*
G01Y227738D01*
X1072399D01*
G03X1072351Y227608I152J-130D01*
G01Y227344D01*
G03X1072399Y227214I200J0D01*
G01X1072400Y227213D01*
G02Y225239I-1131J-987D01*
G01Y225238D01*
X1072399D01*
G03X1072351Y225108I152J-130D01*
G01Y224844D01*
G03X1072399Y224714I200J0D01*
G01X1072400Y224713D01*
G02X1072770Y223726I-1131J-987D01*
G02X1069766I-1502J0D01*
G02X1070136Y224713I1501J0D01*
G01Y224714D01*
X1070137D01*
G03X1070185Y224844I-152J130D01*
G01Y225108D01*
G03X1070137Y225238I-200J0D01*
G01X1070136Y225239D01*
G02Y227213I1131J987D01*
G01Y227214D01*
X1070137D01*
G03X1070185Y227344I-152J130D01*
G01Y227608D01*
G03X1070137Y227738I-200J0D01*
G01X1070136Y227739D01*
G02Y229713I1131J987D01*
G01Y229714D01*
X1070137D01*
G03X1070185Y229844I-152J130D01*
G01Y230108D01*
G03X1070137Y230238I-200J0D01*
G01X1070136Y230239D01*
G02X1069766Y231226I1131J987D01*
G37*
G36*
G01X1172128D02*
G02X1175132I1502J0D01*
G02X1174762Y230239I-1501J0D01*
G01Y230238D01*
X1174761D01*
G03X1174713Y230108I152J-130D01*
G01Y229844D01*
G03X1174761Y229714I200J0D01*
G01X1174762Y229713D01*
G02Y227739I-1131J-987D01*
G01Y227738D01*
X1174761D01*
G03X1174713Y227608I152J-130D01*
G01Y227344D01*
G03X1174761Y227214I200J0D01*
G01X1174762Y227213D01*
G02Y225239I-1131J-987D01*
G01Y225238D01*
X1174761D01*
G03X1174713Y225108I152J-130D01*
G01Y224844D01*
G03X1174761Y224714I200J0D01*
G01X1174762Y224713D01*
G02X1175132Y223726I-1131J-987D01*
G02X1172128I-1502J0D01*
G02X1172498Y224713I1501J0D01*
G01Y224714D01*
X1172499D01*
G03X1172547Y224844I-152J130D01*
G01Y225108D01*
G03X1172499Y225238I-200J0D01*
G01X1172498Y225239D01*
G02Y227213I1131J987D01*
G01Y227214D01*
X1172499D01*
G03X1172547Y227344I-152J130D01*
G01Y227608D01*
G03X1172499Y227738I-200J0D01*
G01X1172498Y227739D01*
G02Y229713I1131J987D01*
G01Y229714D01*
X1172499D01*
G03X1172547Y229844I-152J130D01*
G01Y230108D01*
G03X1172499Y230238I-200J0D01*
G01X1172498Y230239D01*
G02X1172128Y231226I1131J987D01*
G37*
G36*
G01X1274490D02*
G02X1277494I1502J0D01*
G02X1277124Y230239I-1501J0D01*
G01Y230238D01*
X1277123D01*
G03X1277075Y230108I152J-130D01*
G01Y229844D01*
G03X1277123Y229714I200J0D01*
G01X1277124Y229713D01*
G02Y227739I-1131J-987D01*
G01Y227738D01*
X1277123D01*
G03X1277075Y227608I152J-130D01*
G01Y227344D01*
G03X1277123Y227214I200J0D01*
G01X1277124Y227213D01*
G02Y225239I-1131J-987D01*
G01Y225238D01*
X1277123D01*
G03X1277075Y225108I152J-130D01*
G01Y224844D01*
G03X1277123Y224714I200J0D01*
G01X1277124Y224713D01*
G02X1277494Y223726I-1131J-987D01*
G02X1274490I-1502J0D01*
G02X1274860Y224713I1501J0D01*
G01Y224714D01*
X1274861D01*
G03X1274909Y224844I-152J130D01*
G01Y225108D01*
G03X1274861Y225238I-200J0D01*
G01X1274860Y225239D01*
G02Y227213I1131J987D01*
G01Y227214D01*
X1274861D01*
G03X1274909Y227344I-152J130D01*
G01Y227608D01*
G03X1274861Y227738I-200J0D01*
G01X1274860Y227739D01*
G02Y229713I1131J987D01*
G01Y229714D01*
X1274861D01*
G03X1274909Y229844I-152J130D01*
G01Y230108D01*
G03X1274861Y230238I-200J0D01*
G01X1274860Y230239D01*
G02X1274490Y231226I1131J987D01*
G37*
G36*
G01X1424491D02*
G02X1427495I1502J0D01*
G02X1427125Y230239I-1501J0D01*
G01Y230238D01*
X1427124D01*
G03X1427076Y230108I152J-130D01*
G01Y229844D01*
G03X1427124Y229714I200J0D01*
G01X1427125Y229713D01*
G02Y227739I-1131J-987D01*
G01Y227738D01*
X1427124D01*
G03X1427076Y227608I152J-130D01*
G01Y227344D01*
G03X1427124Y227214I200J0D01*
G01X1427125Y227213D01*
G02Y225239I-1131J-987D01*
G01Y225238D01*
X1427124D01*
G03X1427076Y225108I152J-130D01*
G01Y224844D01*
G03X1427124Y224714I200J0D01*
G01X1427125Y224713D01*
G02X1427495Y223726I-1131J-987D01*
G02X1424491I-1502J0D01*
G02X1424861Y224713I1501J0D01*
G01Y224714D01*
X1424862D01*
G03X1424910Y224844I-152J130D01*
G01Y225108D01*
G03X1424862Y225238I-200J0D01*
G01X1424861Y225239D01*
G02Y227213I1131J987D01*
G01Y227214D01*
X1424862D01*
G03X1424910Y227344I-152J130D01*
G01Y227608D01*
G03X1424862Y227738I-200J0D01*
G01X1424861Y227739D01*
G02Y229713I1131J987D01*
G01Y229714D01*
X1424862D01*
G03X1424910Y229844I-152J130D01*
G01Y230108D01*
G03X1424862Y230238I-200J0D01*
G01X1424861Y230239D01*
G02X1424491Y231226I1131J987D01*
G37*
G36*
G01X1526853D02*
G02X1529857I1502J0D01*
G02X1529487Y230239I-1501J0D01*
G01Y230238D01*
X1529486D01*
G03X1529438Y230108I152J-130D01*
G01Y229844D01*
G03X1529486Y229714I200J0D01*
G01X1529487Y229713D01*
G02Y227739I-1131J-987D01*
G01Y227738D01*
X1529486D01*
G03X1529438Y227608I152J-130D01*
G01Y227344D01*
G03X1529486Y227214I200J0D01*
G01X1529487Y227213D01*
G02Y225239I-1131J-987D01*
G01Y225238D01*
X1529486D01*
G03X1529438Y225108I152J-130D01*
G01Y224844D01*
G03X1529486Y224714I200J0D01*
G01X1529487Y224713D01*
G02X1529857Y223726I-1131J-987D01*
G02X1526853I-1502J0D01*
G02X1527223Y224713I1501J0D01*
G01Y224714D01*
X1527224D01*
G03X1527272Y224844I-152J130D01*
G01Y225108D01*
G03X1527224Y225238I-200J0D01*
G01X1527223Y225239D01*
G02Y227213I1131J987D01*
G01Y227214D01*
X1527224D01*
G03X1527272Y227344I-152J130D01*
G01Y227608D01*
G03X1527224Y227738I-200J0D01*
G01X1527223Y227739D01*
G02Y229713I1131J987D01*
G01Y229714D01*
X1527224D01*
G03X1527272Y229844I-152J130D01*
G01Y230108D01*
G03X1527224Y230238I-200J0D01*
G01X1527223Y230239D01*
G02X1526853Y231226I1131J987D01*
G37*
G36*
G01X1629215D02*
G02X1632219I1502J0D01*
G02X1631849Y230239I-1501J0D01*
G01Y230238D01*
X1631848D01*
G03X1631800Y230108I152J-130D01*
G01Y229844D01*
G03X1631848Y229714I200J0D01*
G01X1631849Y229713D01*
G02Y227739I-1131J-987D01*
G01Y227738D01*
X1631848D01*
G03X1631800Y227608I152J-130D01*
G01Y227344D01*
G03X1631848Y227214I200J0D01*
G01X1631849Y227213D01*
G02Y225239I-1131J-987D01*
G01Y225238D01*
X1631848D01*
G03X1631800Y225108I152J-130D01*
G01Y224844D01*
G03X1631848Y224714I200J0D01*
G01X1631849Y224713D01*
G02X1632219Y223726I-1131J-987D01*
G02X1629215I-1502J0D01*
G02X1629585Y224713I1501J0D01*
G01Y224714D01*
X1629586D01*
G03X1629634Y224844I-152J130D01*
G01Y225108D01*
G03X1629586Y225238I-200J0D01*
G01X1629585Y225239D01*
G02Y227213I1131J987D01*
G01Y227214D01*
X1629586D01*
G03X1629634Y227344I-152J130D01*
G01Y227608D01*
G03X1629586Y227738I-200J0D01*
G01X1629585Y227739D01*
G02Y229713I1131J987D01*
G01Y229714D01*
X1629586D01*
G03X1629634Y229844I-152J130D01*
G01Y230108D01*
G03X1629586Y230238I-200J0D01*
G01X1629585Y230239D01*
G02X1629215Y231226I1131J987D01*
G37*
G36*
G01X1731577D02*
G02X1734581I1502J0D01*
G02X1734211Y230239I-1501J0D01*
G01Y230238D01*
X1734210D01*
G03X1734162Y230108I152J-130D01*
G01Y229844D01*
G03X1734210Y229714I200J0D01*
G01X1734211Y229713D01*
G02Y227739I-1131J-987D01*
G01Y227738D01*
X1734210D01*
G03X1734162Y227608I152J-130D01*
G01Y227344D01*
G03X1734210Y227214I200J0D01*
G01X1734211Y227213D01*
G02Y225239I-1131J-987D01*
G01Y225238D01*
X1734210D01*
G03X1734162Y225108I152J-130D01*
G01Y224844D01*
G03X1734210Y224714I200J0D01*
G01X1734211Y224713D01*
G02X1734581Y223726I-1131J-987D01*
G02X1731577I-1502J0D01*
G02X1731947Y224713I1501J0D01*
G01Y224714D01*
X1731948D01*
G03X1731996Y224844I-152J130D01*
G01Y225108D01*
G03X1731948Y225238I-200J0D01*
G01X1731947Y225239D01*
G02Y227213I1131J987D01*
G01Y227214D01*
X1731948D01*
G03X1731996Y227344I-152J130D01*
G01Y227608D01*
G03X1731948Y227738I-200J0D01*
G01X1731947Y227739D01*
G02Y229713I1131J987D01*
G01Y229714D01*
X1731948D01*
G03X1731996Y229844I-152J130D01*
G01Y230108D01*
G03X1731948Y230238I-200J0D01*
G01X1731947Y230239D01*
G02X1731577Y231226I1131J987D01*
G37*
G36*
G01X86296Y231021D02*
G02X89900I1802J0D01*
G01Y231020D01*
G02X89319Y229695I-1802J0D01*
G01X89291Y229669D01*
X89258Y229602D01*
X89233Y229293D01*
G03X89276Y229153I199J-15D01*
G02X89600Y228221I-1178J-932D01*
G02X86596I-1502J0D01*
G02X86920Y229153I1502J0D01*
G03X86963Y229293I-156J125D01*
G01X86938Y229602D01*
X86905Y229669D01*
X86877Y229695D01*
G02X86296Y231020I1221J1325D01*
G01Y231021D01*
G37*
G36*
G01X645745D02*
G02X649349I1802J0D01*
G01Y231020D01*
G02X648768Y229695I-1802J0D01*
G01X648740Y229669D01*
X648707Y229602D01*
X648682Y229293D01*
G03X648725Y229153I199J-15D01*
G02X649049Y228221I-1178J-932D01*
G02X646045I-1502J0D01*
G02X646369Y229153I1502J0D01*
G03X646412Y229293I-156J125D01*
G01X646387Y229602D01*
X646354Y229669D01*
X646326Y229695D01*
G02X645745Y231020I1221J1325D01*
G01Y231021D01*
G37*
G36*
G01X850469D02*
G02X854073I1802J0D01*
G01Y231020D01*
G02X853492Y229695I-1802J0D01*
G01X853464Y229669D01*
X853431Y229602D01*
X853406Y229293D01*
G03X853449Y229153I199J-15D01*
G02X853773Y228221I-1178J-932D01*
G02X850769I-1502J0D01*
G02X851093Y229153I1502J0D01*
G03X851136Y229293I-156J125D01*
G01X851111Y229602D01*
X851078Y229669D01*
X851050Y229695D01*
G02X850469Y231020I1221J1325D01*
G01Y231021D01*
G37*
G36*
G01X1307555D02*
G02X1311159I1802J0D01*
G01Y231020D01*
G02X1310578Y229695I-1802J0D01*
G01X1310550Y229669D01*
X1310517Y229602D01*
X1310492Y229293D01*
G03X1310535Y229153I199J-15D01*
G02X1310859Y228221I-1178J-932D01*
G02X1307855I-1502J0D01*
G02X1308179Y229153I1502J0D01*
G03X1308222Y229293I-156J125D01*
G01X1308197Y229602D01*
X1308164Y229669D01*
X1308136Y229695D01*
G02X1307555Y231020I1221J1325D01*
G01Y231021D01*
G37*
G36*
G01X1662280D02*
G02X1665884I1802J0D01*
G01Y231020D01*
G02X1665303Y229695I-1802J0D01*
G01X1665275Y229669D01*
X1665242Y229602D01*
X1665217Y229293D01*
G03X1665260Y229153I199J-15D01*
G02X1665584Y228221I-1178J-932D01*
G02X1662580I-1502J0D01*
G02X1662904Y229153I1502J0D01*
G03X1662947Y229293I-156J125D01*
G01X1662922Y229602D01*
X1662889Y229669D01*
X1662861Y229695D01*
G02X1662280Y231020I1221J1325D01*
G01Y231021D01*
G37*
G36*
G01X63687Y231461D02*
G02X66691I1502J0D01*
G02X66321Y230474I-1501J0D01*
G01Y230473D01*
X66320D01*
G03X66272Y230343I152J-130D01*
G01Y230079D01*
G03X66320Y229949I200J0D01*
G01X66321Y229948D01*
G02Y227974I-1131J-987D01*
G01Y227973D01*
X66320D01*
G03X66272Y227843I152J-130D01*
G01Y227579D01*
G03X66320Y227449I200J0D01*
G01X66321Y227448D01*
G02X66691Y226461I-1131J-987D01*
G02X66367Y225529I-1502J0D01*
G03X66324Y225389I156J-125D01*
G01X66349Y225080D01*
X66382Y225013D01*
X66410Y224987D01*
G02X66991Y223662I-1221J-1325D01*
G01Y223661D01*
G02X63387I-1802J0D01*
G01Y223662D01*
G02X63968Y224987I1802J0D01*
G01X63996Y225013D01*
X64029Y225080D01*
X64054Y225389D01*
G03X64011Y225529I-199J15D01*
G02X63687Y226461I1178J932D01*
G02X64057Y227448I1501J0D01*
G01Y227449D01*
X64058D01*
G03X64106Y227579I-152J130D01*
G01Y227843D01*
G03X64058Y227973I-200J0D01*
G01X64057Y227974D01*
G02Y229948I1131J987D01*
G01Y229949D01*
X64058D01*
G03X64106Y230079I-152J130D01*
G01Y230343D01*
G03X64058Y230473I-200J0D01*
G01X64057Y230474D01*
G02X63687Y231461I1131J987D01*
G37*
G36*
G01X166049D02*
G02X169053I1502J0D01*
G02X168683Y230474I-1501J0D01*
G01Y230473D01*
X168682D01*
G03X168634Y230343I152J-130D01*
G01Y230079D01*
G03X168682Y229949I200J0D01*
G01X168683Y229948D01*
G02Y227974I-1131J-987D01*
G01Y227973D01*
X168682D01*
G03X168634Y227843I152J-130D01*
G01Y227579D01*
G03X168682Y227449I200J0D01*
G01X168683Y227448D01*
G02X169053Y226461I-1131J-987D01*
G02X168729Y225529I-1502J0D01*
G03X168686Y225389I156J-125D01*
G01X168711Y225080D01*
X168744Y225013D01*
X168772Y224987D01*
G02X169353Y223662I-1221J-1325D01*
G01Y223661D01*
G02X165749I-1802J0D01*
G01Y223662D01*
G02X166330Y224987I1802J0D01*
G01X166358Y225013D01*
X166391Y225080D01*
X166416Y225389D01*
G03X166373Y225529I-199J15D01*
G02X166049Y226461I1178J932D01*
G02X166419Y227448I1501J0D01*
G01Y227449D01*
X166420D01*
G03X166468Y227579I-152J130D01*
G01Y227843D01*
G03X166420Y227973I-200J0D01*
G01X166419Y227974D01*
G02Y229948I1131J987D01*
G01Y229949D01*
X166420D01*
G03X166468Y230079I-152J130D01*
G01Y230343D01*
G03X166420Y230473I-200J0D01*
G01X166419Y230474D01*
G02X166049Y231461I1131J987D01*
G37*
G36*
G01X268411D02*
G02X271415I1502J0D01*
G02X271045Y230474I-1501J0D01*
G01Y230473D01*
X271044D01*
G03X270996Y230343I152J-130D01*
G01Y230079D01*
G03X271044Y229949I200J0D01*
G01X271045Y229948D01*
G02Y227974I-1131J-987D01*
G01Y227973D01*
X271044D01*
G03X270996Y227843I152J-130D01*
G01Y227579D01*
G03X271044Y227449I200J0D01*
G01X271045Y227448D01*
G02X271415Y226461I-1131J-987D01*
G02X271091Y225529I-1502J0D01*
G03X271048Y225389I156J-125D01*
G01X271073Y225080D01*
X271106Y225013D01*
X271134Y224987D01*
G02X271715Y223662I-1221J-1325D01*
G01Y223661D01*
G02X268111I-1802J0D01*
G01Y223662D01*
G02X268692Y224987I1802J0D01*
G01X268720Y225013D01*
X268753Y225080D01*
X268778Y225389D01*
G03X268735Y225529I-199J15D01*
G02X268411Y226461I1178J932D01*
G02X268781Y227448I1501J0D01*
G01Y227449D01*
X268782D01*
G03X268830Y227579I-152J130D01*
G01Y227843D01*
G03X268782Y227973I-200J0D01*
G01X268781Y227974D01*
G02Y229948I1131J987D01*
G01Y229949D01*
X268782D01*
G03X268830Y230079I-152J130D01*
G01Y230343D01*
G03X268782Y230473I-200J0D01*
G01X268781Y230474D01*
G02X268411Y231461I1131J987D01*
G37*
G36*
G01X370773D02*
G02X373777I1502J0D01*
G02X373407Y230474I-1501J0D01*
G01Y230473D01*
X373406D01*
G03X373358Y230343I152J-130D01*
G01Y230079D01*
G03X373406Y229949I200J0D01*
G01X373407Y229948D01*
G02Y227974I-1131J-987D01*
G01Y227973D01*
X373406D01*
G03X373358Y227843I152J-130D01*
G01Y227579D01*
G03X373406Y227449I200J0D01*
G01X373407Y227448D01*
G02X373777Y226461I-1131J-987D01*
G02X373453Y225529I-1502J0D01*
G03X373410Y225389I156J-125D01*
G01X373435Y225080D01*
X373468Y225013D01*
X373496Y224987D01*
G02X374077Y223662I-1221J-1325D01*
G01Y223661D01*
G02X370473I-1802J0D01*
G01Y223662D01*
G02X371054Y224987I1802J0D01*
G01X371082Y225013D01*
X371115Y225080D01*
X371140Y225389D01*
G03X371097Y225529I-199J15D01*
G02X370773Y226461I1178J932D01*
G02X371143Y227448I1501J0D01*
G01Y227449D01*
X371144D01*
G03X371192Y227579I-152J130D01*
G01Y227843D01*
G03X371144Y227973I-200J0D01*
G01X371143Y227974D01*
G02Y229948I1131J987D01*
G01Y229949D01*
X371144D01*
G03X371192Y230079I-152J130D01*
G01Y230343D01*
G03X371144Y230473I-200J0D01*
G01X371143Y230474D01*
G02X370773Y231461I1131J987D01*
G37*
G36*
G01X520774D02*
G02X523778I1502J0D01*
G02X523408Y230474I-1501J0D01*
G01Y230473D01*
X523407D01*
G03X523359Y230343I152J-130D01*
G01Y230079D01*
G03X523407Y229949I200J0D01*
G01X523408Y229948D01*
G02Y227974I-1131J-987D01*
G01Y227973D01*
X523407D01*
G03X523359Y227843I152J-130D01*
G01Y227579D01*
G03X523407Y227449I200J0D01*
G01X523408Y227448D01*
G02X523778Y226461I-1131J-987D01*
G02X523454Y225529I-1502J0D01*
G03X523411Y225389I156J-125D01*
G01X523436Y225080D01*
X523469Y225013D01*
X523497Y224987D01*
G02X524078Y223662I-1221J-1325D01*
G01Y223661D01*
G02X520474I-1802J0D01*
G01Y223662D01*
G02X521055Y224987I1802J0D01*
G01X521083Y225013D01*
X521116Y225080D01*
X521141Y225389D01*
G03X521098Y225529I-199J15D01*
G02X520774Y226461I1178J932D01*
G02X521144Y227448I1501J0D01*
G01Y227449D01*
X521145D01*
G03X521193Y227579I-152J130D01*
G01Y227843D01*
G03X521145Y227973I-200J0D01*
G01X521144Y227974D01*
G02Y229948I1131J987D01*
G01Y229949D01*
X521145D01*
G03X521193Y230079I-152J130D01*
G01Y230343D01*
G03X521145Y230473I-200J0D01*
G01X521144Y230474D01*
G02X520774Y231461I1131J987D01*
G37*
G36*
G01X623136D02*
G02X626140I1502J0D01*
G02X625770Y230474I-1501J0D01*
G01Y230473D01*
X625769D01*
G03X625721Y230343I152J-130D01*
G01Y230079D01*
G03X625769Y229949I200J0D01*
G01X625770Y229948D01*
G02Y227974I-1131J-987D01*
G01Y227973D01*
X625769D01*
G03X625721Y227843I152J-130D01*
G01Y227579D01*
G03X625769Y227449I200J0D01*
G01X625770Y227448D01*
G02X626140Y226461I-1131J-987D01*
G02X625816Y225529I-1502J0D01*
G03X625773Y225389I156J-125D01*
G01X625798Y225080D01*
X625831Y225013D01*
X625859Y224987D01*
G02X626440Y223662I-1221J-1325D01*
G01Y223661D01*
G02X622836I-1802J0D01*
G01Y223662D01*
G02X623417Y224987I1802J0D01*
G01X623445Y225013D01*
X623478Y225080D01*
X623503Y225389D01*
G03X623460Y225529I-199J15D01*
G02X623136Y226461I1178J932D01*
G02X623506Y227448I1501J0D01*
G01Y227449D01*
X623507D01*
G03X623555Y227579I-152J130D01*
G01Y227843D01*
G03X623507Y227973I-200J0D01*
G01X623506Y227974D01*
G02Y229948I1131J987D01*
G01Y229949D01*
X623507D01*
G03X623555Y230079I-152J130D01*
G01Y230343D01*
G03X623507Y230473I-200J0D01*
G01X623506Y230474D01*
G02X623136Y231461I1131J987D01*
G37*
G36*
G01X725498D02*
G02X728502I1502J0D01*
G02X728132Y230474I-1501J0D01*
G01Y230473D01*
X728131D01*
G03X728083Y230343I152J-130D01*
G01Y230079D01*
G03X728131Y229949I200J0D01*
G01X728132Y229948D01*
G02Y227974I-1131J-987D01*
G01Y227973D01*
X728131D01*
G03X728083Y227843I152J-130D01*
G01Y227579D01*
G03X728131Y227449I200J0D01*
G01X728132Y227448D01*
G02X728502Y226461I-1131J-987D01*
G02X728178Y225529I-1502J0D01*
G03X728135Y225389I156J-125D01*
G01X728160Y225080D01*
X728193Y225013D01*
X728221Y224987D01*
G02X728802Y223662I-1221J-1325D01*
G01Y223661D01*
G02X725198I-1802J0D01*
G01Y223662D01*
G02X725779Y224987I1802J0D01*
G01X725807Y225013D01*
X725840Y225080D01*
X725865Y225389D01*
G03X725822Y225529I-199J15D01*
G02X725498Y226461I1178J932D01*
G02X725868Y227448I1501J0D01*
G01Y227449D01*
X725869D01*
G03X725917Y227579I-152J130D01*
G01Y227843D01*
G03X725869Y227973I-200J0D01*
G01X725868Y227974D01*
G02Y229948I1131J987D01*
G01Y229949D01*
X725869D01*
G03X725917Y230079I-152J130D01*
G01Y230343D01*
G03X725869Y230473I-200J0D01*
G01X725868Y230474D01*
G02X725498Y231461I1131J987D01*
G37*
G36*
G01X827860D02*
G02X830864I1502J0D01*
G02X830494Y230474I-1501J0D01*
G01Y230473D01*
X830493D01*
G03X830445Y230343I152J-130D01*
G01Y230079D01*
G03X830493Y229949I200J0D01*
G01X830494Y229948D01*
G02Y227974I-1131J-987D01*
G01Y227973D01*
X830493D01*
G03X830445Y227843I152J-130D01*
G01Y227579D01*
G03X830493Y227449I200J0D01*
G01X830494Y227448D01*
G02X830864Y226461I-1131J-987D01*
G02X830540Y225529I-1502J0D01*
G03X830497Y225389I156J-125D01*
G01X830522Y225080D01*
X830555Y225013D01*
X830583Y224987D01*
G02X831164Y223662I-1221J-1325D01*
G01Y223661D01*
G02X827560I-1802J0D01*
G01Y223662D01*
G02X828141Y224987I1802J0D01*
G01X828169Y225013D01*
X828202Y225080D01*
X828227Y225389D01*
G03X828184Y225529I-199J15D01*
G02X827860Y226461I1178J932D01*
G02X828230Y227448I1501J0D01*
G01Y227449D01*
X828231D01*
G03X828279Y227579I-152J130D01*
G01Y227843D01*
G03X828231Y227973I-200J0D01*
G01X828230Y227974D01*
G02Y229948I1131J987D01*
G01Y229949D01*
X828231D01*
G03X828279Y230079I-152J130D01*
G01Y230343D01*
G03X828231Y230473I-200J0D01*
G01X828230Y230474D01*
G02X827860Y231461I1131J987D01*
G37*
G36*
G01X977860D02*
G02X980864I1502J0D01*
G02X980494Y230474I-1501J0D01*
G01Y230473D01*
X980493D01*
G03X980445Y230343I152J-130D01*
G01Y230079D01*
G03X980493Y229949I200J0D01*
G01X980494Y229948D01*
G02Y227974I-1131J-987D01*
G01Y227973D01*
X980493D01*
G03X980445Y227843I152J-130D01*
G01Y227579D01*
G03X980493Y227449I200J0D01*
G01X980494Y227448D01*
G02X980864Y226461I-1131J-987D01*
G02X980540Y225529I-1502J0D01*
G03X980497Y225389I156J-125D01*
G01X980522Y225080D01*
X980555Y225013D01*
X980583Y224987D01*
G02X981164Y223662I-1221J-1325D01*
G01Y223661D01*
G02X977560I-1802J0D01*
G01Y223662D01*
G02X978141Y224987I1802J0D01*
G01X978169Y225013D01*
X978202Y225080D01*
X978227Y225389D01*
G03X978184Y225529I-199J15D01*
G02X977860Y226461I1178J932D01*
G02X978230Y227448I1501J0D01*
G01Y227449D01*
X978231D01*
G03X978279Y227579I-152J130D01*
G01Y227843D01*
G03X978231Y227973I-200J0D01*
G01X978230Y227974D01*
G02Y229948I1131J987D01*
G01Y229949D01*
X978231D01*
G03X978279Y230079I-152J130D01*
G01Y230343D01*
G03X978231Y230473I-200J0D01*
G01X978230Y230474D01*
G02X977860Y231461I1131J987D01*
G37*
G36*
G01X1080222D02*
G02X1083226I1502J0D01*
G02X1082856Y230474I-1501J0D01*
G01Y230473D01*
X1082855D01*
G03X1082807Y230343I152J-130D01*
G01Y230079D01*
G03X1082855Y229949I200J0D01*
G01X1082856Y229948D01*
G02Y227974I-1131J-987D01*
G01Y227973D01*
X1082855D01*
G03X1082807Y227843I152J-130D01*
G01Y227579D01*
G03X1082855Y227449I200J0D01*
G01X1082856Y227448D01*
G02X1083226Y226461I-1131J-987D01*
G02X1082902Y225529I-1502J0D01*
G03X1082859Y225389I156J-125D01*
G01X1082884Y225080D01*
X1082917Y225013D01*
X1082945Y224987D01*
G02X1083526Y223662I-1221J-1325D01*
G01Y223661D01*
G02X1079922I-1802J0D01*
G01Y223662D01*
G02X1080503Y224987I1802J0D01*
G01X1080531Y225013D01*
X1080564Y225080D01*
X1080589Y225389D01*
G03X1080546Y225529I-199J15D01*
G02X1080222Y226461I1178J932D01*
G02X1080592Y227448I1501J0D01*
G01Y227449D01*
X1080593D01*
G03X1080641Y227579I-152J130D01*
G01Y227843D01*
G03X1080593Y227973I-200J0D01*
G01X1080592Y227974D01*
G02Y229948I1131J987D01*
G01Y229949D01*
X1080593D01*
G03X1080641Y230079I-152J130D01*
G01Y230343D01*
G03X1080593Y230473I-200J0D01*
G01X1080592Y230474D01*
G02X1080222Y231461I1131J987D01*
G37*
G36*
G01X1182584D02*
G02X1185588I1502J0D01*
G02X1185218Y230474I-1501J0D01*
G01Y230473D01*
X1185217D01*
G03X1185169Y230343I152J-130D01*
G01Y230079D01*
G03X1185217Y229949I200J0D01*
G01X1185218Y229948D01*
G02Y227974I-1131J-987D01*
G01Y227973D01*
X1185217D01*
G03X1185169Y227843I152J-130D01*
G01Y227579D01*
G03X1185217Y227449I200J0D01*
G01X1185218Y227448D01*
G02X1185588Y226461I-1131J-987D01*
G02X1185264Y225529I-1502J0D01*
G03X1185221Y225389I156J-125D01*
G01X1185246Y225080D01*
X1185279Y225013D01*
X1185307Y224987D01*
G02X1185888Y223662I-1221J-1325D01*
G01Y223661D01*
G02X1182284I-1802J0D01*
G01Y223662D01*
G02X1182865Y224987I1802J0D01*
G01X1182893Y225013D01*
X1182926Y225080D01*
X1182951Y225389D01*
G03X1182908Y225529I-199J15D01*
G02X1182584Y226461I1178J932D01*
G02X1182954Y227448I1501J0D01*
G01Y227449D01*
X1182955D01*
G03X1183003Y227579I-152J130D01*
G01Y227843D01*
G03X1182955Y227973I-200J0D01*
G01X1182954Y227974D01*
G02Y229948I1131J987D01*
G01Y229949D01*
X1182955D01*
G03X1183003Y230079I-152J130D01*
G01Y230343D01*
G03X1182955Y230473I-200J0D01*
G01X1182954Y230474D01*
G02X1182584Y231461I1131J987D01*
G37*
G36*
G01X1284946D02*
G02X1287950I1502J0D01*
G02X1287580Y230474I-1501J0D01*
G01Y230473D01*
X1287579D01*
G03X1287531Y230343I152J-130D01*
G01Y230079D01*
G03X1287579Y229949I200J0D01*
G01X1287580Y229948D01*
G02Y227974I-1131J-987D01*
G01Y227973D01*
X1287579D01*
G03X1287531Y227843I152J-130D01*
G01Y227579D01*
G03X1287579Y227449I200J0D01*
G01X1287580Y227448D01*
G02X1287950Y226461I-1131J-987D01*
G02X1287626Y225529I-1502J0D01*
G03X1287583Y225389I156J-125D01*
G01X1287608Y225080D01*
X1287641Y225013D01*
X1287669Y224987D01*
G02X1288250Y223662I-1221J-1325D01*
G01Y223661D01*
G02X1284646I-1802J0D01*
G01Y223662D01*
G02X1285227Y224987I1802J0D01*
G01X1285255Y225013D01*
X1285288Y225080D01*
X1285313Y225389D01*
G03X1285270Y225529I-199J15D01*
G02X1284946Y226461I1178J932D01*
G02X1285316Y227448I1501J0D01*
G01Y227449D01*
X1285317D01*
G03X1285365Y227579I-152J130D01*
G01Y227843D01*
G03X1285317Y227973I-200J0D01*
G01X1285316Y227974D01*
G02Y229948I1131J987D01*
G01Y229949D01*
X1285317D01*
G03X1285365Y230079I-152J130D01*
G01Y230343D01*
G03X1285317Y230473I-200J0D01*
G01X1285316Y230474D01*
G02X1284946Y231461I1131J987D01*
G37*
G36*
G01X1434947D02*
G02X1437951I1502J0D01*
G02X1437581Y230474I-1501J0D01*
G01Y230473D01*
X1437580D01*
G03X1437532Y230343I152J-130D01*
G01Y230079D01*
G03X1437580Y229949I200J0D01*
G01X1437581Y229948D01*
G02Y227974I-1131J-987D01*
G01Y227973D01*
X1437580D01*
G03X1437532Y227843I152J-130D01*
G01Y227579D01*
G03X1437580Y227449I200J0D01*
G01X1437581Y227448D01*
G02X1437951Y226461I-1131J-987D01*
G02X1437627Y225529I-1502J0D01*
G03X1437584Y225389I156J-125D01*
G01X1437609Y225080D01*
X1437642Y225013D01*
X1437670Y224987D01*
G02X1438251Y223662I-1221J-1325D01*
G01Y223661D01*
G02X1434647I-1802J0D01*
G01Y223662D01*
G02X1435228Y224987I1802J0D01*
G01X1435256Y225013D01*
X1435289Y225080D01*
X1435314Y225389D01*
G03X1435271Y225529I-199J15D01*
G02X1434947Y226461I1178J932D01*
G02X1435317Y227448I1501J0D01*
G01Y227449D01*
X1435318D01*
G03X1435366Y227579I-152J130D01*
G01Y227843D01*
G03X1435318Y227973I-200J0D01*
G01X1435317Y227974D01*
G02Y229948I1131J987D01*
G01Y229949D01*
X1435318D01*
G03X1435366Y230079I-152J130D01*
G01Y230343D01*
G03X1435318Y230473I-200J0D01*
G01X1435317Y230474D01*
G02X1434947Y231461I1131J987D01*
G37*
G36*
G01X1537309D02*
G02X1540313I1502J0D01*
G02X1539943Y230474I-1501J0D01*
G01Y230473D01*
X1539942D01*
G03X1539894Y230343I152J-130D01*
G01Y230079D01*
G03X1539942Y229949I200J0D01*
G01X1539943Y229948D01*
G02Y227974I-1131J-987D01*
G01Y227973D01*
X1539942D01*
G03X1539894Y227843I152J-130D01*
G01Y227579D01*
G03X1539942Y227449I200J0D01*
G01X1539943Y227448D01*
G02X1540313Y226461I-1131J-987D01*
G02X1539989Y225529I-1502J0D01*
G03X1539946Y225389I156J-125D01*
G01X1539971Y225080D01*
X1540004Y225013D01*
X1540032Y224987D01*
G02X1540613Y223662I-1221J-1325D01*
G01Y223661D01*
G02X1537009I-1802J0D01*
G01Y223662D01*
G02X1537590Y224987I1802J0D01*
G01X1537618Y225013D01*
X1537651Y225080D01*
X1537676Y225389D01*
G03X1537633Y225529I-199J15D01*
G02X1537309Y226461I1178J932D01*
G02X1537679Y227448I1501J0D01*
G01Y227449D01*
X1537680D01*
G03X1537728Y227579I-152J130D01*
G01Y227843D01*
G03X1537680Y227973I-200J0D01*
G01X1537679Y227974D01*
G02Y229948I1131J987D01*
G01Y229949D01*
X1537680D01*
G03X1537728Y230079I-152J130D01*
G01Y230343D01*
G03X1537680Y230473I-200J0D01*
G01X1537679Y230474D01*
G02X1537309Y231461I1131J987D01*
G37*
G36*
G01X1639671D02*
G02X1642675I1502J0D01*
G02X1642305Y230474I-1501J0D01*
G01Y230473D01*
X1642304D01*
G03X1642256Y230343I152J-130D01*
G01Y230079D01*
G03X1642304Y229949I200J0D01*
G01X1642305Y229948D01*
G02Y227974I-1131J-987D01*
G01Y227973D01*
X1642304D01*
G03X1642256Y227843I152J-130D01*
G01Y227579D01*
G03X1642304Y227449I200J0D01*
G01X1642305Y227448D01*
G02X1642675Y226461I-1131J-987D01*
G02X1642351Y225529I-1502J0D01*
G03X1642308Y225389I156J-125D01*
G01X1642333Y225080D01*
X1642366Y225013D01*
X1642394Y224987D01*
G02X1642975Y223662I-1221J-1325D01*
G01Y223661D01*
G02X1639371I-1802J0D01*
G01Y223662D01*
G02X1639952Y224987I1802J0D01*
G01X1639980Y225013D01*
X1640013Y225080D01*
X1640038Y225389D01*
G03X1639995Y225529I-199J15D01*
G02X1639671Y226461I1178J932D01*
G02X1640041Y227448I1501J0D01*
G01Y227449D01*
X1640042D01*
G03X1640090Y227579I-152J130D01*
G01Y227843D01*
G03X1640042Y227973I-200J0D01*
G01X1640041Y227974D01*
G02Y229948I1131J987D01*
G01Y229949D01*
X1640042D01*
G03X1640090Y230079I-152J130D01*
G01Y230343D01*
G03X1640042Y230473I-200J0D01*
G01X1640041Y230474D01*
G02X1639671Y231461I1131J987D01*
G37*
G36*
G01X1742033D02*
G02X1745037I1502J0D01*
G02X1744667Y230474I-1501J0D01*
G01Y230473D01*
X1744666D01*
G03X1744618Y230343I152J-130D01*
G01Y230079D01*
G03X1744666Y229949I200J0D01*
G01X1744667Y229948D01*
G02Y227974I-1131J-987D01*
G01Y227973D01*
X1744666D01*
G03X1744618Y227843I152J-130D01*
G01Y227579D01*
G03X1744666Y227449I200J0D01*
G01X1744667Y227448D01*
G02X1745037Y226461I-1131J-987D01*
G02X1744713Y225529I-1502J0D01*
G03X1744670Y225389I156J-125D01*
G01X1744695Y225080D01*
X1744728Y225013D01*
X1744756Y224987D01*
G02X1745337Y223662I-1221J-1325D01*
G01Y223661D01*
G02X1741733I-1802J0D01*
G01Y223662D01*
G02X1742314Y224987I1802J0D01*
G01X1742342Y225013D01*
X1742375Y225080D01*
X1742400Y225389D01*
G03X1742357Y225529I-199J15D01*
G02X1742033Y226461I1178J932D01*
G02X1742403Y227448I1501J0D01*
G01Y227449D01*
X1742404D01*
G03X1742452Y227579I-152J130D01*
G01Y227843D01*
G03X1742404Y227973I-200J0D01*
G01X1742403Y227974D01*
G02Y229948I1131J987D01*
G01Y229949D01*
X1742404D01*
G03X1742452Y230079I-152J130D01*
G01Y230343D01*
G03X1742404Y230473I-200J0D01*
G01X1742403Y230474D01*
G02X1742033Y231461I1131J987D01*
G37*
G36*
G01X92136Y237321D02*
X92137Y237320D01*
G03X92267Y237272I130J152D01*
G01X92531D01*
G03X92661Y237320I0J200D01*
G01X92662Y237321D01*
G02X93649Y237691I987J-1131D01*
G02Y234687I0J-1502D01*
G02X92662Y235057I0J1501D01*
G01X92661D01*
Y235058D01*
G03X92531Y235106I-130J-152D01*
G01X92267D01*
G03X92137Y235058I0J-200D01*
G01X92136Y235057D01*
G02X90162I-987J1131D01*
G01X90161D01*
Y235058D01*
G03X90031Y235106I-130J-152D01*
G01X89767D01*
G03X89637Y235058I0J-200D01*
G01X89636Y235057D01*
G02X88649Y234687I-987J1131D01*
G02Y237691I0J1502D01*
G02X89636Y237321I0J-1501D01*
G01X89637D01*
Y237320D01*
G03X89767Y237272I130J152D01*
G01X90031D01*
G03X90161Y237320I0J200D01*
G01X90162Y237321D01*
G02X92136I987J-1131D01*
G37*
G36*
G01X194498D02*
X194499Y237320D01*
G03X194629Y237272I130J152D01*
G01X194893D01*
G03X195023Y237320I0J200D01*
G01X195024Y237321D01*
G02X196011Y237691I987J-1131D01*
G02Y234687I0J-1502D01*
G02X195024Y235057I0J1501D01*
G01X195023D01*
Y235058D01*
G03X194893Y235106I-130J-152D01*
G01X194629D01*
G03X194499Y235058I0J-200D01*
G01X194498Y235057D01*
G02X192524I-987J1131D01*
G01X192523D01*
Y235058D01*
G03X192393Y235106I-130J-152D01*
G01X192129D01*
G03X191999Y235058I0J-200D01*
G01X191998Y235057D01*
G02X191011Y234687I-987J1131D01*
G02Y237691I0J1502D01*
G02X191998Y237321I0J-1501D01*
G01X191999D01*
Y237320D01*
G03X192129Y237272I130J152D01*
G01X192393D01*
G03X192523Y237320I0J200D01*
G01X192524Y237321D01*
G02X194498I987J-1131D01*
G37*
G36*
G01X296860D02*
X296861Y237320D01*
G03X296991Y237272I130J152D01*
G01X297255D01*
G03X297385Y237320I0J200D01*
G01X297386Y237321D01*
G02X298373Y237691I987J-1131D01*
G02Y234687I0J-1502D01*
G02X297386Y235057I0J1501D01*
G01X297385D01*
Y235058D01*
G03X297255Y235106I-130J-152D01*
G01X296991D01*
G03X296861Y235058I0J-200D01*
G01X296860Y235057D01*
G02X294886I-987J1131D01*
G01X294885D01*
Y235058D01*
G03X294755Y235106I-130J-152D01*
G01X294491D01*
G03X294361Y235058I0J-200D01*
G01X294360Y235057D01*
G02X293373Y234687I-987J1131D01*
G02Y237691I0J1502D01*
G02X294360Y237321I0J-1501D01*
G01X294361D01*
Y237320D01*
G03X294491Y237272I130J152D01*
G01X294755D01*
G03X294885Y237320I0J200D01*
G01X294886Y237321D01*
G02X296860I987J-1131D01*
G37*
G36*
G01X399222D02*
X399223Y237320D01*
G03X399353Y237272I130J152D01*
G01X399617D01*
G03X399747Y237320I0J200D01*
G01X399748Y237321D01*
G02X400735Y237691I987J-1131D01*
G02Y234687I0J-1502D01*
G02X399748Y235057I0J1501D01*
G01X399747D01*
Y235058D01*
G03X399617Y235106I-130J-152D01*
G01X399353D01*
G03X399223Y235058I0J-200D01*
G01X399222Y235057D01*
G02X397248I-987J1131D01*
G01X397247D01*
Y235058D01*
G03X397117Y235106I-130J-152D01*
G01X396853D01*
G03X396723Y235058I0J-200D01*
G01X396722Y235057D01*
G02X395735Y234687I-987J1131D01*
G02Y237691I0J1502D01*
G02X396722Y237321I0J-1501D01*
G01X396723D01*
Y237320D01*
G03X396853Y237272I130J152D01*
G01X397117D01*
G03X397247Y237320I0J200D01*
G01X397248Y237321D01*
G02X399222I987J-1131D01*
G37*
G36*
G01X549223D02*
X549224Y237320D01*
G03X549354Y237272I130J152D01*
G01X549618D01*
G03X549748Y237320I0J200D01*
G01X549749Y237321D01*
G02X550736Y237691I987J-1131D01*
G02Y234687I0J-1502D01*
G02X549749Y235057I0J1501D01*
G01X549748D01*
Y235058D01*
G03X549618Y235106I-130J-152D01*
G01X549354D01*
G03X549224Y235058I0J-200D01*
G01X549223Y235057D01*
G02X547249I-987J1131D01*
G01X547248D01*
Y235058D01*
G03X547118Y235106I-130J-152D01*
G01X546854D01*
G03X546724Y235058I0J-200D01*
G01X546723Y235057D01*
G02X545736Y234687I-987J1131D01*
G02Y237691I0J1502D01*
G02X546723Y237321I0J-1501D01*
G01X546724D01*
Y237320D01*
G03X546854Y237272I130J152D01*
G01X547118D01*
G03X547248Y237320I0J200D01*
G01X547249Y237321D01*
G02X549223I987J-1131D01*
G37*
G36*
G01X651585D02*
X651586Y237320D01*
G03X651716Y237272I130J152D01*
G01X651980D01*
G03X652110Y237320I0J200D01*
G01X652111Y237321D01*
G02X653098Y237691I987J-1131D01*
G02Y234687I0J-1502D01*
G02X652111Y235057I0J1501D01*
G01X652110D01*
Y235058D01*
G03X651980Y235106I-130J-152D01*
G01X651716D01*
G03X651586Y235058I0J-200D01*
G01X651585Y235057D01*
G02X649611I-987J1131D01*
G01X649610D01*
Y235058D01*
G03X649480Y235106I-130J-152D01*
G01X649216D01*
G03X649086Y235058I0J-200D01*
G01X649085Y235057D01*
G02X648098Y234687I-987J1131D01*
G02Y237691I0J1502D01*
G02X649085Y237321I0J-1501D01*
G01X649086D01*
Y237320D01*
G03X649216Y237272I130J152D01*
G01X649480D01*
G03X649610Y237320I0J200D01*
G01X649611Y237321D01*
G02X651585I987J-1131D01*
G37*
G36*
G01X753947D02*
X753948Y237320D01*
G03X754078Y237272I130J152D01*
G01X754342D01*
G03X754472Y237320I0J200D01*
G01X754473Y237321D01*
G02X755460Y237691I987J-1131D01*
G02Y234687I0J-1502D01*
G02X754473Y235057I0J1501D01*
G01X754472D01*
Y235058D01*
G03X754342Y235106I-130J-152D01*
G01X754078D01*
G03X753948Y235058I0J-200D01*
G01X753947Y235057D01*
G02X751973I-987J1131D01*
G01X751972D01*
Y235058D01*
G03X751842Y235106I-130J-152D01*
G01X751578D01*
G03X751448Y235058I0J-200D01*
G01X751447Y235057D01*
G02X750460Y234687I-987J1131D01*
G02Y237691I0J1502D01*
G02X751447Y237321I0J-1501D01*
G01X751448D01*
Y237320D01*
G03X751578Y237272I130J152D01*
G01X751842D01*
G03X751972Y237320I0J200D01*
G01X751973Y237321D01*
G02X753947I987J-1131D01*
G37*
G36*
G01X856309D02*
X856310Y237320D01*
G03X856440Y237272I130J152D01*
G01X856704D01*
G03X856834Y237320I0J200D01*
G01X856835Y237321D01*
G02X857822Y237691I987J-1131D01*
G02Y234687I0J-1502D01*
G02X856835Y235057I0J1501D01*
G01X856834D01*
Y235058D01*
G03X856704Y235106I-130J-152D01*
G01X856440D01*
G03X856310Y235058I0J-200D01*
G01X856309Y235057D01*
G02X854335I-987J1131D01*
G01X854334D01*
Y235058D01*
G03X854204Y235106I-130J-152D01*
G01X853940D01*
G03X853810Y235058I0J-200D01*
G01X853809Y235057D01*
G02X852822Y234687I-987J1131D01*
G02Y237691I0J1502D01*
G02X853809Y237321I0J-1501D01*
G01X853810D01*
Y237320D01*
G03X853940Y237272I130J152D01*
G01X854204D01*
G03X854334Y237320I0J200D01*
G01X854335Y237321D01*
G02X856309I987J-1131D01*
G37*
G36*
G01X1006309D02*
X1006310Y237320D01*
G03X1006440Y237272I130J152D01*
G01X1006704D01*
G03X1006834Y237320I0J200D01*
G01X1006835Y237321D01*
G02X1007822Y237691I987J-1131D01*
G02Y234687I0J-1502D01*
G02X1006835Y235057I0J1501D01*
G01X1006834D01*
Y235058D01*
G03X1006704Y235106I-130J-152D01*
G01X1006440D01*
G03X1006310Y235058I0J-200D01*
G01X1006309Y235057D01*
G02X1004335I-987J1131D01*
G01X1004334D01*
Y235058D01*
G03X1004204Y235106I-130J-152D01*
G01X1003940D01*
G03X1003810Y235058I0J-200D01*
G01X1003809Y235057D01*
G02X1002822Y234687I-987J1131D01*
G02Y237691I0J1502D01*
G02X1003809Y237321I0J-1501D01*
G01X1003810D01*
Y237320D01*
G03X1003940Y237272I130J152D01*
G01X1004204D01*
G03X1004334Y237320I0J200D01*
G01X1004335Y237321D01*
G02X1006309I987J-1131D01*
G37*
G36*
G01X1108671D02*
X1108672Y237320D01*
G03X1108802Y237272I130J152D01*
G01X1109066D01*
G03X1109196Y237320I0J200D01*
G01X1109197Y237321D01*
G02X1110184Y237691I987J-1131D01*
G02Y234687I0J-1502D01*
G02X1109197Y235057I0J1501D01*
G01X1109196D01*
Y235058D01*
G03X1109066Y235106I-130J-152D01*
G01X1108802D01*
G03X1108672Y235058I0J-200D01*
G01X1108671Y235057D01*
G02X1106697I-987J1131D01*
G01X1106696D01*
Y235058D01*
G03X1106566Y235106I-130J-152D01*
G01X1106302D01*
G03X1106172Y235058I0J-200D01*
G01X1106171Y235057D01*
G02X1105184Y234687I-987J1131D01*
G02Y237691I0J1502D01*
G02X1106171Y237321I0J-1501D01*
G01X1106172D01*
Y237320D01*
G03X1106302Y237272I130J152D01*
G01X1106566D01*
G03X1106696Y237320I0J200D01*
G01X1106697Y237321D01*
G02X1108671I987J-1131D01*
G37*
G36*
G01X1211033D02*
X1211034Y237320D01*
G03X1211164Y237272I130J152D01*
G01X1211428D01*
G03X1211558Y237320I0J200D01*
G01X1211559Y237321D01*
G02X1212546Y237691I987J-1131D01*
G02Y234687I0J-1502D01*
G02X1211559Y235057I0J1501D01*
G01X1211558D01*
Y235058D01*
G03X1211428Y235106I-130J-152D01*
G01X1211164D01*
G03X1211034Y235058I0J-200D01*
G01X1211033Y235057D01*
G02X1209059I-987J1131D01*
G01X1209058D01*
Y235058D01*
G03X1208928Y235106I-130J-152D01*
G01X1208664D01*
G03X1208534Y235058I0J-200D01*
G01X1208533Y235057D01*
G02X1207546Y234687I-987J1131D01*
G02Y237691I0J1502D01*
G02X1208533Y237321I0J-1501D01*
G01X1208534D01*
Y237320D01*
G03X1208664Y237272I130J152D01*
G01X1208928D01*
G03X1209058Y237320I0J200D01*
G01X1209059Y237321D01*
G02X1211033I987J-1131D01*
G37*
G36*
G01X1313395D02*
X1313396Y237320D01*
G03X1313526Y237272I130J152D01*
G01X1313790D01*
G03X1313920Y237320I0J200D01*
G01X1313921Y237321D01*
G02X1314908Y237691I987J-1131D01*
G02Y234687I0J-1502D01*
G02X1313921Y235057I0J1501D01*
G01X1313920D01*
Y235058D01*
G03X1313790Y235106I-130J-152D01*
G01X1313526D01*
G03X1313396Y235058I0J-200D01*
G01X1313395Y235057D01*
G02X1311421I-987J1131D01*
G01X1311420D01*
Y235058D01*
G03X1311290Y235106I-130J-152D01*
G01X1311026D01*
G03X1310896Y235058I0J-200D01*
G01X1310895Y235057D01*
G02X1309908Y234687I-987J1131D01*
G02Y237691I0J1502D01*
G02X1310895Y237321I0J-1501D01*
G01X1310896D01*
Y237320D01*
G03X1311026Y237272I130J152D01*
G01X1311290D01*
G03X1311420Y237320I0J200D01*
G01X1311421Y237321D01*
G02X1313395I987J-1131D01*
G37*
G36*
G01X1463396D02*
X1463397Y237320D01*
G03X1463527Y237272I130J152D01*
G01X1463791D01*
G03X1463921Y237320I0J200D01*
G01X1463922Y237321D01*
G02X1464909Y237691I987J-1131D01*
G02Y234687I0J-1502D01*
G02X1463922Y235057I0J1501D01*
G01X1463921D01*
Y235058D01*
G03X1463791Y235106I-130J-152D01*
G01X1463527D01*
G03X1463397Y235058I0J-200D01*
G01X1463396Y235057D01*
G02X1461422I-987J1131D01*
G01X1461421D01*
Y235058D01*
G03X1461291Y235106I-130J-152D01*
G01X1461027D01*
G03X1460897Y235058I0J-200D01*
G01X1460896Y235057D01*
G02X1459909Y234687I-987J1131D01*
G02Y237691I0J1502D01*
G02X1460896Y237321I0J-1501D01*
G01X1460897D01*
Y237320D01*
G03X1461027Y237272I130J152D01*
G01X1461291D01*
G03X1461421Y237320I0J200D01*
G01X1461422Y237321D01*
G02X1463396I987J-1131D01*
G37*
G36*
G01X1565758D02*
X1565759Y237320D01*
G03X1565889Y237272I130J152D01*
G01X1566153D01*
G03X1566283Y237320I0J200D01*
G01X1566284Y237321D01*
G02X1567271Y237691I987J-1131D01*
G02Y234687I0J-1502D01*
G02X1566284Y235057I0J1501D01*
G01X1566283D01*
Y235058D01*
G03X1566153Y235106I-130J-152D01*
G01X1565889D01*
G03X1565759Y235058I0J-200D01*
G01X1565758Y235057D01*
G02X1563784I-987J1131D01*
G01X1563783D01*
Y235058D01*
G03X1563653Y235106I-130J-152D01*
G01X1563389D01*
G03X1563259Y235058I0J-200D01*
G01X1563258Y235057D01*
G02X1562271Y234687I-987J1131D01*
G02Y237691I0J1502D01*
G02X1563258Y237321I0J-1501D01*
G01X1563259D01*
Y237320D01*
G03X1563389Y237272I130J152D01*
G01X1563653D01*
G03X1563783Y237320I0J200D01*
G01X1563784Y237321D01*
G02X1565758I987J-1131D01*
G37*
G36*
G01X1668120D02*
X1668121Y237320D01*
G03X1668251Y237272I130J152D01*
G01X1668515D01*
G03X1668645Y237320I0J200D01*
G01X1668646Y237321D01*
G02X1669633Y237691I987J-1131D01*
G02Y234687I0J-1502D01*
G02X1668646Y235057I0J1501D01*
G01X1668645D01*
Y235058D01*
G03X1668515Y235106I-130J-152D01*
G01X1668251D01*
G03X1668121Y235058I0J-200D01*
G01X1668120Y235057D01*
G02X1666146I-987J1131D01*
G01X1666145D01*
Y235058D01*
G03X1666015Y235106I-130J-152D01*
G01X1665751D01*
G03X1665621Y235058I0J-200D01*
G01X1665620Y235057D01*
G02X1664633Y234687I-987J1131D01*
G02Y237691I0J1502D01*
G02X1665620Y237321I0J-1501D01*
G01X1665621D01*
Y237320D01*
G03X1665751Y237272I130J152D01*
G01X1666015D01*
G03X1666145Y237320I0J200D01*
G01X1666146Y237321D01*
G02X1668120I987J-1131D01*
G37*
G36*
G01X1770482D02*
X1770483Y237320D01*
G03X1770613Y237272I130J152D01*
G01X1770877D01*
G03X1771007Y237320I0J200D01*
G01X1771008Y237321D01*
G02X1771995Y237691I987J-1131D01*
G02Y234687I0J-1502D01*
G02X1771008Y235057I0J1501D01*
G01X1771007D01*
Y235058D01*
G03X1770877Y235106I-130J-152D01*
G01X1770613D01*
G03X1770483Y235058I0J-200D01*
G01X1770482Y235057D01*
G02X1768508I-987J1131D01*
G01X1768507D01*
Y235058D01*
G03X1768377Y235106I-130J-152D01*
G01X1768113D01*
G03X1767983Y235058I0J-200D01*
G01X1767982Y235057D01*
G02X1766995Y234687I-987J1131D01*
G02Y237691I0J1502D01*
G02X1767982Y237321I0J-1501D01*
G01X1767983D01*
Y237320D01*
G03X1768113Y237272I130J152D01*
G01X1768377D01*
G03X1768507Y237320I0J200D01*
G01X1768508Y237321D01*
G02X1770482I987J-1131D01*
G37*
G36*
G01X72626Y237743D02*
X72627Y237742D01*
G03X72757Y237694I130J152D01*
G01X73021D01*
G03X73151Y237742I0J200D01*
G01X73152Y237743D01*
G02X74139Y238113I987J-1131D01*
G02Y235109I0J-1502D01*
G02X73152Y235479I0J1501D01*
G01X73151D01*
Y235480D01*
G03X73021Y235528I-130J-152D01*
G01X72757D01*
G03X72627Y235480I0J-200D01*
G01X72626Y235479D01*
G02X70652I-987J1131D01*
G01X70651D01*
Y235480D01*
G03X70521Y235528I-130J-152D01*
G01X70257D01*
G03X70127Y235480I0J-200D01*
G01X70126Y235479D01*
G02X69139Y235109I-987J1131D01*
G02Y238113I0J1502D01*
G02X70126Y237743I0J-1501D01*
G01X70127D01*
Y237742D01*
G03X70257Y237694I130J152D01*
G01X70521D01*
G03X70651Y237742I0J200D01*
G01X70652Y237743D01*
G02X72626I987J-1131D01*
G37*
G36*
G01X174988D02*
X174989Y237742D01*
G03X175119Y237694I130J152D01*
G01X175383D01*
G03X175513Y237742I0J200D01*
G01X175514Y237743D01*
G02X176501Y238113I987J-1131D01*
G02Y235109I0J-1502D01*
G02X175514Y235479I0J1501D01*
G01X175513D01*
Y235480D01*
G03X175383Y235528I-130J-152D01*
G01X175119D01*
G03X174989Y235480I0J-200D01*
G01X174988Y235479D01*
G02X173014I-987J1131D01*
G01X173013D01*
Y235480D01*
G03X172883Y235528I-130J-152D01*
G01X172619D01*
G03X172489Y235480I0J-200D01*
G01X172488Y235479D01*
G02X171501Y235109I-987J1131D01*
G02Y238113I0J1502D01*
G02X172488Y237743I0J-1501D01*
G01X172489D01*
Y237742D01*
G03X172619Y237694I130J152D01*
G01X172883D01*
G03X173013Y237742I0J200D01*
G01X173014Y237743D01*
G02X174988I987J-1131D01*
G37*
G36*
G01X277350D02*
X277351Y237742D01*
G03X277481Y237694I130J152D01*
G01X277745D01*
G03X277875Y237742I0J200D01*
G01X277876Y237743D01*
G02X278863Y238113I987J-1131D01*
G02Y235109I0J-1502D01*
G02X277876Y235479I0J1501D01*
G01X277875D01*
Y235480D01*
G03X277745Y235528I-130J-152D01*
G01X277481D01*
G03X277351Y235480I0J-200D01*
G01X277350Y235479D01*
G02X275376I-987J1131D01*
G01X275375D01*
Y235480D01*
G03X275245Y235528I-130J-152D01*
G01X274981D01*
G03X274851Y235480I0J-200D01*
G01X274850Y235479D01*
G02X273863Y235109I-987J1131D01*
G02Y238113I0J1502D01*
G02X274850Y237743I0J-1501D01*
G01X274851D01*
Y237742D01*
G03X274981Y237694I130J152D01*
G01X275245D01*
G03X275375Y237742I0J200D01*
G01X275376Y237743D01*
G02X277350I987J-1131D01*
G37*
G36*
G01X379712D02*
X379713Y237742D01*
G03X379843Y237694I130J152D01*
G01X380107D01*
G03X380237Y237742I0J200D01*
G01X380238Y237743D01*
G02X381225Y238113I987J-1131D01*
G02Y235109I0J-1502D01*
G02X380238Y235479I0J1501D01*
G01X380237D01*
Y235480D01*
G03X380107Y235528I-130J-152D01*
G01X379843D01*
G03X379713Y235480I0J-200D01*
G01X379712Y235479D01*
G02X377738I-987J1131D01*
G01X377737D01*
Y235480D01*
G03X377607Y235528I-130J-152D01*
G01X377343D01*
G03X377213Y235480I0J-200D01*
G01X377212Y235479D01*
G02X376225Y235109I-987J1131D01*
G02Y238113I0J1502D01*
G02X377212Y237743I0J-1501D01*
G01X377213D01*
Y237742D01*
G03X377343Y237694I130J152D01*
G01X377607D01*
G03X377737Y237742I0J200D01*
G01X377738Y237743D01*
G02X379712I987J-1131D01*
G37*
G36*
G01X529713D02*
X529714Y237742D01*
G03X529844Y237694I130J152D01*
G01X530108D01*
G03X530238Y237742I0J200D01*
G01X530239Y237743D01*
G02X531226Y238113I987J-1131D01*
G02Y235109I0J-1502D01*
G02X530239Y235479I0J1501D01*
G01X530238D01*
Y235480D01*
G03X530108Y235528I-130J-152D01*
G01X529844D01*
G03X529714Y235480I0J-200D01*
G01X529713Y235479D01*
G02X527739I-987J1131D01*
G01X527738D01*
Y235480D01*
G03X527608Y235528I-130J-152D01*
G01X527344D01*
G03X527214Y235480I0J-200D01*
G01X527213Y235479D01*
G02X526226Y235109I-987J1131D01*
G02Y238113I0J1502D01*
G02X527213Y237743I0J-1501D01*
G01X527214D01*
Y237742D01*
G03X527344Y237694I130J152D01*
G01X527608D01*
G03X527738Y237742I0J200D01*
G01X527739Y237743D01*
G02X529713I987J-1131D01*
G37*
G36*
G01X632075D02*
X632076Y237742D01*
G03X632206Y237694I130J152D01*
G01X632470D01*
G03X632600Y237742I0J200D01*
G01X632601Y237743D01*
G02X633588Y238113I987J-1131D01*
G02Y235109I0J-1502D01*
G02X632601Y235479I0J1501D01*
G01X632600D01*
Y235480D01*
G03X632470Y235528I-130J-152D01*
G01X632206D01*
G03X632076Y235480I0J-200D01*
G01X632075Y235479D01*
G02X630101I-987J1131D01*
G01X630100D01*
Y235480D01*
G03X629970Y235528I-130J-152D01*
G01X629706D01*
G03X629576Y235480I0J-200D01*
G01X629575Y235479D01*
G02X628588Y235109I-987J1131D01*
G02Y238113I0J1502D01*
G02X629575Y237743I0J-1501D01*
G01X629576D01*
Y237742D01*
G03X629706Y237694I130J152D01*
G01X629970D01*
G03X630100Y237742I0J200D01*
G01X630101Y237743D01*
G02X632075I987J-1131D01*
G37*
G36*
G01X734437D02*
X734438Y237742D01*
G03X734568Y237694I130J152D01*
G01X734832D01*
G03X734962Y237742I0J200D01*
G01X734963Y237743D01*
G02X735950Y238113I987J-1131D01*
G02Y235109I0J-1502D01*
G02X734963Y235479I0J1501D01*
G01X734962D01*
Y235480D01*
G03X734832Y235528I-130J-152D01*
G01X734568D01*
G03X734438Y235480I0J-200D01*
G01X734437Y235479D01*
G02X732463I-987J1131D01*
G01X732462D01*
Y235480D01*
G03X732332Y235528I-130J-152D01*
G01X732068D01*
G03X731938Y235480I0J-200D01*
G01X731937Y235479D01*
G02X730950Y235109I-987J1131D01*
G02Y238113I0J1502D01*
G02X731937Y237743I0J-1501D01*
G01X731938D01*
Y237742D01*
G03X732068Y237694I130J152D01*
G01X732332D01*
G03X732462Y237742I0J200D01*
G01X732463Y237743D01*
G02X734437I987J-1131D01*
G37*
G36*
G01X836799D02*
X836800Y237742D01*
G03X836930Y237694I130J152D01*
G01X837194D01*
G03X837324Y237742I0J200D01*
G01X837325Y237743D01*
G02X838312Y238113I987J-1131D01*
G02Y235109I0J-1502D01*
G02X837325Y235479I0J1501D01*
G01X837324D01*
Y235480D01*
G03X837194Y235528I-130J-152D01*
G01X836930D01*
G03X836800Y235480I0J-200D01*
G01X836799Y235479D01*
G02X834825I-987J1131D01*
G01X834824D01*
Y235480D01*
G03X834694Y235528I-130J-152D01*
G01X834430D01*
G03X834300Y235480I0J-200D01*
G01X834299Y235479D01*
G02X833312Y235109I-987J1131D01*
G02Y238113I0J1502D01*
G02X834299Y237743I0J-1501D01*
G01X834300D01*
Y237742D01*
G03X834430Y237694I130J152D01*
G01X834694D01*
G03X834824Y237742I0J200D01*
G01X834825Y237743D01*
G02X836799I987J-1131D01*
G37*
G36*
G01X986799D02*
X986800Y237742D01*
G03X986930Y237694I130J152D01*
G01X987194D01*
G03X987324Y237742I0J200D01*
G01X987325Y237743D01*
G02X988312Y238113I987J-1131D01*
G02Y235109I0J-1502D01*
G02X987325Y235479I0J1501D01*
G01X987324D01*
Y235480D01*
G03X987194Y235528I-130J-152D01*
G01X986930D01*
G03X986800Y235480I0J-200D01*
G01X986799Y235479D01*
G02X984825I-987J1131D01*
G01X984824D01*
Y235480D01*
G03X984694Y235528I-130J-152D01*
G01X984430D01*
G03X984300Y235480I0J-200D01*
G01X984299Y235479D01*
G02X983312Y235109I-987J1131D01*
G02Y238113I0J1502D01*
G02X984299Y237743I0J-1501D01*
G01X984300D01*
Y237742D01*
G03X984430Y237694I130J152D01*
G01X984694D01*
G03X984824Y237742I0J200D01*
G01X984825Y237743D01*
G02X986799I987J-1131D01*
G37*
G36*
G01X1089161D02*
X1089162Y237742D01*
G03X1089292Y237694I130J152D01*
G01X1089556D01*
G03X1089686Y237742I0J200D01*
G01X1089687Y237743D01*
G02X1090674Y238113I987J-1131D01*
G02Y235109I0J-1502D01*
G02X1089687Y235479I0J1501D01*
G01X1089686D01*
Y235480D01*
G03X1089556Y235528I-130J-152D01*
G01X1089292D01*
G03X1089162Y235480I0J-200D01*
G01X1089161Y235479D01*
G02X1087187I-987J1131D01*
G01X1087186D01*
Y235480D01*
G03X1087056Y235528I-130J-152D01*
G01X1086792D01*
G03X1086662Y235480I0J-200D01*
G01X1086661Y235479D01*
G02X1085674Y235109I-987J1131D01*
G02Y238113I0J1502D01*
G02X1086661Y237743I0J-1501D01*
G01X1086662D01*
Y237742D01*
G03X1086792Y237694I130J152D01*
G01X1087056D01*
G03X1087186Y237742I0J200D01*
G01X1087187Y237743D01*
G02X1089161I987J-1131D01*
G37*
G36*
G01X1191523D02*
X1191524Y237742D01*
G03X1191654Y237694I130J152D01*
G01X1191918D01*
G03X1192048Y237742I0J200D01*
G01X1192049Y237743D01*
G02X1193036Y238113I987J-1131D01*
G02Y235109I0J-1502D01*
G02X1192049Y235479I0J1501D01*
G01X1192048D01*
Y235480D01*
G03X1191918Y235528I-130J-152D01*
G01X1191654D01*
G03X1191524Y235480I0J-200D01*
G01X1191523Y235479D01*
G02X1189549I-987J1131D01*
G01X1189548D01*
Y235480D01*
G03X1189418Y235528I-130J-152D01*
G01X1189154D01*
G03X1189024Y235480I0J-200D01*
G01X1189023Y235479D01*
G02X1188036Y235109I-987J1131D01*
G02Y238113I0J1502D01*
G02X1189023Y237743I0J-1501D01*
G01X1189024D01*
Y237742D01*
G03X1189154Y237694I130J152D01*
G01X1189418D01*
G03X1189548Y237742I0J200D01*
G01X1189549Y237743D01*
G02X1191523I987J-1131D01*
G37*
G36*
G01X1293885D02*
X1293886Y237742D01*
G03X1294016Y237694I130J152D01*
G01X1294280D01*
G03X1294410Y237742I0J200D01*
G01X1294411Y237743D01*
G02X1295398Y238113I987J-1131D01*
G02Y235109I0J-1502D01*
G02X1294411Y235479I0J1501D01*
G01X1294410D01*
Y235480D01*
G03X1294280Y235528I-130J-152D01*
G01X1294016D01*
G03X1293886Y235480I0J-200D01*
G01X1293885Y235479D01*
G02X1291911I-987J1131D01*
G01X1291910D01*
Y235480D01*
G03X1291780Y235528I-130J-152D01*
G01X1291516D01*
G03X1291386Y235480I0J-200D01*
G01X1291385Y235479D01*
G02X1290398Y235109I-987J1131D01*
G02Y238113I0J1502D01*
G02X1291385Y237743I0J-1501D01*
G01X1291386D01*
Y237742D01*
G03X1291516Y237694I130J152D01*
G01X1291780D01*
G03X1291910Y237742I0J200D01*
G01X1291911Y237743D01*
G02X1293885I987J-1131D01*
G37*
G36*
G01X1443886D02*
X1443887Y237742D01*
G03X1444017Y237694I130J152D01*
G01X1444281D01*
G03X1444411Y237742I0J200D01*
G01X1444412Y237743D01*
G02X1445399Y238113I987J-1131D01*
G02Y235109I0J-1502D01*
G02X1444412Y235479I0J1501D01*
G01X1444411D01*
Y235480D01*
G03X1444281Y235528I-130J-152D01*
G01X1444017D01*
G03X1443887Y235480I0J-200D01*
G01X1443886Y235479D01*
G02X1441912I-987J1131D01*
G01X1441911D01*
Y235480D01*
G03X1441781Y235528I-130J-152D01*
G01X1441517D01*
G03X1441387Y235480I0J-200D01*
G01X1441386Y235479D01*
G02X1440399Y235109I-987J1131D01*
G02Y238113I0J1502D01*
G02X1441386Y237743I0J-1501D01*
G01X1441387D01*
Y237742D01*
G03X1441517Y237694I130J152D01*
G01X1441781D01*
G03X1441911Y237742I0J200D01*
G01X1441912Y237743D01*
G02X1443886I987J-1131D01*
G37*
G36*
G01X1546248D02*
X1546249Y237742D01*
G03X1546379Y237694I130J152D01*
G01X1546643D01*
G03X1546773Y237742I0J200D01*
G01X1546774Y237743D01*
G02X1547761Y238113I987J-1131D01*
G02Y235109I0J-1502D01*
G02X1546774Y235479I0J1501D01*
G01X1546773D01*
Y235480D01*
G03X1546643Y235528I-130J-152D01*
G01X1546379D01*
G03X1546249Y235480I0J-200D01*
G01X1546248Y235479D01*
G02X1544274I-987J1131D01*
G01X1544273D01*
Y235480D01*
G03X1544143Y235528I-130J-152D01*
G01X1543879D01*
G03X1543749Y235480I0J-200D01*
G01X1543748Y235479D01*
G02X1542761Y235109I-987J1131D01*
G02Y238113I0J1502D01*
G02X1543748Y237743I0J-1501D01*
G01X1543749D01*
Y237742D01*
G03X1543879Y237694I130J152D01*
G01X1544143D01*
G03X1544273Y237742I0J200D01*
G01X1544274Y237743D01*
G02X1546248I987J-1131D01*
G37*
G36*
G01X1648610D02*
X1648611Y237742D01*
G03X1648741Y237694I130J152D01*
G01X1649005D01*
G03X1649135Y237742I0J200D01*
G01X1649136Y237743D01*
G02X1650123Y238113I987J-1131D01*
G02Y235109I0J-1502D01*
G02X1649136Y235479I0J1501D01*
G01X1649135D01*
Y235480D01*
G03X1649005Y235528I-130J-152D01*
G01X1648741D01*
G03X1648611Y235480I0J-200D01*
G01X1648610Y235479D01*
G02X1646636I-987J1131D01*
G01X1646635D01*
Y235480D01*
G03X1646505Y235528I-130J-152D01*
G01X1646241D01*
G03X1646111Y235480I0J-200D01*
G01X1646110Y235479D01*
G02X1645123Y235109I-987J1131D01*
G02Y238113I0J1502D01*
G02X1646110Y237743I0J-1501D01*
G01X1646111D01*
Y237742D01*
G03X1646241Y237694I130J152D01*
G01X1646505D01*
G03X1646635Y237742I0J200D01*
G01X1646636Y237743D01*
G02X1648610I987J-1131D01*
G37*
G36*
G01X1750972D02*
X1750973Y237742D01*
G03X1751103Y237694I130J152D01*
G01X1751367D01*
G03X1751497Y237742I0J200D01*
G01X1751498Y237743D01*
G02X1752485Y238113I987J-1131D01*
G02Y235109I0J-1502D01*
G02X1751498Y235479I0J1501D01*
G01X1751497D01*
Y235480D01*
G03X1751367Y235528I-130J-152D01*
G01X1751103D01*
G03X1750973Y235480I0J-200D01*
G01X1750972Y235479D01*
G02X1748998I-987J1131D01*
G01X1748997D01*
Y235480D01*
G03X1748867Y235528I-130J-152D01*
G01X1748603D01*
G03X1748473Y235480I0J-200D01*
G01X1748472Y235479D01*
G02X1747485Y235109I-987J1131D01*
G02Y238113I0J1502D01*
G02X1748472Y237743I0J-1501D01*
G01X1748473D01*
Y237742D01*
G03X1748603Y237694I130J152D01*
G01X1748867D01*
G03X1748997Y237742I0J200D01*
G01X1748998Y237743D01*
G02X1750972I987J-1131D01*
G37*
G36*
G01X137162Y241699D02*
G02X140166I1502J0D01*
G02X139554Y240489I-1502J0D01*
G01X139553Y240488D01*
G03X139473Y240335I120J-160D01*
G01X139461Y240021D01*
G03X139533Y239861I200J-6D01*
G02X140065Y238714I-970J-1147D01*
G02X137061I-1502J0D01*
G02X137673Y239924I1502J0D01*
G01X137674Y239925D01*
G03X137754Y240078I-120J160D01*
G01X137766Y240392D01*
G03X137694Y240552I-200J6D01*
G02X137162Y241699I970J1147D01*
G37*
G36*
G01X92077Y249897D02*
X92078Y249896D01*
G03X92208Y249848I130J152D01*
G01X92472D01*
G03X92602Y249896I0J200D01*
G01X92603Y249897D01*
G02X93590Y250267I987J-1131D01*
G02Y247263I0J-1502D01*
G02X92603Y247633I0J1501D01*
G01X92602D01*
Y247634D01*
G03X92472Y247682I-130J-152D01*
G01X92208D01*
G03X92078Y247634I0J-200D01*
G01X92077Y247633D01*
G02X90103I-987J1131D01*
G01X90102D01*
Y247634D01*
G03X89972Y247682I-130J-152D01*
G01X89708D01*
G03X89578Y247634I0J-200D01*
G01X89577Y247633D01*
G02X88590Y247263I-987J1131D01*
G02Y250267I0J1502D01*
G02X89577Y249897I0J-1501D01*
G01X89578D01*
Y249896D01*
G03X89708Y249848I130J152D01*
G01X89972D01*
G03X90102Y249896I0J200D01*
G01X90103Y249897D01*
G02X92077I987J-1131D01*
G37*
G36*
G01X194439D02*
X194440Y249896D01*
G03X194570Y249848I130J152D01*
G01X194834D01*
G03X194964Y249896I0J200D01*
G01X194965Y249897D01*
G02X195952Y250267I987J-1131D01*
G02Y247263I0J-1502D01*
G02X194965Y247633I0J1501D01*
G01X194964D01*
Y247634D01*
G03X194834Y247682I-130J-152D01*
G01X194570D01*
G03X194440Y247634I0J-200D01*
G01X194439Y247633D01*
G02X192465I-987J1131D01*
G01X192464D01*
Y247634D01*
G03X192334Y247682I-130J-152D01*
G01X192070D01*
G03X191940Y247634I0J-200D01*
G01X191939Y247633D01*
G02X190952Y247263I-987J1131D01*
G02Y250267I0J1502D01*
G02X191939Y249897I0J-1501D01*
G01X191940D01*
Y249896D01*
G03X192070Y249848I130J152D01*
G01X192334D01*
G03X192464Y249896I0J200D01*
G01X192465Y249897D01*
G02X194439I987J-1131D01*
G37*
G36*
G01X296801D02*
X296802Y249896D01*
G03X296932Y249848I130J152D01*
G01X297196D01*
G03X297326Y249896I0J200D01*
G01X297327Y249897D01*
G02X298314Y250267I987J-1131D01*
G02Y247263I0J-1502D01*
G02X297327Y247633I0J1501D01*
G01X297326D01*
Y247634D01*
G03X297196Y247682I-130J-152D01*
G01X296932D01*
G03X296802Y247634I0J-200D01*
G01X296801Y247633D01*
G02X294827I-987J1131D01*
G01X294826D01*
Y247634D01*
G03X294696Y247682I-130J-152D01*
G01X294432D01*
G03X294302Y247634I0J-200D01*
G01X294301Y247633D01*
G02X293314Y247263I-987J1131D01*
G02Y250267I0J1502D01*
G02X294301Y249897I0J-1501D01*
G01X294302D01*
Y249896D01*
G03X294432Y249848I130J152D01*
G01X294696D01*
G03X294826Y249896I0J200D01*
G01X294827Y249897D01*
G02X296801I987J-1131D01*
G37*
G36*
G01X399163D02*
X399164Y249896D01*
G03X399294Y249848I130J152D01*
G01X399558D01*
G03X399688Y249896I0J200D01*
G01X399689Y249897D01*
G02X400676Y250267I987J-1131D01*
G02Y247263I0J-1502D01*
G02X399689Y247633I0J1501D01*
G01X399688D01*
Y247634D01*
G03X399558Y247682I-130J-152D01*
G01X399294D01*
G03X399164Y247634I0J-200D01*
G01X399163Y247633D01*
G02X397189I-987J1131D01*
G01X397188D01*
Y247634D01*
G03X397058Y247682I-130J-152D01*
G01X396794D01*
G03X396664Y247634I0J-200D01*
G01X396663Y247633D01*
G02X395676Y247263I-987J1131D01*
G02Y250267I0J1502D01*
G02X396663Y249897I0J-1501D01*
G01X396664D01*
Y249896D01*
G03X396794Y249848I130J152D01*
G01X397058D01*
G03X397188Y249896I0J200D01*
G01X397189Y249897D01*
G02X399163I987J-1131D01*
G37*
G36*
G01X549164D02*
X549165Y249896D01*
G03X549295Y249848I130J152D01*
G01X549559D01*
G03X549689Y249896I0J200D01*
G01X549690Y249897D01*
G02X550677Y250267I987J-1131D01*
G02Y247263I0J-1502D01*
G02X549690Y247633I0J1501D01*
G01X549689D01*
Y247634D01*
G03X549559Y247682I-130J-152D01*
G01X549295D01*
G03X549165Y247634I0J-200D01*
G01X549164Y247633D01*
G02X547190I-987J1131D01*
G01X547189D01*
Y247634D01*
G03X547059Y247682I-130J-152D01*
G01X546795D01*
G03X546665Y247634I0J-200D01*
G01X546664Y247633D01*
G02X545677Y247263I-987J1131D01*
G02Y250267I0J1502D01*
G02X546664Y249897I0J-1501D01*
G01X546665D01*
Y249896D01*
G03X546795Y249848I130J152D01*
G01X547059D01*
G03X547189Y249896I0J200D01*
G01X547190Y249897D01*
G02X549164I987J-1131D01*
G37*
G36*
G01X651526D02*
X651527Y249896D01*
G03X651657Y249848I130J152D01*
G01X651921D01*
G03X652051Y249896I0J200D01*
G01X652052Y249897D01*
G02X653039Y250267I987J-1131D01*
G02Y247263I0J-1502D01*
G02X652052Y247633I0J1501D01*
G01X652051D01*
Y247634D01*
G03X651921Y247682I-130J-152D01*
G01X651657D01*
G03X651527Y247634I0J-200D01*
G01X651526Y247633D01*
G02X649552I-987J1131D01*
G01X649551D01*
Y247634D01*
G03X649421Y247682I-130J-152D01*
G01X649157D01*
G03X649027Y247634I0J-200D01*
G01X649026Y247633D01*
G02X648039Y247263I-987J1131D01*
G02Y250267I0J1502D01*
G02X649026Y249897I0J-1501D01*
G01X649027D01*
Y249896D01*
G03X649157Y249848I130J152D01*
G01X649421D01*
G03X649551Y249896I0J200D01*
G01X649552Y249897D01*
G02X651526I987J-1131D01*
G37*
G36*
G01X753888D02*
X753889Y249896D01*
G03X754019Y249848I130J152D01*
G01X754283D01*
G03X754413Y249896I0J200D01*
G01X754414Y249897D01*
G02X755401Y250267I987J-1131D01*
G02Y247263I0J-1502D01*
G02X754414Y247633I0J1501D01*
G01X754413D01*
Y247634D01*
G03X754283Y247682I-130J-152D01*
G01X754019D01*
G03X753889Y247634I0J-200D01*
G01X753888Y247633D01*
G02X751914I-987J1131D01*
G01X751913D01*
Y247634D01*
G03X751783Y247682I-130J-152D01*
G01X751519D01*
G03X751389Y247634I0J-200D01*
G01X751388Y247633D01*
G02X750401Y247263I-987J1131D01*
G02Y250267I0J1502D01*
G02X751388Y249897I0J-1501D01*
G01X751389D01*
Y249896D01*
G03X751519Y249848I130J152D01*
G01X751783D01*
G03X751913Y249896I0J200D01*
G01X751914Y249897D01*
G02X753888I987J-1131D01*
G37*
G36*
G01X856250D02*
X856251Y249896D01*
G03X856381Y249848I130J152D01*
G01X856645D01*
G03X856775Y249896I0J200D01*
G01X856776Y249897D01*
G02X857763Y250267I987J-1131D01*
G02Y247263I0J-1502D01*
G02X856776Y247633I0J1501D01*
G01X856775D01*
Y247634D01*
G03X856645Y247682I-130J-152D01*
G01X856381D01*
G03X856251Y247634I0J-200D01*
G01X856250Y247633D01*
G02X854276I-987J1131D01*
G01X854275D01*
Y247634D01*
G03X854145Y247682I-130J-152D01*
G01X853881D01*
G03X853751Y247634I0J-200D01*
G01X853750Y247633D01*
G02X852763Y247263I-987J1131D01*
G02Y250267I0J1502D01*
G02X853750Y249897I0J-1501D01*
G01X853751D01*
Y249896D01*
G03X853881Y249848I130J152D01*
G01X854145D01*
G03X854275Y249896I0J200D01*
G01X854276Y249897D01*
G02X856250I987J-1131D01*
G37*
G36*
G01X1006250D02*
X1006251Y249896D01*
G03X1006381Y249848I130J152D01*
G01X1006645D01*
G03X1006775Y249896I0J200D01*
G01X1006776Y249897D01*
G02X1007763Y250267I987J-1131D01*
G02Y247263I0J-1502D01*
G02X1006776Y247633I0J1501D01*
G01X1006775D01*
Y247634D01*
G03X1006645Y247682I-130J-152D01*
G01X1006381D01*
G03X1006251Y247634I0J-200D01*
G01X1006250Y247633D01*
G02X1004276I-987J1131D01*
G01X1004275D01*
Y247634D01*
G03X1004145Y247682I-130J-152D01*
G01X1003881D01*
G03X1003751Y247634I0J-200D01*
G01X1003750Y247633D01*
G02X1002763Y247263I-987J1131D01*
G02Y250267I0J1502D01*
G02X1003750Y249897I0J-1501D01*
G01X1003751D01*
Y249896D01*
G03X1003881Y249848I130J152D01*
G01X1004145D01*
G03X1004275Y249896I0J200D01*
G01X1004276Y249897D01*
G02X1006250I987J-1131D01*
G37*
G36*
G01X1108612D02*
X1108613Y249896D01*
G03X1108743Y249848I130J152D01*
G01X1109007D01*
G03X1109137Y249896I0J200D01*
G01X1109138Y249897D01*
G02X1110125Y250267I987J-1131D01*
G02Y247263I0J-1502D01*
G02X1109138Y247633I0J1501D01*
G01X1109137D01*
Y247634D01*
G03X1109007Y247682I-130J-152D01*
G01X1108743D01*
G03X1108613Y247634I0J-200D01*
G01X1108612Y247633D01*
G02X1106638I-987J1131D01*
G01X1106637D01*
Y247634D01*
G03X1106507Y247682I-130J-152D01*
G01X1106243D01*
G03X1106113Y247634I0J-200D01*
G01X1106112Y247633D01*
G02X1105125Y247263I-987J1131D01*
G02Y250267I0J1502D01*
G02X1106112Y249897I0J-1501D01*
G01X1106113D01*
Y249896D01*
G03X1106243Y249848I130J152D01*
G01X1106507D01*
G03X1106637Y249896I0J200D01*
G01X1106638Y249897D01*
G02X1108612I987J-1131D01*
G37*
G36*
G01X1210974D02*
X1210975Y249896D01*
G03X1211105Y249848I130J152D01*
G01X1211369D01*
G03X1211499Y249896I0J200D01*
G01X1211500Y249897D01*
G02X1212487Y250267I987J-1131D01*
G02Y247263I0J-1502D01*
G02X1211500Y247633I0J1501D01*
G01X1211499D01*
Y247634D01*
G03X1211369Y247682I-130J-152D01*
G01X1211105D01*
G03X1210975Y247634I0J-200D01*
G01X1210974Y247633D01*
G02X1209000I-987J1131D01*
G01X1208999D01*
Y247634D01*
G03X1208869Y247682I-130J-152D01*
G01X1208605D01*
G03X1208475Y247634I0J-200D01*
G01X1208474Y247633D01*
G02X1207487Y247263I-987J1131D01*
G02Y250267I0J1502D01*
G02X1208474Y249897I0J-1501D01*
G01X1208475D01*
Y249896D01*
G03X1208605Y249848I130J152D01*
G01X1208869D01*
G03X1208999Y249896I0J200D01*
G01X1209000Y249897D01*
G02X1210974I987J-1131D01*
G37*
G36*
G01X1313336D02*
X1313337Y249896D01*
G03X1313467Y249848I130J152D01*
G01X1313731D01*
G03X1313861Y249896I0J200D01*
G01X1313862Y249897D01*
G02X1314849Y250267I987J-1131D01*
G02Y247263I0J-1502D01*
G02X1313862Y247633I0J1501D01*
G01X1313861D01*
Y247634D01*
G03X1313731Y247682I-130J-152D01*
G01X1313467D01*
G03X1313337Y247634I0J-200D01*
G01X1313336Y247633D01*
G02X1311362I-987J1131D01*
G01X1311361D01*
Y247634D01*
G03X1311231Y247682I-130J-152D01*
G01X1310967D01*
G03X1310837Y247634I0J-200D01*
G01X1310836Y247633D01*
G02X1309849Y247263I-987J1131D01*
G02Y250267I0J1502D01*
G02X1310836Y249897I0J-1501D01*
G01X1310837D01*
Y249896D01*
G03X1310967Y249848I130J152D01*
G01X1311231D01*
G03X1311361Y249896I0J200D01*
G01X1311362Y249897D01*
G02X1313336I987J-1131D01*
G37*
G36*
G01X1463337D02*
X1463338Y249896D01*
G03X1463468Y249848I130J152D01*
G01X1463732D01*
G03X1463862Y249896I0J200D01*
G01X1463863Y249897D01*
G02X1464850Y250267I987J-1131D01*
G02Y247263I0J-1502D01*
G02X1463863Y247633I0J1501D01*
G01X1463862D01*
Y247634D01*
G03X1463732Y247682I-130J-152D01*
G01X1463468D01*
G03X1463338Y247634I0J-200D01*
G01X1463337Y247633D01*
G02X1461363I-987J1131D01*
G01X1461362D01*
Y247634D01*
G03X1461232Y247682I-130J-152D01*
G01X1460968D01*
G03X1460838Y247634I0J-200D01*
G01X1460837Y247633D01*
G02X1459850Y247263I-987J1131D01*
G02Y250267I0J1502D01*
G02X1460837Y249897I0J-1501D01*
G01X1460838D01*
Y249896D01*
G03X1460968Y249848I130J152D01*
G01X1461232D01*
G03X1461362Y249896I0J200D01*
G01X1461363Y249897D01*
G02X1463337I987J-1131D01*
G37*
G36*
G01X1565699D02*
X1565700Y249896D01*
G03X1565830Y249848I130J152D01*
G01X1566094D01*
G03X1566224Y249896I0J200D01*
G01X1566225Y249897D01*
G02X1567212Y250267I987J-1131D01*
G02Y247263I0J-1502D01*
G02X1566225Y247633I0J1501D01*
G01X1566224D01*
Y247634D01*
G03X1566094Y247682I-130J-152D01*
G01X1565830D01*
G03X1565700Y247634I0J-200D01*
G01X1565699Y247633D01*
G02X1563725I-987J1131D01*
G01X1563724D01*
Y247634D01*
G03X1563594Y247682I-130J-152D01*
G01X1563330D01*
G03X1563200Y247634I0J-200D01*
G01X1563199Y247633D01*
G02X1562212Y247263I-987J1131D01*
G02Y250267I0J1502D01*
G02X1563199Y249897I0J-1501D01*
G01X1563200D01*
Y249896D01*
G03X1563330Y249848I130J152D01*
G01X1563594D01*
G03X1563724Y249896I0J200D01*
G01X1563725Y249897D01*
G02X1565699I987J-1131D01*
G37*
G36*
G01X1668061D02*
X1668062Y249896D01*
G03X1668192Y249848I130J152D01*
G01X1668456D01*
G03X1668586Y249896I0J200D01*
G01X1668587Y249897D01*
G02X1669574Y250267I987J-1131D01*
G02Y247263I0J-1502D01*
G02X1668587Y247633I0J1501D01*
G01X1668586D01*
Y247634D01*
G03X1668456Y247682I-130J-152D01*
G01X1668192D01*
G03X1668062Y247634I0J-200D01*
G01X1668061Y247633D01*
G02X1666087I-987J1131D01*
G01X1666086D01*
Y247634D01*
G03X1665956Y247682I-130J-152D01*
G01X1665692D01*
G03X1665562Y247634I0J-200D01*
G01X1665561Y247633D01*
G02X1664574Y247263I-987J1131D01*
G02Y250267I0J1502D01*
G02X1665561Y249897I0J-1501D01*
G01X1665562D01*
Y249896D01*
G03X1665692Y249848I130J152D01*
G01X1665956D01*
G03X1666086Y249896I0J200D01*
G01X1666087Y249897D01*
G02X1668061I987J-1131D01*
G37*
G36*
G01X1770423D02*
X1770424Y249896D01*
G03X1770554Y249848I130J152D01*
G01X1770818D01*
G03X1770948Y249896I0J200D01*
G01X1770949Y249897D01*
G02X1771936Y250267I987J-1131D01*
G02Y247263I0J-1502D01*
G02X1770949Y247633I0J1501D01*
G01X1770948D01*
Y247634D01*
G03X1770818Y247682I-130J-152D01*
G01X1770554D01*
G03X1770424Y247634I0J-200D01*
G01X1770423Y247633D01*
G02X1768449I-987J1131D01*
G01X1768448D01*
Y247634D01*
G03X1768318Y247682I-130J-152D01*
G01X1768054D01*
G03X1767924Y247634I0J-200D01*
G01X1767923Y247633D01*
G02X1766936Y247263I-987J1131D01*
G02Y250267I0J1502D01*
G02X1767923Y249897I0J-1501D01*
G01X1767924D01*
Y249896D01*
G03X1768054Y249848I130J152D01*
G01X1768318D01*
G03X1768448Y249896I0J200D01*
G01X1768449Y249897D01*
G02X1770423I987J-1131D01*
G37*
G36*
G01X72328Y250023D02*
X72329Y250022D01*
G03X72459Y249974I130J152D01*
G01X72723D01*
G03X72853Y250022I0J200D01*
G01X72854Y250023D01*
G02X73841Y250393I987J-1131D01*
G02Y247389I0J-1502D01*
G02X72854Y247759I0J1501D01*
G01X72853D01*
Y247760D01*
G03X72723Y247808I-130J-152D01*
G01X72459D01*
G03X72329Y247760I0J-200D01*
G01X72328Y247759D01*
G02X70354I-987J1131D01*
G01X70353D01*
Y247760D01*
G03X70223Y247808I-130J-152D01*
G01X69959D01*
G03X69829Y247760I0J-200D01*
G01X69828Y247759D01*
G02X68841Y247389I-987J1131D01*
G02Y250393I0J1502D01*
G02X69828Y250023I0J-1501D01*
G01X69829D01*
Y250022D01*
G03X69959Y249974I130J152D01*
G01X70223D01*
G03X70353Y250022I0J200D01*
G01X70354Y250023D01*
G02X72328I987J-1131D01*
G37*
G36*
G01X174690D02*
X174691Y250022D01*
G03X174821Y249974I130J152D01*
G01X175085D01*
G03X175215Y250022I0J200D01*
G01X175216Y250023D01*
G02X176203Y250393I987J-1131D01*
G02Y247389I0J-1502D01*
G02X175216Y247759I0J1501D01*
G01X175215D01*
Y247760D01*
G03X175085Y247808I-130J-152D01*
G01X174821D01*
G03X174691Y247760I0J-200D01*
G01X174690Y247759D01*
G02X172716I-987J1131D01*
G01X172715D01*
Y247760D01*
G03X172585Y247808I-130J-152D01*
G01X172321D01*
G03X172191Y247760I0J-200D01*
G01X172190Y247759D01*
G02X171203Y247389I-987J1131D01*
G02Y250393I0J1502D01*
G02X172190Y250023I0J-1501D01*
G01X172191D01*
Y250022D01*
G03X172321Y249974I130J152D01*
G01X172585D01*
G03X172715Y250022I0J200D01*
G01X172716Y250023D01*
G02X174690I987J-1131D01*
G37*
G36*
G01X277052D02*
X277053Y250022D01*
G03X277183Y249974I130J152D01*
G01X277447D01*
G03X277577Y250022I0J200D01*
G01X277578Y250023D01*
G02X278565Y250393I987J-1131D01*
G02Y247389I0J-1502D01*
G02X277578Y247759I0J1501D01*
G01X277577D01*
Y247760D01*
G03X277447Y247808I-130J-152D01*
G01X277183D01*
G03X277053Y247760I0J-200D01*
G01X277052Y247759D01*
G02X275078I-987J1131D01*
G01X275077D01*
Y247760D01*
G03X274947Y247808I-130J-152D01*
G01X274683D01*
G03X274553Y247760I0J-200D01*
G01X274552Y247759D01*
G02X273565Y247389I-987J1131D01*
G02Y250393I0J1502D01*
G02X274552Y250023I0J-1501D01*
G01X274553D01*
Y250022D01*
G03X274683Y249974I130J152D01*
G01X274947D01*
G03X275077Y250022I0J200D01*
G01X275078Y250023D01*
G02X277052I987J-1131D01*
G37*
G36*
G01X379414D02*
X379415Y250022D01*
G03X379545Y249974I130J152D01*
G01X379809D01*
G03X379939Y250022I0J200D01*
G01X379940Y250023D01*
G02X380927Y250393I987J-1131D01*
G02Y247389I0J-1502D01*
G02X379940Y247759I0J1501D01*
G01X379939D01*
Y247760D01*
G03X379809Y247808I-130J-152D01*
G01X379545D01*
G03X379415Y247760I0J-200D01*
G01X379414Y247759D01*
G02X377440I-987J1131D01*
G01X377439D01*
Y247760D01*
G03X377309Y247808I-130J-152D01*
G01X377045D01*
G03X376915Y247760I0J-200D01*
G01X376914Y247759D01*
G02X375927Y247389I-987J1131D01*
G02Y250393I0J1502D01*
G02X376914Y250023I0J-1501D01*
G01X376915D01*
Y250022D01*
G03X377045Y249974I130J152D01*
G01X377309D01*
G03X377439Y250022I0J200D01*
G01X377440Y250023D01*
G02X379414I987J-1131D01*
G37*
G36*
G01X529415D02*
X529416Y250022D01*
G03X529546Y249974I130J152D01*
G01X529810D01*
G03X529940Y250022I0J200D01*
G01X529941Y250023D01*
G02X530928Y250393I987J-1131D01*
G02Y247389I0J-1502D01*
G02X529941Y247759I0J1501D01*
G01X529940D01*
Y247760D01*
G03X529810Y247808I-130J-152D01*
G01X529546D01*
G03X529416Y247760I0J-200D01*
G01X529415Y247759D01*
G02X527441I-987J1131D01*
G01X527440D01*
Y247760D01*
G03X527310Y247808I-130J-152D01*
G01X527046D01*
G03X526916Y247760I0J-200D01*
G01X526915Y247759D01*
G02X525928Y247389I-987J1131D01*
G02Y250393I0J1502D01*
G02X526915Y250023I0J-1501D01*
G01X526916D01*
Y250022D01*
G03X527046Y249974I130J152D01*
G01X527310D01*
G03X527440Y250022I0J200D01*
G01X527441Y250023D01*
G02X529415I987J-1131D01*
G37*
G36*
G01X631777D02*
X631778Y250022D01*
G03X631908Y249974I130J152D01*
G01X632172D01*
G03X632302Y250022I0J200D01*
G01X632303Y250023D01*
G02X633290Y250393I987J-1131D01*
G02Y247389I0J-1502D01*
G02X632303Y247759I0J1501D01*
G01X632302D01*
Y247760D01*
G03X632172Y247808I-130J-152D01*
G01X631908D01*
G03X631778Y247760I0J-200D01*
G01X631777Y247759D01*
G02X629803I-987J1131D01*
G01X629802D01*
Y247760D01*
G03X629672Y247808I-130J-152D01*
G01X629408D01*
G03X629278Y247760I0J-200D01*
G01X629277Y247759D01*
G02X628290Y247389I-987J1131D01*
G02Y250393I0J1502D01*
G02X629277Y250023I0J-1501D01*
G01X629278D01*
Y250022D01*
G03X629408Y249974I130J152D01*
G01X629672D01*
G03X629802Y250022I0J200D01*
G01X629803Y250023D01*
G02X631777I987J-1131D01*
G37*
G36*
G01X734139D02*
X734140Y250022D01*
G03X734270Y249974I130J152D01*
G01X734534D01*
G03X734664Y250022I0J200D01*
G01X734665Y250023D01*
G02X735652Y250393I987J-1131D01*
G02Y247389I0J-1502D01*
G02X734665Y247759I0J1501D01*
G01X734664D01*
Y247760D01*
G03X734534Y247808I-130J-152D01*
G01X734270D01*
G03X734140Y247760I0J-200D01*
G01X734139Y247759D01*
G02X732165I-987J1131D01*
G01X732164D01*
Y247760D01*
G03X732034Y247808I-130J-152D01*
G01X731770D01*
G03X731640Y247760I0J-200D01*
G01X731639Y247759D01*
G02X730652Y247389I-987J1131D01*
G02Y250393I0J1502D01*
G02X731639Y250023I0J-1501D01*
G01X731640D01*
Y250022D01*
G03X731770Y249974I130J152D01*
G01X732034D01*
G03X732164Y250022I0J200D01*
G01X732165Y250023D01*
G02X734139I987J-1131D01*
G37*
G36*
G01X836501D02*
X836502Y250022D01*
G03X836632Y249974I130J152D01*
G01X836896D01*
G03X837026Y250022I0J200D01*
G01X837027Y250023D01*
G02X838014Y250393I987J-1131D01*
G02Y247389I0J-1502D01*
G02X837027Y247759I0J1501D01*
G01X837026D01*
Y247760D01*
G03X836896Y247808I-130J-152D01*
G01X836632D01*
G03X836502Y247760I0J-200D01*
G01X836501Y247759D01*
G02X834527I-987J1131D01*
G01X834526D01*
Y247760D01*
G03X834396Y247808I-130J-152D01*
G01X834132D01*
G03X834002Y247760I0J-200D01*
G01X834001Y247759D01*
G02X833014Y247389I-987J1131D01*
G02Y250393I0J1502D01*
G02X834001Y250023I0J-1501D01*
G01X834002D01*
Y250022D01*
G03X834132Y249974I130J152D01*
G01X834396D01*
G03X834526Y250022I0J200D01*
G01X834527Y250023D01*
G02X836501I987J-1131D01*
G37*
G36*
G01X986501D02*
X986502Y250022D01*
G03X986632Y249974I130J152D01*
G01X986896D01*
G03X987026Y250022I0J200D01*
G01X987027Y250023D01*
G02X988014Y250393I987J-1131D01*
G02Y247389I0J-1502D01*
G02X987027Y247759I0J1501D01*
G01X987026D01*
Y247760D01*
G03X986896Y247808I-130J-152D01*
G01X986632D01*
G03X986502Y247760I0J-200D01*
G01X986501Y247759D01*
G02X984527I-987J1131D01*
G01X984526D01*
Y247760D01*
G03X984396Y247808I-130J-152D01*
G01X984132D01*
G03X984002Y247760I0J-200D01*
G01X984001Y247759D01*
G02X983014Y247389I-987J1131D01*
G02Y250393I0J1502D01*
G02X984001Y250023I0J-1501D01*
G01X984002D01*
Y250022D01*
G03X984132Y249974I130J152D01*
G01X984396D01*
G03X984526Y250022I0J200D01*
G01X984527Y250023D01*
G02X986501I987J-1131D01*
G37*
G36*
G01X1088863D02*
X1088864Y250022D01*
G03X1088994Y249974I130J152D01*
G01X1089258D01*
G03X1089388Y250022I0J200D01*
G01X1089389Y250023D01*
G02X1090376Y250393I987J-1131D01*
G02Y247389I0J-1502D01*
G02X1089389Y247759I0J1501D01*
G01X1089388D01*
Y247760D01*
G03X1089258Y247808I-130J-152D01*
G01X1088994D01*
G03X1088864Y247760I0J-200D01*
G01X1088863Y247759D01*
G02X1086889I-987J1131D01*
G01X1086888D01*
Y247760D01*
G03X1086758Y247808I-130J-152D01*
G01X1086494D01*
G03X1086364Y247760I0J-200D01*
G01X1086363Y247759D01*
G02X1085376Y247389I-987J1131D01*
G02Y250393I0J1502D01*
G02X1086363Y250023I0J-1501D01*
G01X1086364D01*
Y250022D01*
G03X1086494Y249974I130J152D01*
G01X1086758D01*
G03X1086888Y250022I0J200D01*
G01X1086889Y250023D01*
G02X1088863I987J-1131D01*
G37*
G36*
G01X1191225D02*
X1191226Y250022D01*
G03X1191356Y249974I130J152D01*
G01X1191620D01*
G03X1191750Y250022I0J200D01*
G01X1191751Y250023D01*
G02X1192738Y250393I987J-1131D01*
G02Y247389I0J-1502D01*
G02X1191751Y247759I0J1501D01*
G01X1191750D01*
Y247760D01*
G03X1191620Y247808I-130J-152D01*
G01X1191356D01*
G03X1191226Y247760I0J-200D01*
G01X1191225Y247759D01*
G02X1189251I-987J1131D01*
G01X1189250D01*
Y247760D01*
G03X1189120Y247808I-130J-152D01*
G01X1188856D01*
G03X1188726Y247760I0J-200D01*
G01X1188725Y247759D01*
G02X1187738Y247389I-987J1131D01*
G02Y250393I0J1502D01*
G02X1188725Y250023I0J-1501D01*
G01X1188726D01*
Y250022D01*
G03X1188856Y249974I130J152D01*
G01X1189120D01*
G03X1189250Y250022I0J200D01*
G01X1189251Y250023D01*
G02X1191225I987J-1131D01*
G37*
G36*
G01X1293587D02*
X1293588Y250022D01*
G03X1293718Y249974I130J152D01*
G01X1293982D01*
G03X1294112Y250022I0J200D01*
G01X1294113Y250023D01*
G02X1295100Y250393I987J-1131D01*
G02Y247389I0J-1502D01*
G02X1294113Y247759I0J1501D01*
G01X1294112D01*
Y247760D01*
G03X1293982Y247808I-130J-152D01*
G01X1293718D01*
G03X1293588Y247760I0J-200D01*
G01X1293587Y247759D01*
G02X1291613I-987J1131D01*
G01X1291612D01*
Y247760D01*
G03X1291482Y247808I-130J-152D01*
G01X1291218D01*
G03X1291088Y247760I0J-200D01*
G01X1291087Y247759D01*
G02X1290100Y247389I-987J1131D01*
G02Y250393I0J1502D01*
G02X1291087Y250023I0J-1501D01*
G01X1291088D01*
Y250022D01*
G03X1291218Y249974I130J152D01*
G01X1291482D01*
G03X1291612Y250022I0J200D01*
G01X1291613Y250023D01*
G02X1293587I987J-1131D01*
G37*
G36*
G01X1443588D02*
X1443589Y250022D01*
G03X1443719Y249974I130J152D01*
G01X1443983D01*
G03X1444113Y250022I0J200D01*
G01X1444114Y250023D01*
G02X1445101Y250393I987J-1131D01*
G02Y247389I0J-1502D01*
G02X1444114Y247759I0J1501D01*
G01X1444113D01*
Y247760D01*
G03X1443983Y247808I-130J-152D01*
G01X1443719D01*
G03X1443589Y247760I0J-200D01*
G01X1443588Y247759D01*
G02X1441614I-987J1131D01*
G01X1441613D01*
Y247760D01*
G03X1441483Y247808I-130J-152D01*
G01X1441219D01*
G03X1441089Y247760I0J-200D01*
G01X1441088Y247759D01*
G02X1440101Y247389I-987J1131D01*
G02Y250393I0J1502D01*
G02X1441088Y250023I0J-1501D01*
G01X1441089D01*
Y250022D01*
G03X1441219Y249974I130J152D01*
G01X1441483D01*
G03X1441613Y250022I0J200D01*
G01X1441614Y250023D01*
G02X1443588I987J-1131D01*
G37*
G36*
G01X1545950D02*
X1545951Y250022D01*
G03X1546081Y249974I130J152D01*
G01X1546345D01*
G03X1546475Y250022I0J200D01*
G01X1546476Y250023D01*
G02X1547463Y250393I987J-1131D01*
G02Y247389I0J-1502D01*
G02X1546476Y247759I0J1501D01*
G01X1546475D01*
Y247760D01*
G03X1546345Y247808I-130J-152D01*
G01X1546081D01*
G03X1545951Y247760I0J-200D01*
G01X1545950Y247759D01*
G02X1543976I-987J1131D01*
G01X1543975D01*
Y247760D01*
G03X1543845Y247808I-130J-152D01*
G01X1543581D01*
G03X1543451Y247760I0J-200D01*
G01X1543450Y247759D01*
G02X1542463Y247389I-987J1131D01*
G02Y250393I0J1502D01*
G02X1543450Y250023I0J-1501D01*
G01X1543451D01*
Y250022D01*
G03X1543581Y249974I130J152D01*
G01X1543845D01*
G03X1543975Y250022I0J200D01*
G01X1543976Y250023D01*
G02X1545950I987J-1131D01*
G37*
G36*
G01X1648312D02*
X1648313Y250022D01*
G03X1648443Y249974I130J152D01*
G01X1648707D01*
G03X1648837Y250022I0J200D01*
G01X1648838Y250023D01*
G02X1649825Y250393I987J-1131D01*
G02Y247389I0J-1502D01*
G02X1648838Y247759I0J1501D01*
G01X1648837D01*
Y247760D01*
G03X1648707Y247808I-130J-152D01*
G01X1648443D01*
G03X1648313Y247760I0J-200D01*
G01X1648312Y247759D01*
G02X1646338I-987J1131D01*
G01X1646337D01*
Y247760D01*
G03X1646207Y247808I-130J-152D01*
G01X1645943D01*
G03X1645813Y247760I0J-200D01*
G01X1645812Y247759D01*
G02X1644825Y247389I-987J1131D01*
G02Y250393I0J1502D01*
G02X1645812Y250023I0J-1501D01*
G01X1645813D01*
Y250022D01*
G03X1645943Y249974I130J152D01*
G01X1646207D01*
G03X1646337Y250022I0J200D01*
G01X1646338Y250023D01*
G02X1648312I987J-1131D01*
G37*
G36*
G01X1750674D02*
X1750675Y250022D01*
G03X1750805Y249974I130J152D01*
G01X1751069D01*
G03X1751199Y250022I0J200D01*
G01X1751200Y250023D01*
G02X1752187Y250393I987J-1131D01*
G02Y247389I0J-1502D01*
G02X1751200Y247759I0J1501D01*
G01X1751199D01*
Y247760D01*
G03X1751069Y247808I-130J-152D01*
G01X1750805D01*
G03X1750675Y247760I0J-200D01*
G01X1750674Y247759D01*
G02X1748700I-987J1131D01*
G01X1748699D01*
Y247760D01*
G03X1748569Y247808I-130J-152D01*
G01X1748305D01*
G03X1748175Y247760I0J-200D01*
G01X1748174Y247759D01*
G02X1747187Y247389I-987J1131D01*
G02Y250393I0J1502D01*
G02X1748174Y250023I0J-1501D01*
G01X1748175D01*
Y250022D01*
G03X1748305Y249974I130J152D01*
G01X1748569D01*
G03X1748699Y250022I0J200D01*
G01X1748700Y250023D01*
G02X1750674I987J-1131D01*
G37*
G36*
G01X884082Y255118D02*
G02X887686I1802J0D01*
G01Y255117D01*
G02X887168Y253853I-1802J0D01*
G01X887138Y253823D01*
X887108Y253744D01*
X887130Y253362D01*
X887169Y253287D01*
X887202Y253261D01*
G02X887763Y252090I-942J-1171D01*
G02X887649Y251516I-1502J0D01*
G03X887647Y251514I129J-131D01*
G01Y251513D01*
G03X887645Y251370I186J-74D01*
G01X887752Y251079D01*
X887802Y251023D01*
X887835Y251006D01*
G02X888650Y249670I-688J-1336D01*
G02X885646I-1502J0D01*
G02X885760Y250244I1502J0D01*
G03X885762Y250246I-129J131D01*
G01Y250247D01*
G03X885764Y250390I-186J74D01*
G01X885657Y250681D01*
X885607Y250737D01*
X885574Y250754D01*
G02X884759Y252090I688J1336D01*
G02X885062Y252994I1502J-1D01*
G01X885087Y253028D01*
X885106Y253110D01*
X885035Y253486D01*
X884987Y253555D01*
X884950Y253577D01*
G02X884082Y255118I934J1541D01*
G37*
G36*
G01X71656Y231786D02*
G02X74660I1502J0D01*
G02X74290Y230799I-1501J0D01*
G01Y230798D01*
X74289D01*
G03X74241Y230668I152J-130D01*
G01Y230404D01*
G03X74289Y230274I200J0D01*
G01X74290Y230273D01*
G02X74660Y229286I-1131J-987D01*
G02X73422Y227807I-1502J0D01*
G01X73371Y227798D01*
X73292Y227734D01*
X73125Y227326D01*
X73137Y227225D01*
X73166Y227183D01*
G02X73498Y226141I-1469J-1042D01*
G02X71696Y224339I-1802J0D01*
G01X71695D01*
G02X70370Y224920I0J1802D01*
G01X70344Y224948D01*
X70277Y224981D01*
X69968Y225006D01*
G03X69828Y224963I-15J-199D01*
G02X68896Y224639I-932J1178D01*
G02Y227643I0J1502D01*
G02X69828Y227319I0J-1502D01*
G03X69968Y227276I125J156D01*
G01X70277Y227301D01*
X70344Y227334D01*
X70370Y227362D01*
G02X71544Y227937I1326J-1221D01*
G03X71705Y228044I-16J199D01*
G01X71885Y228389D01*
X71883Y228490D01*
X71857Y228535D01*
G02X71656Y229285I1301J751D01*
G01Y229286D01*
G02X72026Y230273I1501J0D01*
G01Y230274D01*
X72027D01*
G03X72075Y230404I-152J130D01*
G01Y230668D01*
G03X72027Y230798I-200J0D01*
G01X72026Y230799D01*
G02X71656Y231786I1131J987D01*
G37*
G36*
G01X174018D02*
G02X177022I1502J0D01*
G02X176652Y230799I-1501J0D01*
G01Y230798D01*
X176651D01*
G03X176603Y230668I152J-130D01*
G01Y230404D01*
G03X176651Y230274I200J0D01*
G01X176652Y230273D01*
G02X177022Y229286I-1131J-987D01*
G02X175784Y227807I-1502J0D01*
G01X175733Y227798D01*
X175654Y227734D01*
X175487Y227326D01*
X175499Y227225D01*
X175528Y227183D01*
G02X175860Y226141I-1469J-1042D01*
G02X174058Y224339I-1802J0D01*
G01X174057D01*
G02X172732Y224920I0J1802D01*
G01X172706Y224948D01*
X172639Y224981D01*
X172330Y225006D01*
G03X172190Y224963I-15J-199D01*
G02X171258Y224639I-932J1178D01*
G02Y227643I0J1502D01*
G02X172190Y227319I0J-1502D01*
G03X172330Y227276I125J156D01*
G01X172639Y227301D01*
X172706Y227334D01*
X172732Y227362D01*
G02X173906Y227937I1326J-1221D01*
G03X174067Y228044I-16J199D01*
G01X174247Y228389D01*
X174245Y228490D01*
X174219Y228535D01*
G02X174018Y229285I1301J751D01*
G01Y229286D01*
G02X174388Y230273I1501J0D01*
G01Y230274D01*
X174389D01*
G03X174437Y230404I-152J130D01*
G01Y230668D01*
G03X174389Y230798I-200J0D01*
G01X174388Y230799D01*
G02X174018Y231786I1131J987D01*
G37*
G36*
G01X276380D02*
G02X279384I1502J0D01*
G02X279014Y230799I-1501J0D01*
G01Y230798D01*
X279013D01*
G03X278965Y230668I152J-130D01*
G01Y230404D01*
G03X279013Y230274I200J0D01*
G01X279014Y230273D01*
G02X279384Y229286I-1131J-987D01*
G02X278146Y227807I-1502J0D01*
G01X278095Y227798D01*
X278016Y227734D01*
X277849Y227326D01*
X277861Y227225D01*
X277890Y227183D01*
G02X278222Y226141I-1469J-1042D01*
G02X276420Y224339I-1802J0D01*
G01X276419D01*
G02X275094Y224920I0J1802D01*
G01X275068Y224948D01*
X275001Y224981D01*
X274692Y225006D01*
G03X274552Y224963I-15J-199D01*
G02X273620Y224639I-932J1178D01*
G02Y227643I0J1502D01*
G02X274552Y227319I0J-1502D01*
G03X274692Y227276I125J156D01*
G01X275001Y227301D01*
X275068Y227334D01*
X275094Y227362D01*
G02X276268Y227937I1326J-1221D01*
G03X276429Y228044I-16J199D01*
G01X276609Y228389D01*
X276607Y228490D01*
X276581Y228535D01*
G02X276380Y229285I1301J751D01*
G01Y229286D01*
G02X276750Y230273I1501J0D01*
G01Y230274D01*
X276751D01*
G03X276799Y230404I-152J130D01*
G01Y230668D01*
G03X276751Y230798I-200J0D01*
G01X276750Y230799D01*
G02X276380Y231786I1131J987D01*
G37*
G36*
G01X378742D02*
G02X381746I1502J0D01*
G02X381376Y230799I-1501J0D01*
G01Y230798D01*
X381375D01*
G03X381327Y230668I152J-130D01*
G01Y230404D01*
G03X381375Y230274I200J0D01*
G01X381376Y230273D01*
G02X381746Y229286I-1131J-987D01*
G02X380508Y227807I-1502J0D01*
G01X380457Y227798D01*
X380378Y227734D01*
X380211Y227326D01*
X380223Y227225D01*
X380252Y227183D01*
G02X380584Y226141I-1469J-1042D01*
G02X378782Y224339I-1802J0D01*
G01X378781D01*
G02X377456Y224920I0J1802D01*
G01X377430Y224948D01*
X377363Y224981D01*
X377054Y225006D01*
G03X376914Y224963I-15J-199D01*
G02X375982Y224639I-932J1178D01*
G02Y227643I0J1502D01*
G02X376914Y227319I0J-1502D01*
G03X377054Y227276I125J156D01*
G01X377363Y227301D01*
X377430Y227334D01*
X377456Y227362D01*
G02X378630Y227937I1326J-1221D01*
G03X378791Y228044I-16J199D01*
G01X378971Y228389D01*
X378969Y228490D01*
X378943Y228535D01*
G02X378742Y229285I1301J751D01*
G01Y229286D01*
G02X379112Y230273I1501J0D01*
G01Y230274D01*
X379113D01*
G03X379161Y230404I-152J130D01*
G01Y230668D01*
G03X379113Y230798I-200J0D01*
G01X379112Y230799D01*
G02X378742Y231786I1131J987D01*
G37*
G36*
G01X528743D02*
G02X531747I1502J0D01*
G02X531377Y230799I-1501J0D01*
G01Y230798D01*
X531376D01*
G03X531328Y230668I152J-130D01*
G01Y230404D01*
G03X531376Y230274I200J0D01*
G01X531377Y230273D01*
G02X531747Y229286I-1131J-987D01*
G02X530509Y227807I-1502J0D01*
G01X530458Y227798D01*
X530379Y227734D01*
X530212Y227326D01*
X530224Y227225D01*
X530253Y227183D01*
G02X530585Y226141I-1469J-1042D01*
G02X528783Y224339I-1802J0D01*
G01X528782D01*
G02X527457Y224920I0J1802D01*
G01X527431Y224948D01*
X527364Y224981D01*
X527055Y225006D01*
G03X526915Y224963I-15J-199D01*
G02X525983Y224639I-932J1178D01*
G02Y227643I0J1502D01*
G02X526915Y227319I0J-1502D01*
G03X527055Y227276I125J156D01*
G01X527364Y227301D01*
X527431Y227334D01*
X527457Y227362D01*
G02X528631Y227937I1326J-1221D01*
G03X528792Y228044I-16J199D01*
G01X528972Y228389D01*
X528970Y228490D01*
X528944Y228535D01*
G02X528743Y229285I1301J751D01*
G01Y229286D01*
G02X529113Y230273I1501J0D01*
G01Y230274D01*
X529114D01*
G03X529162Y230404I-152J130D01*
G01Y230668D01*
G03X529114Y230798I-200J0D01*
G01X529113Y230799D01*
G02X528743Y231786I1131J987D01*
G37*
G36*
G01X631105D02*
G02X634109I1502J0D01*
G02X633739Y230799I-1501J0D01*
G01Y230798D01*
X633738D01*
G03X633690Y230668I152J-130D01*
G01Y230404D01*
G03X633738Y230274I200J0D01*
G01X633739Y230273D01*
G02X634109Y229286I-1131J-987D01*
G02X632871Y227807I-1502J0D01*
G01X632820Y227798D01*
X632741Y227734D01*
X632574Y227326D01*
X632586Y227225D01*
X632615Y227183D01*
G02X632947Y226141I-1469J-1042D01*
G02X631145Y224339I-1802J0D01*
G01X631144D01*
G02X629819Y224920I0J1802D01*
G01X629793Y224948D01*
X629726Y224981D01*
X629417Y225006D01*
G03X629277Y224963I-15J-199D01*
G02X628345Y224639I-932J1178D01*
G02Y227643I0J1502D01*
G02X629277Y227319I0J-1502D01*
G03X629417Y227276I125J156D01*
G01X629726Y227301D01*
X629793Y227334D01*
X629819Y227362D01*
G02X630993Y227937I1326J-1221D01*
G03X631154Y228044I-16J199D01*
G01X631334Y228389D01*
X631332Y228490D01*
X631306Y228535D01*
G02X631105Y229285I1301J751D01*
G01Y229286D01*
G02X631475Y230273I1501J0D01*
G01Y230274D01*
X631476D01*
G03X631524Y230404I-152J130D01*
G01Y230668D01*
G03X631476Y230798I-200J0D01*
G01X631475Y230799D01*
G02X631105Y231786I1131J987D01*
G37*
G36*
G01X733467D02*
G02X736471I1502J0D01*
G02X736101Y230799I-1501J0D01*
G01Y230798D01*
X736100D01*
G03X736052Y230668I152J-130D01*
G01Y230404D01*
G03X736100Y230274I200J0D01*
G01X736101Y230273D01*
G02X736471Y229286I-1131J-987D01*
G02X735233Y227807I-1502J0D01*
G01X735182Y227798D01*
X735103Y227734D01*
X734936Y227326D01*
X734948Y227225D01*
X734977Y227183D01*
G02X735309Y226141I-1469J-1042D01*
G02X733507Y224339I-1802J0D01*
G01X733506D01*
G02X732181Y224920I0J1802D01*
G01X732155Y224948D01*
X732088Y224981D01*
X731779Y225006D01*
G03X731639Y224963I-15J-199D01*
G02X730707Y224639I-932J1178D01*
G02Y227643I0J1502D01*
G02X731639Y227319I0J-1502D01*
G03X731779Y227276I125J156D01*
G01X732088Y227301D01*
X732155Y227334D01*
X732181Y227362D01*
G02X733355Y227937I1326J-1221D01*
G03X733516Y228044I-16J199D01*
G01X733696Y228389D01*
X733694Y228490D01*
X733668Y228535D01*
G02X733467Y229285I1301J751D01*
G01Y229286D01*
G02X733837Y230273I1501J0D01*
G01Y230274D01*
X733838D01*
G03X733886Y230404I-152J130D01*
G01Y230668D01*
G03X733838Y230798I-200J0D01*
G01X733837Y230799D01*
G02X733467Y231786I1131J987D01*
G37*
G36*
G01X835829D02*
G02X838833I1502J0D01*
G02X838463Y230799I-1501J0D01*
G01Y230798D01*
X838462D01*
G03X838414Y230668I152J-130D01*
G01Y230404D01*
G03X838462Y230274I200J0D01*
G01X838463Y230273D01*
G02X838833Y229286I-1131J-987D01*
G02X837595Y227807I-1502J0D01*
G01X837544Y227798D01*
X837465Y227734D01*
X837298Y227326D01*
X837310Y227225D01*
X837339Y227183D01*
G02X837671Y226141I-1469J-1042D01*
G02X835869Y224339I-1802J0D01*
G01X835868D01*
G02X834543Y224920I0J1802D01*
G01X834517Y224948D01*
X834450Y224981D01*
X834141Y225006D01*
G03X834001Y224963I-15J-199D01*
G02X833069Y224639I-932J1178D01*
G02Y227643I0J1502D01*
G02X834001Y227319I0J-1502D01*
G03X834141Y227276I125J156D01*
G01X834450Y227301D01*
X834517Y227334D01*
X834543Y227362D01*
G02X835717Y227937I1326J-1221D01*
G03X835878Y228044I-16J199D01*
G01X836058Y228389D01*
X836056Y228490D01*
X836030Y228535D01*
G02X835829Y229285I1301J751D01*
G01Y229286D01*
G02X836199Y230273I1501J0D01*
G01Y230274D01*
X836200D01*
G03X836248Y230404I-152J130D01*
G01Y230668D01*
G03X836200Y230798I-200J0D01*
G01X836199Y230799D01*
G02X835829Y231786I1131J987D01*
G37*
G36*
G01X985829D02*
G02X988833I1502J0D01*
G02X988463Y230799I-1501J0D01*
G01Y230798D01*
X988462D01*
G03X988414Y230668I152J-130D01*
G01Y230404D01*
G03X988462Y230274I200J0D01*
G01X988463Y230273D01*
G02X988833Y229286I-1131J-987D01*
G02X987595Y227807I-1502J0D01*
G01X987544Y227798D01*
X987465Y227734D01*
X987298Y227326D01*
X987310Y227225D01*
X987339Y227183D01*
G02X987671Y226141I-1469J-1042D01*
G02X985869Y224339I-1802J0D01*
G01X985868D01*
G02X984543Y224920I0J1802D01*
G01X984517Y224948D01*
X984450Y224981D01*
X984141Y225006D01*
G03X984001Y224963I-15J-199D01*
G02X983069Y224639I-932J1178D01*
G02Y227643I0J1502D01*
G02X984001Y227319I0J-1502D01*
G03X984141Y227276I125J156D01*
G01X984450Y227301D01*
X984517Y227334D01*
X984543Y227362D01*
G02X985717Y227937I1326J-1221D01*
G03X985878Y228044I-16J199D01*
G01X986058Y228389D01*
X986056Y228490D01*
X986030Y228535D01*
G02X985829Y229285I1301J751D01*
G01Y229286D01*
G02X986199Y230273I1501J0D01*
G01Y230274D01*
X986200D01*
G03X986248Y230404I-152J130D01*
G01Y230668D01*
G03X986200Y230798I-200J0D01*
G01X986199Y230799D01*
G02X985829Y231786I1131J987D01*
G37*
G36*
G01X1088191D02*
G02X1091195I1502J0D01*
G02X1090825Y230799I-1501J0D01*
G01Y230798D01*
X1090824D01*
G03X1090776Y230668I152J-130D01*
G01Y230404D01*
G03X1090824Y230274I200J0D01*
G01X1090825Y230273D01*
G02X1091195Y229286I-1131J-987D01*
G02X1089957Y227807I-1502J0D01*
G01X1089906Y227798D01*
X1089827Y227734D01*
X1089660Y227326D01*
X1089672Y227225D01*
X1089701Y227183D01*
G02X1090033Y226141I-1469J-1042D01*
G02X1088231Y224339I-1802J0D01*
G01X1088230D01*
G02X1086905Y224920I0J1802D01*
G01X1086879Y224948D01*
X1086812Y224981D01*
X1086503Y225006D01*
G03X1086363Y224963I-15J-199D01*
G02X1085431Y224639I-932J1178D01*
G02Y227643I0J1502D01*
G02X1086363Y227319I0J-1502D01*
G03X1086503Y227276I125J156D01*
G01X1086812Y227301D01*
X1086879Y227334D01*
X1086905Y227362D01*
G02X1088079Y227937I1326J-1221D01*
G03X1088240Y228044I-16J199D01*
G01X1088420Y228389D01*
X1088418Y228490D01*
X1088392Y228535D01*
G02X1088191Y229285I1301J751D01*
G01Y229286D01*
G02X1088561Y230273I1501J0D01*
G01Y230274D01*
X1088562D01*
G03X1088610Y230404I-152J130D01*
G01Y230668D01*
G03X1088562Y230798I-200J0D01*
G01X1088561Y230799D01*
G02X1088191Y231786I1131J987D01*
G37*
G36*
G01X1190553D02*
G02X1193557I1502J0D01*
G02X1193187Y230799I-1501J0D01*
G01Y230798D01*
X1193186D01*
G03X1193138Y230668I152J-130D01*
G01Y230404D01*
G03X1193186Y230274I200J0D01*
G01X1193187Y230273D01*
G02X1193557Y229286I-1131J-987D01*
G02X1192319Y227807I-1502J0D01*
G01X1192268Y227798D01*
X1192189Y227734D01*
X1192022Y227326D01*
X1192034Y227225D01*
X1192063Y227183D01*
G02X1192395Y226141I-1469J-1042D01*
G02X1190593Y224339I-1802J0D01*
G01X1190592D01*
G02X1189267Y224920I0J1802D01*
G01X1189241Y224948D01*
X1189174Y224981D01*
X1188865Y225006D01*
G03X1188725Y224963I-15J-199D01*
G02X1187793Y224639I-932J1178D01*
G02Y227643I0J1502D01*
G02X1188725Y227319I0J-1502D01*
G03X1188865Y227276I125J156D01*
G01X1189174Y227301D01*
X1189241Y227334D01*
X1189267Y227362D01*
G02X1190441Y227937I1326J-1221D01*
G03X1190602Y228044I-16J199D01*
G01X1190782Y228389D01*
X1190780Y228490D01*
X1190754Y228535D01*
G02X1190553Y229285I1301J751D01*
G01Y229286D01*
G02X1190923Y230273I1501J0D01*
G01Y230274D01*
X1190924D01*
G03X1190972Y230404I-152J130D01*
G01Y230668D01*
G03X1190924Y230798I-200J0D01*
G01X1190923Y230799D01*
G02X1190553Y231786I1131J987D01*
G37*
G36*
G01X1292915D02*
G02X1295919I1502J0D01*
G02X1295549Y230799I-1501J0D01*
G01Y230798D01*
X1295548D01*
G03X1295500Y230668I152J-130D01*
G01Y230404D01*
G03X1295548Y230274I200J0D01*
G01X1295549Y230273D01*
G02X1295919Y229286I-1131J-987D01*
G02X1294681Y227807I-1502J0D01*
G01X1294630Y227798D01*
X1294551Y227734D01*
X1294384Y227326D01*
X1294396Y227225D01*
X1294425Y227183D01*
G02X1294757Y226141I-1469J-1042D01*
G02X1292955Y224339I-1802J0D01*
G01X1292954D01*
G02X1291629Y224920I0J1802D01*
G01X1291603Y224948D01*
X1291536Y224981D01*
X1291227Y225006D01*
G03X1291087Y224963I-15J-199D01*
G02X1290155Y224639I-932J1178D01*
G02Y227643I0J1502D01*
G02X1291087Y227319I0J-1502D01*
G03X1291227Y227276I125J156D01*
G01X1291536Y227301D01*
X1291603Y227334D01*
X1291629Y227362D01*
G02X1292803Y227937I1326J-1221D01*
G03X1292964Y228044I-16J199D01*
G01X1293144Y228389D01*
X1293142Y228490D01*
X1293116Y228535D01*
G02X1292915Y229285I1301J751D01*
G01Y229286D01*
G02X1293285Y230273I1501J0D01*
G01Y230274D01*
X1293286D01*
G03X1293334Y230404I-152J130D01*
G01Y230668D01*
G03X1293286Y230798I-200J0D01*
G01X1293285Y230799D01*
G02X1292915Y231786I1131J987D01*
G37*
G36*
G01X1442916D02*
G02X1445920I1502J0D01*
G02X1445550Y230799I-1501J0D01*
G01Y230798D01*
X1445549D01*
G03X1445501Y230668I152J-130D01*
G01Y230404D01*
G03X1445549Y230274I200J0D01*
G01X1445550Y230273D01*
G02X1445920Y229286I-1131J-987D01*
G02X1444682Y227807I-1502J0D01*
G01X1444631Y227798D01*
X1444552Y227734D01*
X1444385Y227326D01*
X1444397Y227225D01*
X1444426Y227183D01*
G02X1444758Y226141I-1469J-1042D01*
G02X1442956Y224339I-1802J0D01*
G01X1442955D01*
G02X1441630Y224920I0J1802D01*
G01X1441604Y224948D01*
X1441537Y224981D01*
X1441228Y225006D01*
G03X1441088Y224963I-15J-199D01*
G02X1440156Y224639I-932J1178D01*
G02Y227643I0J1502D01*
G02X1441088Y227319I0J-1502D01*
G03X1441228Y227276I125J156D01*
G01X1441537Y227301D01*
X1441604Y227334D01*
X1441630Y227362D01*
G02X1442804Y227937I1326J-1221D01*
G03X1442965Y228044I-16J199D01*
G01X1443145Y228389D01*
X1443143Y228490D01*
X1443117Y228535D01*
G02X1442916Y229285I1301J751D01*
G01Y229286D01*
G02X1443286Y230273I1501J0D01*
G01Y230274D01*
X1443287D01*
G03X1443335Y230404I-152J130D01*
G01Y230668D01*
G03X1443287Y230798I-200J0D01*
G01X1443286Y230799D01*
G02X1442916Y231786I1131J987D01*
G37*
G36*
G01X1545278D02*
G02X1548282I1502J0D01*
G02X1547912Y230799I-1501J0D01*
G01Y230798D01*
X1547911D01*
G03X1547863Y230668I152J-130D01*
G01Y230404D01*
G03X1547911Y230274I200J0D01*
G01X1547912Y230273D01*
G02X1548282Y229286I-1131J-987D01*
G02X1547044Y227807I-1502J0D01*
G01X1546993Y227798D01*
X1546914Y227734D01*
X1546747Y227326D01*
X1546759Y227225D01*
X1546788Y227183D01*
G02X1547120Y226141I-1469J-1042D01*
G02X1545318Y224339I-1802J0D01*
G01X1545317D01*
G02X1543992Y224920I0J1802D01*
G01X1543966Y224948D01*
X1543899Y224981D01*
X1543590Y225006D01*
G03X1543450Y224963I-15J-199D01*
G02X1542518Y224639I-932J1178D01*
G02Y227643I0J1502D01*
G02X1543450Y227319I0J-1502D01*
G03X1543590Y227276I125J156D01*
G01X1543899Y227301D01*
X1543966Y227334D01*
X1543992Y227362D01*
G02X1545166Y227937I1326J-1221D01*
G03X1545327Y228044I-16J199D01*
G01X1545507Y228389D01*
X1545505Y228490D01*
X1545479Y228535D01*
G02X1545278Y229285I1301J751D01*
G01Y229286D01*
G02X1545648Y230273I1501J0D01*
G01Y230274D01*
X1545649D01*
G03X1545697Y230404I-152J130D01*
G01Y230668D01*
G03X1545649Y230798I-200J0D01*
G01X1545648Y230799D01*
G02X1545278Y231786I1131J987D01*
G37*
G36*
G01X1647640D02*
G02X1650644I1502J0D01*
G02X1650274Y230799I-1501J0D01*
G01Y230798D01*
X1650273D01*
G03X1650225Y230668I152J-130D01*
G01Y230404D01*
G03X1650273Y230274I200J0D01*
G01X1650274Y230273D01*
G02X1650644Y229286I-1131J-987D01*
G02X1649406Y227807I-1502J0D01*
G01X1649355Y227798D01*
X1649276Y227734D01*
X1649109Y227326D01*
X1649121Y227225D01*
X1649150Y227183D01*
G02X1649482Y226141I-1469J-1042D01*
G02X1647680Y224339I-1802J0D01*
G01X1647679D01*
G02X1646354Y224920I0J1802D01*
G01X1646328Y224948D01*
X1646261Y224981D01*
X1645952Y225006D01*
G03X1645812Y224963I-15J-199D01*
G02X1644880Y224639I-932J1178D01*
G02Y227643I0J1502D01*
G02X1645812Y227319I0J-1502D01*
G03X1645952Y227276I125J156D01*
G01X1646261Y227301D01*
X1646328Y227334D01*
X1646354Y227362D01*
G02X1647528Y227937I1326J-1221D01*
G03X1647689Y228044I-16J199D01*
G01X1647869Y228389D01*
X1647867Y228490D01*
X1647841Y228535D01*
G02X1647640Y229285I1301J751D01*
G01Y229286D01*
G02X1648010Y230273I1501J0D01*
G01Y230274D01*
X1648011D01*
G03X1648059Y230404I-152J130D01*
G01Y230668D01*
G03X1648011Y230798I-200J0D01*
G01X1648010Y230799D01*
G02X1647640Y231786I1131J987D01*
G37*
G36*
G01X1750002D02*
G02X1753006I1502J0D01*
G02X1752636Y230799I-1501J0D01*
G01Y230798D01*
X1752635D01*
G03X1752587Y230668I152J-130D01*
G01Y230404D01*
G03X1752635Y230274I200J0D01*
G01X1752636Y230273D01*
G02X1753006Y229286I-1131J-987D01*
G02X1751768Y227807I-1502J0D01*
G01X1751717Y227798D01*
X1751638Y227734D01*
X1751471Y227326D01*
X1751483Y227225D01*
X1751512Y227183D01*
G02X1751844Y226141I-1469J-1042D01*
G02X1750042Y224339I-1802J0D01*
G01X1750041D01*
G02X1748716Y224920I0J1802D01*
G01X1748690Y224948D01*
X1748623Y224981D01*
X1748314Y225006D01*
G03X1748174Y224963I-15J-199D01*
G02X1747242Y224639I-932J1178D01*
G02Y227643I0J1502D01*
G02X1748174Y227319I0J-1502D01*
G03X1748314Y227276I125J156D01*
G01X1748623Y227301D01*
X1748690Y227334D01*
X1748716Y227362D01*
G02X1749890Y227937I1326J-1221D01*
G03X1750051Y228044I-16J199D01*
G01X1750231Y228389D01*
X1750229Y228490D01*
X1750203Y228535D01*
G02X1750002Y229285I1301J751D01*
G01Y229286D01*
G02X1750372Y230273I1501J0D01*
G01Y230274D01*
X1750373D01*
G03X1750421Y230404I-152J130D01*
G01Y230668D01*
G03X1750373Y230798I-200J0D01*
G01X1750372Y230799D01*
G02X1750002Y231786I1131J987D01*
G37*
G36*
G01X918180Y236921D02*
G02X921184I1502J0D01*
G02X920530Y235681I-1503J0D01*
G01X920490Y235654D01*
X920444Y235571D01*
X920431Y235201D01*
G03X920508Y235037I200J-6D01*
G02X921079Y233858I-932J-1179D01*
G02X920580Y232740I-1502J0D01*
G01X920579Y232739D01*
G03X920513Y232588I134J-148D01*
G01X920517Y232245D01*
X920553Y232167D01*
X920586Y232139D01*
G02X921108Y231001I-980J-1138D01*
G01Y231000D01*
G02X918104I-1502J0D01*
G02X918603Y232118I1502J0D01*
G01X918604Y232119D01*
G03X918670Y232270I-134J148D01*
G01X918666Y232613D01*
X918630Y232691D01*
X918597Y232719D01*
G02X918075Y233857I980J1138D01*
G01Y233858D01*
G02X918729Y235098I1503J0D01*
G01X918769Y235125D01*
X918815Y235208D01*
X918828Y235578D01*
G03X918751Y235742I-200J6D01*
G02X918180Y236921I932J1179D01*
G37*
G36*
G01X869924Y303566D02*
G02X871726Y305368I0J1802D01*
G02X871595Y304694I-1802J0D01*
G01X871576Y304647D01*
X871588Y304546D01*
X871841Y304187D01*
X871933Y304143D01*
X871984Y304145D01*
G02X872049Y304146I56J-1501D01*
G01X872051D01*
G02X873552Y302644I-1J-1502D01*
G01Y302643D01*
G02X873499Y302248I-1502J0D01*
G01X873488Y302209D01*
X873497Y302132D01*
X873654Y301852D01*
G03X873770Y301758I175J97D01*
G01X873771D01*
G02X875064Y300030I-508J-1728D01*
G02X871460I-1802J0D01*
G02X871614Y300758I1802J-1D01*
G01X871630Y300795D01*
X871632Y300872D01*
X871505Y301209D01*
X871452Y301266D01*
X871416Y301282D01*
G02X870548Y302644I635J1362D01*
G02X870611Y303073I1502J-1D01*
G01X870625Y303121D01*
X870604Y303221D01*
X870318Y303554D01*
X870223Y303590D01*
X870172Y303583D01*
G02X869926Y303566I-247J1785D01*
G01X869924D01*
G37*
G36*
G01X877669Y303898D02*
G02X876475Y305368I308J1470D01*
G02X879479I1502J0D01*
G02X879181Y304470I-1502J0D01*
G03X879420Y303839I320J-239D01*
G02X880614Y302369I-308J-1470D01*
G02X877610I-1502J0D01*
G02X877908Y303267I1502J0D01*
G03X877669Y303898I-320J239D01*
G37*
G36*
G01X836429Y271528D02*
G02X837931Y270026I0J-1502D01*
G02X837561Y269039I-1501J0D01*
G01Y269038D01*
X837560D01*
G03X837512Y268908I152J-130D01*
G01Y268644D01*
G03X837560Y268514I200J0D01*
G01X837561Y268513D01*
G02X837931Y267526I-1131J-987D01*
G01Y267499D01*
G03X838038Y267319I200J-3D01*
G01X838405Y267126D01*
X838517Y267134D01*
X838563Y267167D01*
G02X839611Y267503I1048J-1466D01*
G02X837809Y265701I0J-1802D01*
G02X837816Y265865I1802J5D01*
G01X837821Y265921D01*
X837771Y266023D01*
X837371Y266272D01*
X837259Y266273D01*
X837210Y266243D01*
G02X836429Y266024I-781J1283D01*
G02X835442Y266394I0J1501D01*
G01X835441D01*
Y266395D01*
G03X835311Y266443I-130J-152D01*
G01X835047D01*
G03X834917Y266395I0J-200D01*
G01X834916Y266394D01*
G02X833929Y266024I-987J1131D01*
G02X832823Y266509I0J1504D01*
G03X832676Y266574I-148J-135D01*
G01X832382D01*
G03X832235Y266509I1J-200D01*
G02X831129Y266024I-1106J1019D01*
G02X829627Y267526I0J1502D01*
G02X829997Y268513I1501J0D01*
G01Y268514D01*
X829998D01*
G03X830046Y268644I-152J130D01*
G01Y268908D01*
G03X829998Y269038I-200J0D01*
G01X829997Y269039D01*
G02X829627Y270026I1131J987D01*
G02X831129Y271528I1502J0D01*
G02X832235Y271043I0J-1504D01*
G03X832382Y270978I148J135D01*
G01X832676D01*
G03X832823Y271043I-1J200D01*
G02X833929Y271528I1106J-1019D01*
G02X834916Y271158I0J-1501D01*
G01X834917D01*
Y271157D01*
G03X835047Y271109I130J152D01*
G01X835311D01*
G03X835441Y271157I0J200D01*
G01X835442Y271158D01*
G02X836429Y271528I987J-1131D01*
G37*
G36*
G01X734067D02*
G02X735569Y270026I0J-1502D01*
G02X735199Y269039I-1501J0D01*
G01Y269038D01*
X735198D01*
G03X735150Y268908I152J-130D01*
G01Y268644D01*
G03X735198Y268514I200J0D01*
G01X735199Y268513D01*
G02X735569Y267526I-1131J-987D01*
G01Y267499D01*
G03X735676Y267319I200J-3D01*
G01X736043Y267126D01*
X736155Y267134D01*
X736201Y267167D01*
G02X737249Y267503I1048J-1466D01*
G02X735447Y265701I0J-1802D01*
G02X735454Y265865I1802J5D01*
G01X735459Y265921D01*
X735409Y266023D01*
X735009Y266272D01*
X734897Y266273D01*
X734848Y266243D01*
G02X734067Y266024I-781J1283D01*
G02X733080Y266394I0J1501D01*
G01X733079D01*
Y266395D01*
G03X732949Y266443I-130J-152D01*
G01X732685D01*
G03X732555Y266395I0J-200D01*
G01X732554Y266394D01*
G02X731567Y266024I-987J1131D01*
G02X730461Y266509I0J1504D01*
G03X730314Y266574I-148J-135D01*
G01X730020D01*
G03X729873Y266509I1J-200D01*
G02X728767Y266024I-1106J1019D01*
G02X727265Y267526I0J1502D01*
G02X727635Y268513I1501J0D01*
G01Y268514D01*
X727636D01*
G03X727684Y268644I-152J130D01*
G01Y268908D01*
G03X727636Y269038I-200J0D01*
G01X727635Y269039D01*
G02X727265Y270026I1131J987D01*
G02X728767Y271528I1502J0D01*
G02X729873Y271043I0J-1504D01*
G03X730020Y270978I148J135D01*
G01X730314D01*
G03X730461Y271043I-1J200D01*
G02X731567Y271528I1106J-1019D01*
G02X732554Y271158I0J-1501D01*
G01X732555D01*
Y271157D01*
G03X732685Y271109I130J152D01*
G01X732949D01*
G03X733079Y271157I0J200D01*
G01X733080Y271158D01*
G02X734067Y271528I987J-1131D01*
G37*
G36*
G01X631705D02*
G02X633207Y270026I0J-1502D01*
G02X632837Y269039I-1501J0D01*
G01Y269038D01*
X632836D01*
G03X632788Y268908I152J-130D01*
G01Y268644D01*
G03X632836Y268514I200J0D01*
G01X632837Y268513D01*
G02X633207Y267526I-1131J-987D01*
G01Y267499D01*
G03X633314Y267319I200J-3D01*
G01X633681Y267126D01*
X633793Y267134D01*
X633839Y267167D01*
G02X634887Y267503I1048J-1466D01*
G02X633085Y265701I0J-1802D01*
G02X633092Y265865I1802J5D01*
G01X633097Y265921D01*
X633047Y266023D01*
X632647Y266272D01*
X632535Y266273D01*
X632486Y266243D01*
G02X631705Y266024I-781J1283D01*
G02X630718Y266394I0J1501D01*
G01X630717D01*
Y266395D01*
G03X630587Y266443I-130J-152D01*
G01X630323D01*
G03X630193Y266395I0J-200D01*
G01X630192Y266394D01*
G02X629205Y266024I-987J1131D01*
G02X628099Y266509I0J1504D01*
G03X627952Y266574I-148J-135D01*
G01X627658D01*
G03X627511Y266509I1J-200D01*
G02X626405Y266024I-1106J1019D01*
G02X624903Y267526I0J1502D01*
G02X625273Y268513I1501J0D01*
G01Y268514D01*
X625274D01*
G03X625322Y268644I-152J130D01*
G01Y268908D01*
G03X625274Y269038I-200J0D01*
G01X625273Y269039D01*
G02X624903Y270026I1131J987D01*
G02X626405Y271528I1502J0D01*
G02X627511Y271043I0J-1504D01*
G03X627658Y270978I148J135D01*
G01X627952D01*
G03X628099Y271043I-1J200D01*
G02X629205Y271528I1106J-1019D01*
G02X630192Y271158I0J-1501D01*
G01X630193D01*
Y271157D01*
G03X630323Y271109I130J152D01*
G01X630587D01*
G03X630717Y271157I0J200D01*
G01X630718Y271158D01*
G02X631705Y271528I987J-1131D01*
G37*
G36*
G01X529343D02*
G02X530845Y270026I0J-1502D01*
G02X530475Y269039I-1501J0D01*
G01Y269038D01*
X530474D01*
G03X530426Y268908I152J-130D01*
G01Y268644D01*
G03X530474Y268514I200J0D01*
G01X530475Y268513D01*
G02X530845Y267526I-1131J-987D01*
G01Y267499D01*
G03X530952Y267319I200J-3D01*
G01X531319Y267126D01*
X531431Y267134D01*
X531477Y267167D01*
G02X532525Y267503I1048J-1466D01*
G02X530723Y265701I0J-1802D01*
G02X530730Y265865I1802J5D01*
G01X530735Y265921D01*
X530685Y266023D01*
X530285Y266272D01*
X530173Y266273D01*
X530124Y266243D01*
G02X529343Y266024I-781J1283D01*
G02X528356Y266394I0J1501D01*
G01X528355D01*
Y266395D01*
G03X528225Y266443I-130J-152D01*
G01X527961D01*
G03X527831Y266395I0J-200D01*
G01X527830Y266394D01*
G02X526843Y266024I-987J1131D01*
G02X525737Y266509I0J1504D01*
G03X525590Y266574I-148J-135D01*
G01X525296D01*
G03X525149Y266509I1J-200D01*
G02X524043Y266024I-1106J1019D01*
G02X522541Y267526I0J1502D01*
G02X522911Y268513I1501J0D01*
G01Y268514D01*
X522912D01*
G03X522960Y268644I-152J130D01*
G01Y268908D01*
G03X522912Y269038I-200J0D01*
G01X522911Y269039D01*
G02X522541Y270026I1131J987D01*
G02X524043Y271528I1502J0D01*
G02X525149Y271043I0J-1504D01*
G03X525296Y270978I148J135D01*
G01X525590D01*
G03X525737Y271043I-1J200D01*
G02X526843Y271528I1106J-1019D01*
G02X527830Y271158I0J-1501D01*
G01X527831D01*
Y271157D01*
G03X527961Y271109I130J152D01*
G01X528225D01*
G03X528355Y271157I0J200D01*
G01X528356Y271158D01*
G02X529343Y271528I987J-1131D01*
G37*
G36*
G01X379342D02*
G02X380844Y270026I0J-1502D01*
G02X380474Y269039I-1501J0D01*
G01Y269038D01*
X380473D01*
G03X380425Y268908I152J-130D01*
G01Y268644D01*
G03X380473Y268514I200J0D01*
G01X380474Y268513D01*
G02X380844Y267526I-1131J-987D01*
G01Y267499D01*
G03X380951Y267319I200J-3D01*
G01X381318Y267126D01*
X381430Y267134D01*
X381476Y267167D01*
G02X382524Y267503I1048J-1466D01*
G02X380722Y265701I0J-1802D01*
G02X380729Y265865I1802J5D01*
G01X380734Y265921D01*
X380684Y266023D01*
X380284Y266272D01*
X380172Y266273D01*
X380123Y266243D01*
G02X379342Y266024I-781J1283D01*
G02X378355Y266394I0J1501D01*
G01X378354D01*
Y266395D01*
G03X378224Y266443I-130J-152D01*
G01X377960D01*
G03X377830Y266395I0J-200D01*
G01X377829Y266394D01*
G02X376842Y266024I-987J1131D01*
G02X375736Y266509I0J1504D01*
G03X375589Y266574I-148J-135D01*
G01X375295D01*
G03X375148Y266509I1J-200D01*
G02X374042Y266024I-1106J1019D01*
G02X372540Y267526I0J1502D01*
G02X372910Y268513I1501J0D01*
G01Y268514D01*
X372911D01*
G03X372959Y268644I-152J130D01*
G01Y268908D01*
G03X372911Y269038I-200J0D01*
G01X372910Y269039D01*
G02X372540Y270026I1131J987D01*
G02X374042Y271528I1502J0D01*
G02X375148Y271043I0J-1504D01*
G03X375295Y270978I148J135D01*
G01X375589D01*
G03X375736Y271043I-1J200D01*
G02X376842Y271528I1106J-1019D01*
G02X377829Y271158I0J-1501D01*
G01X377830D01*
Y271157D01*
G03X377960Y271109I130J152D01*
G01X378224D01*
G03X378354Y271157I0J200D01*
G01X378355Y271158D01*
G02X379342Y271528I987J-1131D01*
G37*
G36*
G01X276980D02*
G02X278482Y270026I0J-1502D01*
G02X278112Y269039I-1501J0D01*
G01Y269038D01*
X278111D01*
G03X278063Y268908I152J-130D01*
G01Y268644D01*
G03X278111Y268514I200J0D01*
G01X278112Y268513D01*
G02X278482Y267526I-1131J-987D01*
G01Y267499D01*
G03X278589Y267319I200J-3D01*
G01X278956Y267126D01*
X279068Y267134D01*
X279114Y267167D01*
G02X280162Y267503I1048J-1466D01*
G02X278360Y265701I0J-1802D01*
G02X278367Y265865I1802J5D01*
G01X278372Y265921D01*
X278322Y266023D01*
X277922Y266272D01*
X277810Y266273D01*
X277761Y266243D01*
G02X276980Y266024I-781J1283D01*
G02X275993Y266394I0J1501D01*
G01X275992D01*
Y266395D01*
G03X275862Y266443I-130J-152D01*
G01X275598D01*
G03X275468Y266395I0J-200D01*
G01X275467Y266394D01*
G02X274480Y266024I-987J1131D01*
G02X273374Y266509I0J1504D01*
G03X273227Y266574I-148J-135D01*
G01X272933D01*
G03X272786Y266509I1J-200D01*
G02X271680Y266024I-1106J1019D01*
G02X270178Y267526I0J1502D01*
G02X270548Y268513I1501J0D01*
G01Y268514D01*
X270549D01*
G03X270597Y268644I-152J130D01*
G01Y268908D01*
G03X270549Y269038I-200J0D01*
G01X270548Y269039D01*
G02X270178Y270026I1131J987D01*
G02X271680Y271528I1502J0D01*
G02X272786Y271043I0J-1504D01*
G03X272933Y270978I148J135D01*
G01X273227D01*
G03X273374Y271043I-1J200D01*
G02X274480Y271528I1106J-1019D01*
G02X275467Y271158I0J-1501D01*
G01X275468D01*
Y271157D01*
G03X275598Y271109I130J152D01*
G01X275862D01*
G03X275992Y271157I0J200D01*
G01X275993Y271158D01*
G02X276980Y271528I987J-1131D01*
G37*
G36*
G01X174618D02*
G02X176120Y270026I0J-1502D01*
G02X175750Y269039I-1501J0D01*
G01Y269038D01*
X175749D01*
G03X175701Y268908I152J-130D01*
G01Y268644D01*
G03X175749Y268514I200J0D01*
G01X175750Y268513D01*
G02X176120Y267526I-1131J-987D01*
G01Y267499D01*
G03X176227Y267319I200J-3D01*
G01X176594Y267126D01*
X176706Y267134D01*
X176752Y267167D01*
G02X177800Y267503I1048J-1466D01*
G02X175998Y265701I0J-1802D01*
G02X176005Y265865I1802J5D01*
G01X176010Y265921D01*
X175960Y266023D01*
X175560Y266272D01*
X175448Y266273D01*
X175399Y266243D01*
G02X174618Y266024I-781J1283D01*
G02X173631Y266394I0J1501D01*
G01X173630D01*
Y266395D01*
G03X173500Y266443I-130J-152D01*
G01X173236D01*
G03X173106Y266395I0J-200D01*
G01X173105Y266394D01*
G02X172118Y266024I-987J1131D01*
G02X171012Y266509I0J1504D01*
G03X170865Y266574I-148J-135D01*
G01X170571D01*
G03X170424Y266509I1J-200D01*
G02X169318Y266024I-1106J1019D01*
G02X167816Y267526I0J1502D01*
G02X168186Y268513I1501J0D01*
G01Y268514D01*
X168187D01*
G03X168235Y268644I-152J130D01*
G01Y268908D01*
G03X168187Y269038I-200J0D01*
G01X168186Y269039D01*
G02X167816Y270026I1131J987D01*
G02X169318Y271528I1502J0D01*
G02X170424Y271043I0J-1504D01*
G03X170571Y270978I148J135D01*
G01X170865D01*
G03X171012Y271043I-1J200D01*
G02X172118Y271528I1106J-1019D01*
G02X173105Y271158I0J-1501D01*
G01X173106D01*
Y271157D01*
G03X173236Y271109I130J152D01*
G01X173500D01*
G03X173630Y271157I0J200D01*
G01X173631Y271158D01*
G02X174618Y271528I987J-1131D01*
G37*
G36*
G01X72256D02*
G02X73758Y270026I0J-1502D01*
G02X73388Y269039I-1501J0D01*
G01Y269038D01*
X73387D01*
G03X73339Y268908I152J-130D01*
G01Y268644D01*
G03X73387Y268514I200J0D01*
G01X73388Y268513D01*
G02X73758Y267526I-1131J-987D01*
G01Y267499D01*
G03X73865Y267319I200J-3D01*
G01X74232Y267126D01*
X74344Y267134D01*
X74390Y267167D01*
G02X75438Y267503I1048J-1466D01*
G02X73636Y265701I0J-1802D01*
G02X73643Y265865I1802J5D01*
G01X73648Y265921D01*
X73598Y266023D01*
X73198Y266272D01*
X73086Y266273D01*
X73037Y266243D01*
G02X72256Y266024I-781J1283D01*
G02X71269Y266394I0J1501D01*
G01X71268D01*
Y266395D01*
G03X71138Y266443I-130J-152D01*
G01X70874D01*
G03X70744Y266395I0J-200D01*
G01X70743Y266394D01*
G02X69756Y266024I-987J1131D01*
G02X68650Y266509I0J1504D01*
G03X68503Y266574I-148J-135D01*
G01X68209D01*
G03X68062Y266509I1J-200D01*
G02X66956Y266024I-1106J1019D01*
G02X65454Y267526I0J1502D01*
G02X65824Y268513I1501J0D01*
G01Y268514D01*
X65825D01*
G03X65873Y268644I-152J130D01*
G01Y268908D01*
G03X65825Y269038I-200J0D01*
G01X65824Y269039D01*
G02X65454Y270026I1131J987D01*
G02X66956Y271528I1502J0D01*
G02X68062Y271043I0J-1504D01*
G03X68209Y270978I148J135D01*
G01X68503D01*
G03X68650Y271043I-1J200D01*
G02X69756Y271528I1106J-1019D01*
G02X70743Y271158I0J-1501D01*
G01X70744D01*
Y271157D01*
G03X70874Y271109I130J152D01*
G01X71138D01*
G03X71268Y271157I0J200D01*
G01X71269Y271158D01*
G02X72256Y271528I987J-1131D01*
G37*
G36*
G01X855460Y272197D02*
G02X856566Y271712I0J-1504D01*
G03X856713Y271647I148J135D01*
G01X857007D01*
G03X857154Y271712I-1J200D01*
G02X858260Y272197I1106J-1019D01*
G02X859762Y270695I0J-1502D01*
G02X859392Y269708I-1501J0D01*
G01Y269707D01*
X859391D01*
G03X859343Y269577I152J-130D01*
G01Y269313D01*
G03X859391Y269183I200J0D01*
G01X859392Y269182D01*
G02X859762Y268195I-1131J-987D01*
G02X858260Y266693I-1502J0D01*
G02X857154Y267178I0J1504D01*
G03X857007Y267243I-148J-135D01*
G01X856713D01*
G03X856566Y267178I1J-200D01*
G02X855460Y266693I-1106J1019D01*
G02X854473Y267063I0J1501D01*
G01X854472D01*
Y267064D01*
G03X854342Y267112I-130J-152D01*
G01X854078D01*
G03X853948Y267064I0J-200D01*
G01X853947Y267063D01*
G02X852960Y266693I-987J1131D01*
G02X851458Y268195I0J1502D01*
G02X851828Y269182I1501J0D01*
G01Y269183D01*
X851829D01*
G03X851877Y269313I-152J130D01*
G01Y269577D01*
G03X851829Y269707I-200J0D01*
G01X851828Y269708D01*
G02X851458Y270695I1131J987D01*
G02X852960Y272197I1502J0D01*
G02X853947Y271827I0J-1501D01*
G01X853948D01*
Y271826D01*
G03X854078Y271778I130J152D01*
G01X854342D01*
G03X854472Y271826I0J200D01*
G01X854473Y271827D01*
G02X855460Y272197I987J-1131D01*
G37*
G36*
G01X753098D02*
G02X754204Y271712I0J-1504D01*
G03X754351Y271647I148J135D01*
G01X754645D01*
G03X754792Y271712I-1J200D01*
G02X755898Y272197I1106J-1019D01*
G02X757400Y270695I0J-1502D01*
G02X757030Y269708I-1501J0D01*
G01Y269707D01*
X757029D01*
G03X756981Y269577I152J-130D01*
G01Y269313D01*
G03X757029Y269183I200J0D01*
G01X757030Y269182D01*
G02X757400Y268195I-1131J-987D01*
G02X755898Y266693I-1502J0D01*
G02X754792Y267178I0J1504D01*
G03X754645Y267243I-148J-135D01*
G01X754351D01*
G03X754204Y267178I1J-200D01*
G02X753098Y266693I-1106J1019D01*
G02X752111Y267063I0J1501D01*
G01X752110D01*
Y267064D01*
G03X751980Y267112I-130J-152D01*
G01X751716D01*
G03X751586Y267064I0J-200D01*
G01X751585Y267063D01*
G02X750598Y266693I-987J1131D01*
G02X749096Y268195I0J1502D01*
G02X749466Y269182I1501J0D01*
G01Y269183D01*
X749467D01*
G03X749515Y269313I-152J130D01*
G01Y269577D01*
G03X749467Y269707I-200J0D01*
G01X749466Y269708D01*
G02X749096Y270695I1131J987D01*
G02X750598Y272197I1502J0D01*
G02X751585Y271827I0J-1501D01*
G01X751586D01*
Y271826D01*
G03X751716Y271778I130J152D01*
G01X751980D01*
G03X752110Y271826I0J200D01*
G01X752111Y271827D01*
G02X753098Y272197I987J-1131D01*
G37*
G36*
G01X650736D02*
G02X651842Y271712I0J-1504D01*
G03X651989Y271647I148J135D01*
G01X652283D01*
G03X652430Y271712I-1J200D01*
G02X653536Y272197I1106J-1019D01*
G02X655038Y270695I0J-1502D01*
G02X654668Y269708I-1501J0D01*
G01Y269707D01*
X654667D01*
G03X654619Y269577I152J-130D01*
G01Y269313D01*
G03X654667Y269183I200J0D01*
G01X654668Y269182D01*
G02X655038Y268195I-1131J-987D01*
G02X653536Y266693I-1502J0D01*
G02X652430Y267178I0J1504D01*
G03X652283Y267243I-148J-135D01*
G01X651989D01*
G03X651842Y267178I1J-200D01*
G02X650736Y266693I-1106J1019D01*
G02X649749Y267063I0J1501D01*
G01X649748D01*
Y267064D01*
G03X649618Y267112I-130J-152D01*
G01X649354D01*
G03X649224Y267064I0J-200D01*
G01X649223Y267063D01*
G02X648236Y266693I-987J1131D01*
G02X646734Y268195I0J1502D01*
G02X647104Y269182I1501J0D01*
G01Y269183D01*
X647105D01*
G03X647153Y269313I-152J130D01*
G01Y269577D01*
G03X647105Y269707I-200J0D01*
G01X647104Y269708D01*
G02X646734Y270695I1131J987D01*
G02X648236Y272197I1502J0D01*
G02X649223Y271827I0J-1501D01*
G01X649224D01*
Y271826D01*
G03X649354Y271778I130J152D01*
G01X649618D01*
G03X649748Y271826I0J200D01*
G01X649749Y271827D01*
G02X650736Y272197I987J-1131D01*
G37*
G36*
G01X548374D02*
G02X549480Y271712I0J-1504D01*
G03X549627Y271647I148J135D01*
G01X549921D01*
G03X550068Y271712I-1J200D01*
G02X551174Y272197I1106J-1019D01*
G02X552676Y270695I0J-1502D01*
G02X552306Y269708I-1501J0D01*
G01Y269707D01*
X552305D01*
G03X552257Y269577I152J-130D01*
G01Y269313D01*
G03X552305Y269183I200J0D01*
G01X552306Y269182D01*
G02X552676Y268195I-1131J-987D01*
G02X551174Y266693I-1502J0D01*
G02X550068Y267178I0J1504D01*
G03X549921Y267243I-148J-135D01*
G01X549627D01*
G03X549480Y267178I1J-200D01*
G02X548374Y266693I-1106J1019D01*
G02X547387Y267063I0J1501D01*
G01X547386D01*
Y267064D01*
G03X547256Y267112I-130J-152D01*
G01X546992D01*
G03X546862Y267064I0J-200D01*
G01X546861Y267063D01*
G02X545874Y266693I-987J1131D01*
G02X544372Y268195I0J1502D01*
G02X544742Y269182I1501J0D01*
G01Y269183D01*
X544743D01*
G03X544791Y269313I-152J130D01*
G01Y269577D01*
G03X544743Y269707I-200J0D01*
G01X544742Y269708D01*
G02X544372Y270695I1131J987D01*
G02X545874Y272197I1502J0D01*
G02X546861Y271827I0J-1501D01*
G01X546862D01*
Y271826D01*
G03X546992Y271778I130J152D01*
G01X547256D01*
G03X547386Y271826I0J200D01*
G01X547387Y271827D01*
G02X548374Y272197I987J-1131D01*
G37*
G36*
G01X398373D02*
G02X399479Y271712I0J-1504D01*
G03X399626Y271647I148J135D01*
G01X399920D01*
G03X400067Y271712I-1J200D01*
G02X401173Y272197I1106J-1019D01*
G02X402675Y270695I0J-1502D01*
G02X402305Y269708I-1501J0D01*
G01Y269707D01*
X402304D01*
G03X402256Y269577I152J-130D01*
G01Y269313D01*
G03X402304Y269183I200J0D01*
G01X402305Y269182D01*
G02X402675Y268195I-1131J-987D01*
G02X401173Y266693I-1502J0D01*
G02X400067Y267178I0J1504D01*
G03X399920Y267243I-148J-135D01*
G01X399626D01*
G03X399479Y267178I1J-200D01*
G02X398373Y266693I-1106J1019D01*
G02X397386Y267063I0J1501D01*
G01X397385D01*
Y267064D01*
G03X397255Y267112I-130J-152D01*
G01X396991D01*
G03X396861Y267064I0J-200D01*
G01X396860Y267063D01*
G02X395873Y266693I-987J1131D01*
G02X394371Y268195I0J1502D01*
G02X394741Y269182I1501J0D01*
G01Y269183D01*
X394742D01*
G03X394790Y269313I-152J130D01*
G01Y269577D01*
G03X394742Y269707I-200J0D01*
G01X394741Y269708D01*
G02X394371Y270695I1131J987D01*
G02X395873Y272197I1502J0D01*
G02X396860Y271827I0J-1501D01*
G01X396861D01*
Y271826D01*
G03X396991Y271778I130J152D01*
G01X397255D01*
G03X397385Y271826I0J200D01*
G01X397386Y271827D01*
G02X398373Y272197I987J-1131D01*
G37*
G36*
G01X296011D02*
G02X297117Y271712I0J-1504D01*
G03X297264Y271647I148J135D01*
G01X297558D01*
G03X297705Y271712I-1J200D01*
G02X298811Y272197I1106J-1019D01*
G02X300313Y270695I0J-1502D01*
G02X299943Y269708I-1501J0D01*
G01Y269707D01*
X299942D01*
G03X299894Y269577I152J-130D01*
G01Y269313D01*
G03X299942Y269183I200J0D01*
G01X299943Y269182D01*
G02X300313Y268195I-1131J-987D01*
G02X298811Y266693I-1502J0D01*
G02X297705Y267178I0J1504D01*
G03X297558Y267243I-148J-135D01*
G01X297264D01*
G03X297117Y267178I1J-200D01*
G02X296011Y266693I-1106J1019D01*
G02X295024Y267063I0J1501D01*
G01X295023D01*
Y267064D01*
G03X294893Y267112I-130J-152D01*
G01X294629D01*
G03X294499Y267064I0J-200D01*
G01X294498Y267063D01*
G02X293511Y266693I-987J1131D01*
G02X292009Y268195I0J1502D01*
G02X292379Y269182I1501J0D01*
G01Y269183D01*
X292380D01*
G03X292428Y269313I-152J130D01*
G01Y269577D01*
G03X292380Y269707I-200J0D01*
G01X292379Y269708D01*
G02X292009Y270695I1131J987D01*
G02X293511Y272197I1502J0D01*
G02X294498Y271827I0J-1501D01*
G01X294499D01*
Y271826D01*
G03X294629Y271778I130J152D01*
G01X294893D01*
G03X295023Y271826I0J200D01*
G01X295024Y271827D01*
G02X296011Y272197I987J-1131D01*
G37*
G36*
G01X193649D02*
G02X194755Y271712I0J-1504D01*
G03X194902Y271647I148J135D01*
G01X195196D01*
G03X195343Y271712I-1J200D01*
G02X196449Y272197I1106J-1019D01*
G02X197951Y270695I0J-1502D01*
G02X197581Y269708I-1501J0D01*
G01Y269707D01*
X197580D01*
G03X197532Y269577I152J-130D01*
G01Y269313D01*
G03X197580Y269183I200J0D01*
G01X197581Y269182D01*
G02X197951Y268195I-1131J-987D01*
G02X196449Y266693I-1502J0D01*
G02X195343Y267178I0J1504D01*
G03X195196Y267243I-148J-135D01*
G01X194902D01*
G03X194755Y267178I1J-200D01*
G02X193649Y266693I-1106J1019D01*
G02X192662Y267063I0J1501D01*
G01X192661D01*
Y267064D01*
G03X192531Y267112I-130J-152D01*
G01X192267D01*
G03X192137Y267064I0J-200D01*
G01X192136Y267063D01*
G02X191149Y266693I-987J1131D01*
G02X189647Y268195I0J1502D01*
G02X190017Y269182I1501J0D01*
G01Y269183D01*
X190018D01*
G03X190066Y269313I-152J130D01*
G01Y269577D01*
G03X190018Y269707I-200J0D01*
G01X190017Y269708D01*
G02X189647Y270695I1131J987D01*
G02X191149Y272197I1502J0D01*
G02X192136Y271827I0J-1501D01*
G01X192137D01*
Y271826D01*
G03X192267Y271778I130J152D01*
G01X192531D01*
G03X192661Y271826I0J200D01*
G01X192662Y271827D01*
G02X193649Y272197I987J-1131D01*
G37*
G36*
G01X91287D02*
G02X92393Y271712I0J-1504D01*
G03X92540Y271647I148J135D01*
G01X92834D01*
G03X92981Y271712I-1J200D01*
G02X94087Y272197I1106J-1019D01*
G02X95589Y270695I0J-1502D01*
G02X95219Y269708I-1501J0D01*
G01Y269707D01*
X95218D01*
G03X95170Y269577I152J-130D01*
G01Y269313D01*
G03X95218Y269183I200J0D01*
G01X95219Y269182D01*
G02X95589Y268195I-1131J-987D01*
G02X94087Y266693I-1502J0D01*
G02X92981Y267178I0J1504D01*
G03X92834Y267243I-148J-135D01*
G01X92540D01*
G03X92393Y267178I1J-200D01*
G02X91287Y266693I-1106J1019D01*
G02X90300Y267063I0J1501D01*
G01X90299D01*
Y267064D01*
G03X90169Y267112I-130J-152D01*
G01X89905D01*
G03X89775Y267064I0J-200D01*
G01X89774Y267063D01*
G02X88787Y266693I-987J1131D01*
G02X87285Y268195I0J1502D01*
G02X87655Y269182I1501J0D01*
G01Y269183D01*
X87656D01*
G03X87704Y269313I-152J130D01*
G01Y269577D01*
G03X87656Y269707I-200J0D01*
G01X87655Y269708D01*
G02X87285Y270695I1131J987D01*
G02X88787Y272197I1502J0D01*
G02X89774Y271827I0J-1501D01*
G01X89775D01*
Y271826D01*
G03X89905Y271778I130J152D01*
G01X90169D01*
G03X90299Y271826I0J200D01*
G01X90300Y271827D01*
G02X91287Y272197I987J-1131D01*
G37*
G36*
G01X861920Y264395D02*
G02Y267399I0J1502D01*
G02X862907Y267029I0J-1501D01*
G01X862908D01*
Y267028D01*
G03X863038Y266980I130J152D01*
G01X863302D01*
G03X863432Y267028I0J200D01*
G01X863433Y267029D01*
G02X864420Y267399I987J-1131D01*
G02Y264395I0J-1502D01*
G02X863433Y264765I0J1501D01*
G01X863432D01*
Y264766D01*
G03X863302Y264814I-130J-152D01*
G01X863038D01*
G03X862908Y264766I0J-200D01*
G01X862907Y264765D01*
G02X861920Y264395I-987J1131D01*
G37*
G36*
G01X759558D02*
G02Y267399I0J1502D01*
G02X760545Y267029I0J-1501D01*
G01X760546D01*
Y267028D01*
G03X760676Y266980I130J152D01*
G01X760940D01*
G03X761070Y267028I0J200D01*
G01X761071Y267029D01*
G02X762058Y267399I987J-1131D01*
G02Y264395I0J-1502D01*
G02X761071Y264765I0J1501D01*
G01X761070D01*
Y264766D01*
G03X760940Y264814I-130J-152D01*
G01X760676D01*
G03X760546Y264766I0J-200D01*
G01X760545Y264765D01*
G02X759558Y264395I-987J1131D01*
G37*
G36*
G01X657196D02*
G02Y267399I0J1502D01*
G02X658183Y267029I0J-1501D01*
G01X658184D01*
Y267028D01*
G03X658314Y266980I130J152D01*
G01X658578D01*
G03X658708Y267028I0J200D01*
G01X658709Y267029D01*
G02X659696Y267399I987J-1131D01*
G02Y264395I0J-1502D01*
G02X658709Y264765I0J1501D01*
G01X658708D01*
Y264766D01*
G03X658578Y264814I-130J-152D01*
G01X658314D01*
G03X658184Y264766I0J-200D01*
G01X658183Y264765D01*
G02X657196Y264395I-987J1131D01*
G37*
G36*
G01X554834D02*
G02Y267399I0J1502D01*
G02X555821Y267029I0J-1501D01*
G01X555822D01*
Y267028D01*
G03X555952Y266980I130J152D01*
G01X556216D01*
G03X556346Y267028I0J200D01*
G01X556347Y267029D01*
G02X557334Y267399I987J-1131D01*
G02Y264395I0J-1502D01*
G02X556347Y264765I0J1501D01*
G01X556346D01*
Y264766D01*
G03X556216Y264814I-130J-152D01*
G01X555952D01*
G03X555822Y264766I0J-200D01*
G01X555821Y264765D01*
G02X554834Y264395I-987J1131D01*
G37*
G36*
G01X404833D02*
G02Y267399I0J1502D01*
G02X405820Y267029I0J-1501D01*
G01X405821D01*
Y267028D01*
G03X405951Y266980I130J152D01*
G01X406215D01*
G03X406345Y267028I0J200D01*
G01X406346Y267029D01*
G02X407333Y267399I987J-1131D01*
G02Y264395I0J-1502D01*
G02X406346Y264765I0J1501D01*
G01X406345D01*
Y264766D01*
G03X406215Y264814I-130J-152D01*
G01X405951D01*
G03X405821Y264766I0J-200D01*
G01X405820Y264765D01*
G02X404833Y264395I-987J1131D01*
G37*
G36*
G01X302471D02*
G02Y267399I0J1502D01*
G02X303458Y267029I0J-1501D01*
G01X303459D01*
Y267028D01*
G03X303589Y266980I130J152D01*
G01X303853D01*
G03X303983Y267028I0J200D01*
G01X303984Y267029D01*
G02X304971Y267399I987J-1131D01*
G02Y264395I0J-1502D01*
G02X303984Y264765I0J1501D01*
G01X303983D01*
Y264766D01*
G03X303853Y264814I-130J-152D01*
G01X303589D01*
G03X303459Y264766I0J-200D01*
G01X303458Y264765D01*
G02X302471Y264395I-987J1131D01*
G37*
G36*
G01X200109D02*
G02Y267399I0J1502D01*
G02X201096Y267029I0J-1501D01*
G01X201097D01*
Y267028D01*
G03X201227Y266980I130J152D01*
G01X201491D01*
G03X201621Y267028I0J200D01*
G01X201622Y267029D01*
G02X202609Y267399I987J-1131D01*
G02Y264395I0J-1502D01*
G02X201622Y264765I0J1501D01*
G01X201621D01*
Y264766D01*
G03X201491Y264814I-130J-152D01*
G01X201227D01*
G03X201097Y264766I0J-200D01*
G01X201096Y264765D01*
G02X200109Y264395I-987J1131D01*
G37*
G36*
G01X97747D02*
G02Y267399I0J1502D01*
G02X98734Y267029I0J-1501D01*
G01X98735D01*
Y267028D01*
G03X98865Y266980I130J152D01*
G01X99129D01*
G03X99259Y267028I0J200D01*
G01X99260Y267029D01*
G02X100247Y267399I987J-1131D01*
G02Y264395I0J-1502D01*
G02X99260Y264765I0J1501D01*
G01X99259D01*
Y264766D01*
G03X99129Y264814I-130J-152D01*
G01X98865D01*
G03X98735Y264766I0J-200D01*
G01X98734Y264765D01*
G02X97747Y264395I-987J1131D01*
G37*
G36*
G01X822235Y262678D02*
G02Y265682I0J1502D01*
G02X823222Y265312I0J-1501D01*
G01X823223D01*
Y265311D01*
G03X823353Y265263I130J152D01*
G01X823617D01*
G03X823747Y265311I0J200D01*
G01X823748Y265312D01*
G02X824735Y265682I987J-1131D01*
G02Y262678I0J-1502D01*
G02X823748Y263048I0J1501D01*
G01X823747D01*
Y263049D01*
G03X823617Y263097I-130J-152D01*
G01X823353D01*
G03X823223Y263049I0J-200D01*
G01X823222Y263048D01*
G02X822235Y262678I-987J1131D01*
G37*
G36*
G01X719873D02*
G02Y265682I0J1502D01*
G02X720860Y265312I0J-1501D01*
G01X720861D01*
Y265311D01*
G03X720991Y265263I130J152D01*
G01X721255D01*
G03X721385Y265311I0J200D01*
G01X721386Y265312D01*
G02X722373Y265682I987J-1131D01*
G02Y262678I0J-1502D01*
G02X721386Y263048I0J1501D01*
G01X721385D01*
Y263049D01*
G03X721255Y263097I-130J-152D01*
G01X720991D01*
G03X720861Y263049I0J-200D01*
G01X720860Y263048D01*
G02X719873Y262678I-987J1131D01*
G37*
G36*
G01X617511D02*
G02Y265682I0J1502D01*
G02X618498Y265312I0J-1501D01*
G01X618499D01*
Y265311D01*
G03X618629Y265263I130J152D01*
G01X618893D01*
G03X619023Y265311I0J200D01*
G01X619024Y265312D01*
G02X620011Y265682I987J-1131D01*
G02Y262678I0J-1502D01*
G02X619024Y263048I0J1501D01*
G01X619023D01*
Y263049D01*
G03X618893Y263097I-130J-152D01*
G01X618629D01*
G03X618499Y263049I0J-200D01*
G01X618498Y263048D01*
G02X617511Y262678I-987J1131D01*
G37*
G36*
G01X515149D02*
G02Y265682I0J1502D01*
G02X516136Y265312I0J-1501D01*
G01X516137D01*
Y265311D01*
G03X516267Y265263I130J152D01*
G01X516531D01*
G03X516661Y265311I0J200D01*
G01X516662Y265312D01*
G02X517649Y265682I987J-1131D01*
G02Y262678I0J-1502D01*
G02X516662Y263048I0J1501D01*
G01X516661D01*
Y263049D01*
G03X516531Y263097I-130J-152D01*
G01X516267D01*
G03X516137Y263049I0J-200D01*
G01X516136Y263048D01*
G02X515149Y262678I-987J1131D01*
G37*
G36*
G01X365148D02*
G02Y265682I0J1502D01*
G02X366135Y265312I0J-1501D01*
G01X366136D01*
Y265311D01*
G03X366266Y265263I130J152D01*
G01X366530D01*
G03X366660Y265311I0J200D01*
G01X366661Y265312D01*
G02X367648Y265682I987J-1131D01*
G02Y262678I0J-1502D01*
G02X366661Y263048I0J1501D01*
G01X366660D01*
Y263049D01*
G03X366530Y263097I-130J-152D01*
G01X366266D01*
G03X366136Y263049I0J-200D01*
G01X366135Y263048D01*
G02X365148Y262678I-987J1131D01*
G37*
G36*
G01X262786D02*
G02Y265682I0J1502D01*
G02X263773Y265312I0J-1501D01*
G01X263774D01*
Y265311D01*
G03X263904Y265263I130J152D01*
G01X264168D01*
G03X264298Y265311I0J200D01*
G01X264299Y265312D01*
G02X265286Y265682I987J-1131D01*
G02Y262678I0J-1502D01*
G02X264299Y263048I0J1501D01*
G01X264298D01*
Y263049D01*
G03X264168Y263097I-130J-152D01*
G01X263904D01*
G03X263774Y263049I0J-200D01*
G01X263773Y263048D01*
G02X262786Y262678I-987J1131D01*
G37*
G36*
G01X160424D02*
G02Y265682I0J1502D01*
G02X161411Y265312I0J-1501D01*
G01X161412D01*
Y265311D01*
G03X161542Y265263I130J152D01*
G01X161806D01*
G03X161936Y265311I0J200D01*
G01X161937Y265312D01*
G02X162924Y265682I987J-1131D01*
G02Y262678I0J-1502D01*
G02X161937Y263048I0J1501D01*
G01X161936D01*
Y263049D01*
G03X161806Y263097I-130J-152D01*
G01X161542D01*
G03X161412Y263049I0J-200D01*
G01X161411Y263048D01*
G02X160424Y262678I-987J1131D01*
G37*
G36*
G01X431525Y306272D02*
X434925D01*
G02Y302668I0J-1802D01*
G01X431525D01*
G02Y306272I0J1802D01*
G37*
G36*
G01X415777D02*
X419177D01*
G02Y302668I0J-1802D01*
G01X415777D01*
G02Y306272I0J1802D01*
G37*
G36*
G01X61039Y1086151D02*
X61065Y1086525D01*
X61037Y1086603D01*
X61009Y1086633D01*
G02X60607Y1087656I1101J1023D01*
G02X63611I1502J0D01*
G02X63209Y1086633I-1503J0D01*
G01X63181Y1086603D01*
X63153Y1086525D01*
X63179Y1086151D01*
X63217Y1086078D01*
X63249Y1086051D01*
G02X63911Y1084656I-1139J-1395D01*
G02X60307I-1802J0D01*
G02X60969Y1086051I1801J0D01*
G01X61001Y1086078D01*
X61039Y1086151D01*
G37*
G36*
G01X44280Y1255138D02*
X44616D01*
X44683Y1255163D01*
X44711Y1255187D01*
G02X46685I987J-1131D01*
G01X46713Y1255163D01*
X46780Y1255138D01*
X47116D01*
X47183Y1255163D01*
X47211Y1255187D01*
G02X48198Y1255557I987J-1131D01*
G02X49700Y1254055I0J-1502D01*
G02X49330Y1253068I-1501J0D01*
G01X49306Y1253040D01*
X49281Y1252973D01*
Y1252637D01*
X49306Y1252570D01*
X49330Y1252542D01*
G02X49700Y1251555I-1131J-987D01*
G02X48198Y1250053I-1502J0D01*
G02X47211Y1250423I0J1501D01*
G01X47183Y1250447D01*
X47116Y1250472D01*
X46780D01*
X46713Y1250447D01*
X46685Y1250423D01*
G02X44711I-987J1131D01*
G01X44683Y1250447D01*
X44616Y1250472D01*
X44280D01*
X44213Y1250447D01*
X44185Y1250423D01*
G02X43198Y1250053I-987J1131D01*
G02X41696Y1251555I0J1502D01*
G02X42066Y1252542I1501J0D01*
G01X42090Y1252570D01*
X42115Y1252637D01*
Y1252973D01*
X42090Y1253040D01*
X42066Y1253068D01*
G02X41696Y1254055I1131J987D01*
G02X43198Y1255557I1502J0D01*
G02X44185Y1255187I0J-1501D01*
G01X44213Y1255163D01*
X44280Y1255138D01*
G37*
G36*
G01X45408Y84108D02*
Y84460D01*
X45380Y84529D01*
X45354Y84557D01*
G02X44948Y85584I1096J1027D01*
G02X47952I1502J0D01*
G02X47546Y84557I-1502J0D01*
G01X47520Y84529D01*
X47492Y84460D01*
Y84108D01*
X47520Y84039D01*
X47546Y84011D01*
G02Y81957I-1096J-1027D01*
G01X47520Y81929D01*
X47492Y81860D01*
Y81508D01*
X47520Y81439D01*
X47546Y81411D01*
G02Y79357I-1096J-1027D01*
G01X47520Y79329D01*
X47492Y79260D01*
Y78908D01*
X47520Y78839D01*
X47546Y78811D01*
G02Y76757I-1096J-1027D01*
G01X47520Y76729D01*
X47492Y76660D01*
Y76308D01*
X47520Y76239D01*
X47546Y76211D01*
G02X47952Y75184I-1096J-1027D01*
G02X44948I-1502J0D01*
G02X45354Y76211I1502J0D01*
G01X45380Y76239D01*
X45408Y76308D01*
Y76660D01*
X45380Y76729D01*
X45354Y76757D01*
G02Y78811I1096J1027D01*
G01X45380Y78839D01*
X45408Y78908D01*
Y79260D01*
X45380Y79329D01*
X45354Y79357D01*
G02Y81411I1096J1027D01*
G01X45380Y81439D01*
X45408Y81508D01*
Y81860D01*
X45380Y81929D01*
X45354Y81957D01*
G02Y84011I1096J1027D01*
G01X45380Y84039D01*
X45408Y84108D01*
G37*
G36*
G01X46510Y92278D02*
X46822Y92504D01*
X46865Y92578D01*
X46869Y92621D01*
G02X48364Y93975I1495J-148D01*
G02Y90971I0J-1502D01*
G02X48226Y90977I-4J1502D01*
G01X48183Y90981D01*
X48102Y90953D01*
X47821Y90689D01*
X47788Y90610D01*
X47789Y90567D01*
G02X47790Y90512I-1801J-60D01*
G02X45988Y92314I-1802J0D01*
G02X46383Y92270I-1J-1802D01*
G01X46426Y92261D01*
X46510Y92278D01*
G37*
G36*
G01X54886Y101516D02*
X54922Y101900D01*
X54895Y101981D01*
X54866Y102013D01*
G02X54462Y103037I1098J1025D01*
G02X57466I1502J0D01*
G02X56999Y101948I-1503J0D01*
G01X56967Y101918D01*
X56935Y101839D01*
X56948Y101454D01*
X56986Y101377D01*
X57019Y101350D01*
G02X57673Y99961I-1148J-1389D01*
G02X54069I-1802J0D01*
G02X54809Y101417I1802J0D01*
G01X54844Y101442D01*
X54886Y101516D01*
G37*
G36*
G01X74851Y116195D02*
X74970Y116168D01*
G03X75113Y116189I44J195D01*
G02X76005Y116426I893J-1566D01*
G02X76897Y116189I-1J-1803D01*
G03X77040Y116168I99J174D01*
G01X77159Y116195D01*
G03X77278Y116274I-44J195D01*
G02X78501Y116903I1222J-873D01*
G02Y113899I0J-1502D01*
G02X78269Y113917I0J1502D01*
G01X78226Y113924D01*
X78142Y113900D01*
X77877Y113674D01*
G03X77808Y113522I131J-151D01*
G01Y112324D01*
G03X77877Y112172I200J-1D01*
G01X78142Y111946D01*
X78226Y111922D01*
X78269Y111929D01*
G02X78501Y111947I232J-1484D01*
G02Y108943I0J-1502D01*
G02X77278Y109572I-1J1502D01*
G03X77159Y109651I-163J-116D01*
G01X77040Y109678D01*
G03X76897Y109657I-44J-195D01*
G02X76005Y109420I-893J1566D01*
G02X75113Y109657I1J1803D01*
G03X74970Y109678I-99J-174D01*
G01X74851Y109651D01*
G03X74732Y109572I44J-195D01*
G02X73509Y108943I-1222J873D01*
G02Y111947I0J1502D01*
G02X73741Y111929I0J-1502D01*
G01X73784Y111922D01*
X73868Y111946D01*
X74133Y112172D01*
G03X74202Y112324I-131J151D01*
G01Y113522D01*
G03X74133Y113674I-200J1D01*
G01X73868Y113900D01*
X73784Y113924D01*
X73741Y113917D01*
G02X73509Y113899I-232J1484D01*
G02Y116903I0J1502D01*
G02X74732Y116274I1J-1502D01*
G03X74851Y116195I163J116D01*
G37*
G36*
G01Y130368D02*
X74970Y130341D01*
G03X75113Y130362I44J195D01*
G02X76005Y130598I892J-1566D01*
G02X76897Y130362I0J-1802D01*
G03X77040Y130341I99J174D01*
G01X77159Y130368D01*
G03X77278Y130447I-44J195D01*
G02X78501Y131076I1222J-873D01*
G02Y128072I0J-1502D01*
G02X78269Y128090I0J1502D01*
G01X78226Y128097D01*
X78142Y128073D01*
X77877Y127847D01*
G03X77808Y127695I131J-151D01*
G01Y126497D01*
G03X77877Y126345I200J-1D01*
G01X78142Y126119D01*
X78226Y126095D01*
X78269Y126102D01*
G02X78501Y126120I232J-1484D01*
G02Y123116I0J-1502D01*
G02X77278Y123745I-1J1502D01*
G03X77159Y123824I-163J-116D01*
G01X77040Y123851D01*
G03X76897Y123830I-44J-195D01*
G02X76005Y123594I-892J1566D01*
G02X75113Y123830I0J1802D01*
G03X74970Y123851I-99J-174D01*
G01X74851Y123824D01*
G03X74732Y123745I44J-195D01*
G02X73509Y123116I-1222J873D01*
G02Y126120I0J1502D01*
G02X73741Y126102I0J-1502D01*
G01X73784Y126095D01*
X73868Y126119D01*
X74133Y126345D01*
G03X74202Y126497I-131J151D01*
G01Y127695D01*
G03X74133Y127847I-200J1D01*
G01X73868Y128073D01*
X73784Y128097D01*
X73741Y128090D01*
G02X73509Y128072I-232J1484D01*
G02Y131076I0J1502D01*
G02X74732Y130447I1J-1502D01*
G03X74851Y130368I163J116D01*
G37*
G36*
G01X47700Y146496D02*
X47393D01*
G02Y153898I0J3701D01*
G01X54693D01*
G02Y146496I0J-3701D01*
G01X54386D01*
G03X54186Y146296I0J-200D01*
G01Y146236D01*
X54219Y146186D01*
G02X47867I-3176J-2091D01*
G01X47883Y146211D01*
X47900Y146266D01*
Y146296D01*
G03X47700Y146496I-200J0D01*
G37*
G36*
G01X72268Y100457D02*
G02X71608Y101701I842J1244D01*
G02X74612I1502J0D01*
G02X73952Y100457I-1502J0D01*
G03Y99795I224J-331D01*
G02X74612Y98551I-842J-1244D01*
G02X71608I-1502J0D01*
G02X72268Y99795I1502J0D01*
G03Y100457I-224J331D01*
G37*
G36*
G01X64680Y108025D02*
G02X64098Y107908I-581J1385D01*
G02Y110912I0J1502D01*
G02X65586Y109616I0J-1502D01*
G01X65592Y109569D01*
X65645Y109492D01*
X66004Y109290D01*
X66097Y109285D01*
X66141Y109304D01*
G02X66856Y109452I715J-1655D01*
G02X68658Y107649I-1J-1803D01*
G01Y104249D01*
G02X66856Y102446I-1802J-1D01*
G02X66153Y102589I1J1803D01*
G01X66108Y102608D01*
X66011Y102601D01*
X65650Y102375D01*
X65600Y102291D01*
X65598Y102242D01*
G02X64098Y100821I-1500J81D01*
G02Y103825I0J1502D01*
G02X64539Y103759I1J-1502D01*
G01X64586Y103744D01*
X64682Y103762D01*
X65017Y104023D01*
X65058Y104112D01*
X65056Y104161D01*
G02X65054Y104249I1800J85D01*
G01Y107649D01*
G02X65057Y107759I1802J6D01*
G03X64972Y107935I-200J12D01*
G01X64872Y108005D01*
G03X64680Y108025I-114J-164D01*
G37*
G36*
G01X49670Y484205D02*
X49668D01*
G03X49521Y484140I1J-200D01*
G01X49518Y484137D01*
X49513Y484132D01*
X49509Y484128D01*
G02X48390Y483626I-1120J999D01*
G02X46888Y485128I0J1502D01*
G02X48390Y486630I1502J0D01*
G02X49511Y486127I0J-1501D01*
G03X49662Y486060I149J133D01*
G01X49959Y486061D01*
X49961D01*
G03X50108Y486126I-1J200D01*
G01X50111Y486129D01*
X50116Y486134D01*
X50120Y486138D01*
G02X51239Y486640I1120J-999D01*
G02X52225Y486271I0J-1502D01*
G03X52227Y486269I142J140D01*
G03X52357Y486221I130J152D01*
G01X52621D01*
G03X52751Y486269I0J200D01*
G01X52752Y486270D01*
G02X54725Y486271I987J-1131D01*
G03X54727Y486269I142J140D01*
G03X54857Y486221I130J152D01*
G01X55121D01*
G03X55251Y486269I0J200D01*
G01X55252Y486270D01*
G02X56239Y486640I987J-1131D01*
G02X57741Y485138I0J-1502D01*
G02X57474Y484283I-1502J0D01*
G01X57450Y484249D01*
X57434Y484168D01*
X57504Y483843D01*
G03X57583Y483722I196J42D01*
G02X58326Y482425I-761J-1297D01*
G02X55322I-1502J0D01*
G02X55589Y483280I1502J0D01*
G01X55613Y483314D01*
X55629Y483395D01*
X55559Y483720D01*
G03X55481Y483841I-196J-41D01*
G02X55253Y484005I759J1296D01*
G03X55251Y484007I-142J-140D01*
G03X55121Y484055I-130J-152D01*
G01X54857D01*
G03X54727Y484007I0J-200D01*
G01X54726Y484006D01*
G02X52753Y484005I-987J1131D01*
G03X52751Y484007I-142J-140D01*
G03X52621Y484055I-130J-152D01*
G01X52357D01*
G03X52227Y484007I0J-200D01*
G01X52226Y484006D01*
G02X51239Y483636I-987J1131D01*
G02X50118Y484139I0J1501D01*
G03X49967Y484206I-149J-133D01*
G01X49670Y484205D01*
G37*
G36*
G01X67504Y483120D02*
G02X67873Y482134I-1133J-986D01*
G02X64869I-1502J0D01*
G02X65238Y483120I1502J0D01*
G01X65239Y483121D01*
X65240Y483122D01*
G03X65288Y483252I-152J130D01*
G01Y483516D01*
G03X65240Y483646I-200J0D01*
G01X65239Y483647D01*
X65238Y483648D01*
G02X64869Y484634I1133J986D01*
G02X67873I1502J0D01*
G02X67504Y483648I-1502J0D01*
G01X67503Y483647D01*
X67502Y483646D01*
G03X67454Y483516I152J-130D01*
G01Y483252D01*
G03X67502Y483122I200J0D01*
G01X67503Y483121D01*
X67504Y483120D01*
G37*
G36*
G01X57798Y460827D02*
X57800Y460825D01*
G02Y458853I-1132J-986D01*
G01X57798Y458851D01*
G03X57750Y458721I152J-130D01*
G01Y458457D01*
G03X57798Y458327I200J0D01*
G01X57800Y458325D01*
G02X58169Y457339I-1133J-986D01*
G02X56667Y455837I-1502J0D01*
G02X55681Y456206I0J1502D01*
G03X55679Y456208I-142J-140D01*
G03X55549Y456256I-130J-152D01*
G01X55285D01*
G03X55155Y456208I0J-200D01*
G01X55154Y456207D01*
G02X54167Y455837I-987J1131D01*
G02X52665Y457339I0J1502D01*
G02X53034Y458325I1502J0D01*
G01X53036Y458327D01*
G03X53084Y458457I-152J130D01*
G01Y458721D01*
G03X53036Y458851I-200J0D01*
G01X53034Y458853D01*
G02Y460825I1132J986D01*
G01X53036Y460827D01*
G03X53084Y460957I-152J130D01*
G01Y461221D01*
G03X53036Y461351I-200J0D01*
G01X53034Y461353D01*
G02X52665Y462339I1133J986D01*
G02X54167Y463841I1502J0D01*
G02X55153Y463472I0J-1502D01*
G03X55155Y463470I142J140D01*
G03X55285Y463422I130J152D01*
G01X55549D01*
G03X55679Y463470I0J200D01*
G01X55680Y463471D01*
G02X56281Y463790I986J-1133D01*
G01X56324Y463801D01*
X56359Y463830D01*
G02X56361Y463832I142J-140D01*
G01X56394Y463858D01*
X56546Y464163D01*
G03X56557Y464316I-179J90D01*
G01X56551Y464334D01*
X56549Y464339D01*
G02X56422Y465001I1675J665D01*
G01Y465004D01*
G02X60026I1802J0D01*
G02X58456Y463217I-1802J0D01*
G01X58413Y463211D01*
X58340Y463166D01*
X58124Y462842D01*
X58109Y462758D01*
X58120Y462716D01*
G02X58169Y462339I-1453J-380D01*
G02X57800Y461353I-1502J0D01*
G01X57798Y461351D01*
G03X57750Y461221I152J-130D01*
G01Y460957D01*
G03X57798Y460827I200J0D01*
G37*
G36*
G01X56141Y476931D02*
G02X56626Y475826I-1017J-1105D01*
G01Y475825D01*
G02X55222Y474326I-1502J0D01*
G01X55168Y474322D01*
X55081Y474265D01*
X54876Y473863D01*
X54881Y473757D01*
X54910Y473712D01*
G02X55145Y472905I-1268J-807D01*
G02X52141I-1502J0D01*
G02X53545Y474404I1502J0D01*
G01X53599Y474408D01*
X53686Y474465D01*
X53891Y474867D01*
X53886Y474973D01*
X53857Y475018D01*
G02X53622Y475825I1268J807D01*
G01Y475826D01*
G02X54107Y476931I1502J0D01*
G03X54172Y477078I-135J148D01*
G01Y477372D01*
G03X54107Y477519I-200J-1D01*
G02X53622Y478624I1017J1105D01*
G01Y478625D01*
G02X56626I1502J0D01*
G01Y478624D01*
G02X56141Y477519I-1502J0D01*
G03X56076Y477372I135J-148D01*
G01Y477078D01*
G03X56141Y476931I200J1D01*
G37*
G36*
G01X70947Y476934D02*
X70949Y476932D01*
G02X71318Y475946I-1133J-986D01*
G02X68314I-1502J0D01*
G02X68683Y476932I1502J0D01*
G01X68685Y476934D01*
G03X68733Y477064I-152J130D01*
G01Y477328D01*
G03X68685Y477458I-200J0D01*
G01X68683Y477460D01*
G02X68314Y478446I1133J986D01*
G02X69816Y479948I1502J0D01*
G02X69928Y479944I2J-1502D01*
G01X69929D01*
X69976Y479941D01*
X70018Y479957D01*
G03X70075Y479992I-75J186D01*
G03X70094Y480011I-132J151D01*
G01X70336Y480284D01*
X70348Y480329D01*
X70360Y480373D01*
X70352Y480419D01*
Y480422D01*
X70349Y480440D01*
G02X70324Y480705I1476J273D01*
G02X71826Y482207I1502J0D01*
G02X72812Y481838I0J-1502D01*
G03X72814Y481836I142J140D01*
G03X72944Y481788I130J152D01*
G01X73208D01*
G03X73338Y481836I0J200D01*
G01X73339Y481837D01*
G02X74326Y482207I987J-1131D01*
G02Y479203I0J-1502D01*
G02X73340Y479572I0J1502D01*
G03X73338Y479574I-142J-140D01*
G03X73208Y479622I-130J-152D01*
G01X72944D01*
G03X72814Y479574I0J-200D01*
G01X72813Y479573D01*
G02X71826Y479203I-987J1131D01*
G02X71714Y479207I-2J1502D01*
G01X71713D01*
X71666Y479210D01*
X71624Y479194D01*
G03X71567Y479159I75J-186D01*
G03X71548Y479140I132J-151D01*
G01X71306Y478867D01*
X71294Y478822D01*
X71282Y478778D01*
X71290Y478732D01*
Y478729D01*
X71293Y478711D01*
G02X71318Y478446I-1476J-273D01*
G02X70949Y477460I-1502J0D01*
G01X70947Y477458D01*
G03X70899Y477328I152J-130D01*
G01Y477064D01*
G03X70947Y476934I200J0D01*
G37*
G36*
G01X79164Y479574D02*
X79166Y479572D01*
G02Y477600I-1132J-986D01*
G01X79164Y477598D01*
G03X79116Y477468I152J-130D01*
G01Y477204D01*
G03X79164Y477074I200J0D01*
G01X79166Y477072D01*
G02X79535Y476086I-1133J-986D01*
G02X76531I-1502J0D01*
G02X76900Y477072I1502J0D01*
G01X76902Y477074D01*
G03X76950Y477204I-152J130D01*
G01Y477468D01*
G03X76902Y477598I-200J0D01*
G01X76900Y477600D01*
G02Y479572I1132J986D01*
G01X76902Y479574D01*
G03X76950Y479704I-152J130D01*
G01Y479968D01*
G03X76902Y480098I-200J0D01*
G01X76900Y480100D01*
G02Y482072I1132J986D01*
G01X76902Y482074D01*
G03X76950Y482204I-152J130D01*
G01Y482468D01*
G03X76902Y482598I-200J0D01*
G01X76900Y482600D01*
G02X76531Y483586I1133J986D01*
G02X79535I1502J0D01*
G02X79166Y482600I-1502J0D01*
G01X79164Y482598D01*
G03X79116Y482468I152J-130D01*
G01Y482204D01*
G03X79164Y482074I200J0D01*
G01X79166Y482072D01*
G02Y480100I-1132J-986D01*
G01X79164Y480098D01*
G03X79116Y479968I152J-130D01*
G01Y479704D01*
G03X79164Y479574I200J0D01*
G37*
G36*
G01X65644Y572121D02*
G02X64408Y571473I-1236J855D01*
G02Y574477I0J1502D01*
G02X65710Y573724I0J-1502D01*
G03X66386Y573696I347J199D01*
G02X67622Y574344I1236J-855D01*
G02Y571340I0J-1502D01*
G02X66320Y572093I0J1502D01*
G03X65644Y572121I-347J-199D01*
G37*
G36*
G01X147770Y84108D02*
Y84460D01*
X147742Y84529D01*
X147716Y84557D01*
G02X147310Y85584I1096J1027D01*
G02X150314I1502J0D01*
G02X149908Y84557I-1502J0D01*
G01X149882Y84529D01*
X149854Y84460D01*
Y84108D01*
X149882Y84039D01*
X149908Y84011D01*
G02Y81957I-1096J-1027D01*
G01X149882Y81929D01*
X149854Y81860D01*
Y81508D01*
X149882Y81439D01*
X149908Y81411D01*
G02Y79357I-1096J-1027D01*
G01X149882Y79329D01*
X149854Y79260D01*
Y78908D01*
X149882Y78839D01*
X149908Y78811D01*
G02Y76757I-1096J-1027D01*
G01X149882Y76729D01*
X149854Y76660D01*
Y76308D01*
X149882Y76239D01*
X149908Y76211D01*
G02X150314Y75184I-1096J-1027D01*
G02X147310I-1502J0D01*
G02X147716Y76211I1502J0D01*
G01X147742Y76239D01*
X147770Y76308D01*
Y76660D01*
X147742Y76729D01*
X147716Y76757D01*
G02Y78811I1096J1027D01*
G01X147742Y78839D01*
X147770Y78908D01*
Y79260D01*
X147742Y79329D01*
X147716Y79357D01*
G02Y81411I1096J1027D01*
G01X147742Y81439D01*
X147770Y81508D01*
Y81860D01*
X147742Y81929D01*
X147716Y81957D01*
G02Y84011I1096J1027D01*
G01X147742Y84039D01*
X147770Y84108D01*
G37*
G36*
G01X177213Y116195D02*
X177332Y116168D01*
G03X177475Y116189I44J195D01*
G02X178367Y116426I893J-1566D01*
G02X179259Y116189I-1J-1803D01*
G03X179402Y116168I99J174D01*
G01X179521Y116195D01*
G03X179640Y116274I-44J195D01*
G02X180863Y116903I1222J-873D01*
G02Y113899I0J-1502D01*
G02X180631Y113917I0J1502D01*
G01X180588Y113924D01*
X180504Y113900D01*
X180239Y113674D01*
G03X180170Y113522I131J-151D01*
G01Y112324D01*
G03X180239Y112172I200J-1D01*
G01X180504Y111946D01*
X180588Y111922D01*
X180631Y111929D01*
G02X180863Y111947I232J-1484D01*
G02Y108943I0J-1502D01*
G02X179640Y109572I-1J1502D01*
G03X179521Y109651I-163J-116D01*
G01X179402Y109678D01*
G03X179259Y109657I-44J-195D01*
G02X178367Y109420I-893J1566D01*
G02X177475Y109657I1J1803D01*
G03X177332Y109678I-99J-174D01*
G01X177213Y109651D01*
G03X177094Y109572I44J-195D01*
G02X175871Y108943I-1222J873D01*
G02Y111947I0J1502D01*
G02X176103Y111929I0J-1502D01*
G01X176146Y111922D01*
X176230Y111946D01*
X176495Y112172D01*
G03X176564Y112324I-131J151D01*
G01Y113522D01*
G03X176495Y113674I-200J1D01*
G01X176230Y113900D01*
X176146Y113924D01*
X176103Y113917D01*
G02X175871Y113899I-232J1484D01*
G02Y116903I0J1502D01*
G02X177094Y116274I1J-1502D01*
G03X177213Y116195I163J116D01*
G37*
G36*
G01Y130368D02*
X177332Y130341D01*
G03X177475Y130362I44J195D01*
G02X178367Y130598I892J-1566D01*
G02X179259Y130362I0J-1802D01*
G03X179402Y130341I99J174D01*
G01X179521Y130368D01*
G03X179640Y130447I-44J195D01*
G02X180863Y131076I1222J-873D01*
G02Y128072I0J-1502D01*
G02X180631Y128090I0J1502D01*
G01X180588Y128097D01*
X180504Y128073D01*
X180239Y127847D01*
G03X180170Y127695I131J-151D01*
G01Y126497D01*
G03X180239Y126345I200J-1D01*
G01X180504Y126119D01*
X180588Y126095D01*
X180631Y126102D01*
G02X180863Y126120I232J-1484D01*
G02Y123116I0J-1502D01*
G02X179640Y123745I-1J1502D01*
G03X179521Y123824I-163J-116D01*
G01X179402Y123851D01*
G03X179259Y123830I-44J-195D01*
G02X178367Y123594I-892J1566D01*
G02X177475Y123830I0J1802D01*
G03X177332Y123851I-99J-174D01*
G01X177213Y123824D01*
G03X177094Y123745I44J-195D01*
G02X175871Y123116I-1222J873D01*
G02Y126120I0J1502D01*
G02X176103Y126102I0J-1502D01*
G01X176146Y126095D01*
X176230Y126119D01*
X176495Y126345D01*
G03X176564Y126497I-131J151D01*
G01Y127695D01*
G03X176495Y127847I-200J1D01*
G01X176230Y128073D01*
X176146Y128097D01*
X176103Y128090D01*
G02X175871Y128072I-232J1484D01*
G02Y131076I0J1502D01*
G02X177094Y130447I1J-1502D01*
G03X177213Y130368I163J116D01*
G37*
G36*
G01X150062Y146496D02*
X149755D01*
G02Y153898I0J3701D01*
G01X157055D01*
G02Y146496I0J-3701D01*
G01X156748D01*
G03X156548Y146296I0J-200D01*
G01Y146236D01*
X156581Y146186D01*
G02X150229I-3176J-2091D01*
G01X150245Y146211D01*
X150262Y146266D01*
Y146296D01*
G03X150062Y146496I-200J0D01*
G37*
G36*
G01X149876Y92655D02*
X149871Y92709D01*
G02X149864Y92849I1495J145D01*
G02X152868I1502J0D01*
G02X152865Y92747I-1502J-7D01*
G01X152861Y92696D01*
X152900Y92607D01*
X153238Y92340D01*
X153333Y92322D01*
X153381Y92337D01*
G02X153912Y92417I531J-1722D01*
G02X152110Y90615I0J-1802D01*
G02X152136Y90917I1802J-3D01*
G01X152144Y90967D01*
X152114Y91059D01*
X151805Y91359D01*
X151712Y91386D01*
X151662Y91377D01*
G02X151366Y91347I-299J1472D01*
G02X150893Y91424I2J1502D01*
G01X150841Y91441D01*
X150739Y91420D01*
X150398Y91124D01*
X150363Y91026D01*
X150373Y90972D01*
G02X150402Y90650I-1773J-322D01*
G02X148600Y92452I-1802J0D01*
G02X149314Y92305I1J-1802D01*
G01X149363Y92283D01*
X149467Y92295D01*
X149833Y92560D01*
X149876Y92655D01*
G37*
G36*
G01X174630Y100457D02*
G02X173970Y101701I842J1244D01*
G02X176974I1502J0D01*
G02X176314Y100457I-1502J0D01*
G03Y99795I224J-331D01*
G02X176974Y98551I-842J-1244D01*
G02X173970I-1502J0D01*
G02X174630Y99795I1502J0D01*
G03Y100457I-224J331D01*
G37*
G36*
G01X157407Y101849D02*
G02X156824Y103037I919J1188D01*
G02X159828I1502J0D01*
G02X159172Y101796I-1502J0D01*
G03X159152Y101149I225J-331D01*
G02X159735Y99961I-919J-1188D01*
G02X156731I-1502J0D01*
G02X157387Y101202I1502J0D01*
G03X157407Y101849I-225J331D01*
G37*
G36*
G01X167042Y108025D02*
G02X166460Y107908I-581J1385D01*
G02Y110912I0J1502D01*
G02X167948Y109616I0J-1502D01*
G01X167954Y109569D01*
X168007Y109492D01*
X168366Y109290D01*
X168459Y109285D01*
X168503Y109304D01*
G02X169218Y109452I715J-1655D01*
G02X171020Y107649I-1J-1803D01*
G01Y104249D01*
G02X169218Y102446I-1802J-1D01*
G02X168515Y102589I1J1803D01*
G01X168470Y102608D01*
X168373Y102601D01*
X168012Y102375D01*
X167962Y102291D01*
X167960Y102242D01*
G02X166460Y100821I-1500J81D01*
G02Y103825I0J1502D01*
G02X166901Y103759I1J-1502D01*
G01X166948Y103744D01*
X167044Y103762D01*
X167379Y104023D01*
X167420Y104112D01*
X167418Y104161D01*
G02X167416Y104249I1800J85D01*
G01Y107649D01*
G02X167419Y107759I1802J6D01*
G03X167334Y107935I-200J12D01*
G01X167234Y108005D01*
G03X167042Y108025I-114J-164D01*
G37*
G36*
G01X182482Y1143639D02*
G02X182030Y1143188I-452J1D01*
G01X180989D01*
X180937Y1143181D01*
G02X180610Y1143137I-329J1208D01*
G02Y1145641I0J1252D01*
G02X180937Y1145597I-2J-1252D01*
G01X180963Y1145590D01*
X182030D01*
X182031D01*
G02X182482Y1145139I0J-451D01*
G01Y1143639D01*
G37*
G36*
G01X193250Y1146928D02*
X192183D01*
X192157Y1146921D01*
G02X191830Y1146877I-329J1208D01*
G02Y1149381I0J1252D01*
G02X192157Y1149337I-2J-1252D01*
G01X192183Y1149330D01*
X193250D01*
G02X193702Y1148879I1J-451D01*
G01Y1147379D01*
G02X193250Y1146928I-452J1D01*
G37*
G36*
G01X190628Y1155963D02*
Y1157030D01*
G02X191080Y1157482I452J0D01*
G01X192580D01*
G02X193032Y1157030I0J-452D01*
G01Y1155963D01*
X193038Y1155937D01*
G02X193082Y1155610I-1208J-329D01*
G02X190578I-1252J0D01*
G02X190622Y1155937I1252J-2D01*
G01X190628Y1155963D01*
G37*
G36*
G01X194368Y1157930D02*
Y1158997D01*
X194362Y1159023D01*
G02X194318Y1159350I1208J329D01*
G02X196822I1252J0D01*
G02X196778Y1159023I-1252J2D01*
G01X196772Y1158997D01*
Y1157930D01*
G02X196320Y1157478I-452J0D01*
G01X194820D01*
G02X194368Y1157930I0J452D01*
G37*
G36*
G01X201850D02*
Y1158997D01*
X201843Y1159023D01*
G02X201799Y1159350I1208J329D01*
G02X204303I1252J0D01*
G02X204259Y1159023I-1252J2D01*
G01X204252Y1158997D01*
Y1157930D01*
G02X203801Y1157478I-451J-1D01*
G01X202301D01*
G02X201850Y1157930I1J452D01*
G37*
G36*
G01X216810D02*
Y1158997D01*
X216803Y1159023D01*
G02X216759Y1159350I1208J329D01*
G02X219263I1252J0D01*
G02X219219Y1159023I-1252J2D01*
G01X219212Y1158997D01*
Y1157930D01*
G02X218761Y1157478I-451J-1D01*
G01X217261D01*
G02X216810Y1157930I1J452D01*
G37*
G36*
G01X235510D02*
Y1158997D01*
X235504Y1159023D01*
G02X235460Y1159350I1208J329D01*
G02X237964I1252J0D01*
G02X237920Y1159023I-1252J2D01*
G01X237914Y1158997D01*
Y1157930D01*
G02X237462Y1157478I-452J0D01*
G01X235962D01*
G02X235510Y1157930I0J452D01*
G37*
G36*
G01X250472D02*
Y1158997D01*
X250465Y1159023D01*
G02X250421Y1159350I1208J329D01*
G02X252925I1252J0D01*
G02X252881Y1159023I-1252J2D01*
G01X252874Y1158997D01*
Y1157930D01*
G02X252423Y1157478I-451J-1D01*
G01X250923D01*
G02X250472Y1157930I1J452D01*
G37*
G36*
G01X206190Y1160891D02*
Y1163691D01*
G02X206642Y1164142I452J-1D01*
G01X209842D01*
G02X210294Y1163691I1J-451D01*
G01Y1161809D01*
G03X210352Y1161668I200J0D01*
G01X210814Y1161207D01*
G02X211041Y1160865I-746J-741D01*
G01X211231Y1160407D01*
X211263Y1160366D01*
X211285Y1160349D01*
G02X211783Y1159350I-753J-999D01*
G02X211739Y1159023I-1252J2D01*
G01X211732Y1158997D01*
Y1157930D01*
G02X211281Y1157478I-451J-1D01*
G01X209781D01*
G02X209330Y1157930I1J452D01*
G01Y1158997D01*
X209323Y1159023D01*
G02X209279Y1159350I1208J329D01*
G02X209291Y1159524I1252J1D01*
G01X209295Y1159551D01*
X209288Y1159602D01*
X209194Y1159831D01*
G03X209150Y1159896I-185J-78D01*
G01X208665Y1160381D01*
G03X208524Y1160440I-142J-141D01*
G01X206642D01*
G02X206190Y1160891I-1J451D01*
G37*
G36*
G01X221152D02*
Y1163691D01*
G02X221603Y1164142I451J0D01*
G01X224803D01*
G02X225254Y1163691I0J-451D01*
G01Y1161809D01*
G03X225313Y1161668I200J1D01*
G01X226236Y1160746D01*
G02X226541Y1160077I-744J-743D01*
G03X226568Y1159990I199J14D01*
G02X226744Y1159350I-1076J-640D01*
G02X226700Y1159023I-1252J2D01*
G01X226694Y1158997D01*
Y1157930D01*
G02X226242Y1157478I-452J0D01*
G01X224742D01*
G02X224290Y1157930I0J452D01*
G01Y1158997D01*
X224284Y1159023D01*
G02X224240Y1159350I1208J329D01*
G02X224267Y1159611I1252J2D01*
G01X224278Y1159661D01*
X224250Y1159757D01*
X223626Y1160381D01*
G03X223485Y1160440I-142J-141D01*
G01X221603D01*
G02X221152Y1160891I0J451D01*
G37*
G36*
G01X239852D02*
Y1163691D01*
G02X240304Y1164142I452J-1D01*
G01X243504D01*
G02X243956Y1163691I1J-451D01*
G01Y1161809D01*
G03X244014Y1161668I200J0D01*
G01X244936Y1160747D01*
G02X245241Y1160077I-744J-743D01*
G03X245268Y1159989I200J13D01*
G02X245444Y1159350I-1076J-640D01*
G02X245400Y1159023I-1252J2D01*
G01X245394Y1158997D01*
Y1157930D01*
G02X244942Y1157478I-452J0D01*
G01X243442D01*
G02X242990Y1157930I0J452D01*
G01Y1158997D01*
X242984Y1159023D01*
G02X242940Y1159350I1208J329D01*
G02X242968Y1159611I1252J-2D01*
G01X242978Y1159662D01*
X242950Y1159758D01*
X242327Y1160381D01*
G03X242186Y1160440I-142J-141D01*
G01X240304D01*
G02X239852Y1160891I-1J451D01*
G37*
G36*
G01X192230Y1165628D02*
G02X192217Y1165629I28J450D01*
G03X192158Y1165622I-6J-200D01*
G02X191830Y1165578I-329J1208D01*
G02Y1168082I0J1252D01*
G02X192158Y1168038I-1J-1252D01*
G03X192217Y1168031I53J193D01*
G02X192230Y1168032I41J-449D01*
G01X193430D01*
G02X193882Y1167580I0J-452D01*
G01Y1166080D01*
G02X193430Y1165628I-452J0D01*
G01X192230D01*
G37*
G36*
G01X199711D02*
G02X199698Y1165629I28J450D01*
G03X199639Y1165622I-6J-200D01*
G02X199311Y1165578I-329J1208D01*
G02Y1168082I0J1252D01*
G02X199639Y1168038I-1J-1252D01*
G03X199698Y1168031I53J193D01*
G02X199711Y1168032I41J-449D01*
G01X200911D01*
G02X201362Y1167580I-1J-452D01*
G01Y1166080D01*
G02X200911Y1165628I-451J-1D01*
G01X199711D01*
G37*
G36*
G01X207191D02*
G02X207178Y1165629I28J450D01*
G03X207119Y1165622I-6J-200D01*
G02X206791Y1165578I-329J1208D01*
G02Y1168082I0J1252D01*
G02X207119Y1168038I-1J-1252D01*
G03X207178Y1168031I53J193D01*
G02X207191Y1168032I41J-449D01*
G01X208391D01*
G02X208842Y1167580I-1J-452D01*
G01Y1166080D01*
G02X208391Y1165628I-451J-1D01*
G01X207191D01*
G37*
G36*
G01X214671D02*
G02X214658Y1165629I28J450D01*
G03X214599Y1165622I-6J-200D01*
G02X214271Y1165578I-329J1208D01*
G02Y1168082I0J1252D01*
G02X214599Y1168038I-1J-1252D01*
G03X214658Y1168031I53J193D01*
G02X214671Y1168032I41J-449D01*
G01X215871D01*
G02X216322Y1167580I-1J-452D01*
G01Y1166080D01*
G02X215871Y1165628I-451J-1D01*
G01X214671D01*
G37*
G36*
G01X222152D02*
G02X222139Y1165629I28J450D01*
G03X222080Y1165622I-6J-200D01*
G02X221752Y1165578I-329J1208D01*
G02Y1168082I0J1252D01*
G02X222080Y1168038I-1J-1252D01*
G03X222139Y1168031I53J193D01*
G02X222152Y1168032I41J-449D01*
G01X223352D01*
G02X223804Y1167580I0J-452D01*
G01Y1166080D01*
G02X223352Y1165628I-452J0D01*
G01X222152D01*
G37*
G36*
G01X230732D02*
X229585D01*
X229559Y1165622D01*
G02X229232Y1165578I-329J1208D01*
G02Y1168082I0J1252D01*
G02X229559Y1168038I-2J-1252D01*
G01X229585Y1168032D01*
X230732D01*
G02X231184Y1167580I0J-452D01*
G01Y1166080D01*
G02X230732Y1165628I-452J0D01*
G37*
G36*
G01X249433D02*
X248286D01*
X248260Y1165622D01*
G02X247933Y1165578I-329J1208D01*
G02Y1168082I0J1252D01*
G02X248260Y1168038I-2J-1252D01*
G01X248286Y1168032D01*
X249433D01*
G02X249884Y1167580I-1J-452D01*
G01Y1166080D01*
G02X249433Y1165628I-451J-1D01*
G37*
G36*
G01X256913D02*
X255766D01*
X255740Y1165622D01*
G02X255413Y1165578I-329J1208D01*
G02Y1168082I0J1252D01*
G02X255740Y1168038I-2J-1252D01*
G01X255766Y1168032D01*
X256913D01*
G02X257364Y1167580I-1J-452D01*
G01Y1166080D01*
G02X256913Y1165628I-451J-1D01*
G37*
G36*
G01X241009Y1167952D02*
X241014D01*
G02X241350Y1168102I336J-301D01*
G01X242550D01*
G02X243002Y1167650I0J-452D01*
G01Y1166150D01*
G02X242550Y1165698I-452J0D01*
G01X241350D01*
G02X241190Y1165728I2J452D01*
G03X241028Y1165718I-70J-187D01*
G02X240452Y1165578I-575J1112D01*
G02X239909Y1165702I0J1251D01*
G03X239769Y1165715I-87J-180D01*
G02X239650Y1165698I-123J434D01*
G01X238450D01*
G02X237998Y1166150I0J452D01*
G01Y1167650D01*
G02X238450Y1168102I452J0D01*
G01X239650D01*
G02X239885Y1168035I-2J-452D01*
G03X240053Y1168017I103J171D01*
G02X240452Y1168082I398J-1187D01*
G02X241009Y1167952I1J-1252D01*
G37*
G36*
G01X194368Y1170923D02*
Y1171990D01*
G02X194820Y1172442I452J0D01*
G01X196320D01*
G02X196772Y1171990I0J-452D01*
G01Y1170923D01*
X196778Y1170897D01*
G02X196822Y1170570I-1208J-329D01*
G02X194318I-1252J0D01*
G02X194362Y1170897I1252J-2D01*
G01X194368Y1170923D01*
G37*
G36*
G01X201850D02*
Y1171990D01*
G02X202301Y1172442I451J1D01*
G01X203801D01*
G02X204252Y1171990I-1J-452D01*
G01Y1170923D01*
X204259Y1170897D01*
G02X204303Y1170570I-1208J-329D01*
G02X201799I-1252J0D01*
G02X201843Y1170897I1252J-2D01*
G01X201850Y1170923D01*
G37*
G36*
G01X209330D02*
Y1171990D01*
G02X209781Y1172442I451J1D01*
G01X211281D01*
G02X211732Y1171990I-1J-452D01*
G01Y1170923D01*
X211739Y1170897D01*
G02X211783Y1170570I-1208J-329D01*
G02X209279I-1252J0D01*
G02X209323Y1170897I1252J-2D01*
G01X209330Y1170923D01*
G37*
G36*
G01X216810D02*
Y1171990D01*
G02X217261Y1172442I451J1D01*
G01X218761D01*
G02X219212Y1171990I-1J-452D01*
G01Y1170923D01*
X219219Y1170897D01*
G02X219263Y1170570I-1208J-329D01*
G02X216759I-1252J0D01*
G02X216803Y1170897I1252J-2D01*
G01X216810Y1170923D01*
G37*
G36*
G01X224290D02*
Y1171990D01*
G02X224742Y1172442I452J0D01*
G01X226242D01*
G02X226694Y1171990I0J-452D01*
G01Y1170923D01*
X226700Y1170897D01*
G02X226744Y1170570I-1208J-329D01*
G02X224240I-1252J0D01*
G02X224284Y1170897I1252J-2D01*
G01X224290Y1170923D01*
G37*
G36*
G01X235510D02*
Y1171990D01*
G02X235962Y1172442I452J0D01*
G01X237462D01*
G02X237914Y1171990I0J-452D01*
G01Y1170923D01*
X237920Y1170897D01*
G02X237964Y1170570I-1208J-329D01*
G02X235460I-1252J0D01*
G02X235504Y1170897I1252J-2D01*
G01X235510Y1170923D01*
G37*
G36*
G01X242990D02*
Y1171990D01*
G02X243442Y1172442I452J0D01*
G01X244942D01*
G02X245394Y1171990I0J-452D01*
G01Y1170923D01*
X245400Y1170897D01*
G02X245444Y1170570I-1208J-329D01*
G02X242940I-1252J0D01*
G02X242984Y1170897I1252J-2D01*
G01X242990Y1170923D01*
G37*
G36*
G01X250472D02*
Y1171990D01*
G02X250923Y1172442I451J1D01*
G01X252423D01*
G02X252874Y1171990I-1J-452D01*
G01Y1170923D01*
X252881Y1170897D01*
G02X252925Y1170570I-1208J-329D01*
G02X250421I-1252J0D01*
G02X250465Y1170897I1252J-2D01*
G01X250472Y1170923D01*
G37*
G36*
G01X190628Y1172890D02*
Y1173957D01*
X190622Y1173983D01*
G02X190578Y1174310I1208J329D01*
G02X193082I1252J0D01*
G02X193038Y1173983I-1252J2D01*
G01X193032Y1173957D01*
Y1172890D01*
G02X192580Y1172438I-452J0D01*
G01X191080D01*
G02X190628Y1172890I0J452D01*
G37*
G36*
G01X193250Y1180590D02*
X192183D01*
X192157Y1180583D01*
G02X191830Y1180539I-329J1208D01*
G02Y1183043I0J1252D01*
G02X192157Y1182999I-2J-1252D01*
G01X192183Y1182992D01*
X193250D01*
G02X193702Y1182541I1J-451D01*
G01Y1181041D01*
G02X193250Y1180590I-452J1D01*
G37*
G36*
G01X199657Y1149888D02*
X199686Y1149902D01*
X200224Y1150440D01*
G02X200365Y1150498I141J-142D01*
G01X266868D01*
G02X267718Y1150146I0J-1201D01*
G01X268099Y1149765D01*
G02X268452Y1148915I-849J-851D01*
G01Y1147879D01*
G02X268099Y1147029I-1202J1D01*
G01X267518Y1146448D01*
G02X266668Y1146096I-850J849D01*
G01X200671D01*
G02X200530Y1146154I0J200D01*
G01X199781Y1146903D01*
X199678Y1146931D01*
X199627Y1146917D01*
G02X199311Y1146877I-314J1212D01*
G02X198059Y1148129I0J1252D01*
G02X198997Y1149341I1252J0D01*
G01X199023Y1149348D01*
X199069Y1149374D01*
X199387Y1149693D01*
G02X199657Y1149888I743J-744D01*
G37*
G36*
G01X266959Y1156819D02*
X266984Y1156812D01*
X270022D01*
X270047Y1156819D01*
G02X270373Y1156862I325J-1209D01*
G02Y1154358I0J-1252D01*
G02X270047Y1154401I-1J1252D01*
G01X270022Y1154408D01*
X266984D01*
X266959Y1154401D01*
G02X266633Y1154358I-325J1209D01*
G02Y1156862I0J1252D01*
G02X266959Y1156819I1J-1252D01*
G37*
G36*
G01X268393Y1180986D02*
X266853Y1179446D01*
G02X266712Y1179388I-141J142D01*
G01X199092D01*
G02X198951Y1179446I0J200D01*
G01X197653Y1180744D01*
G02X197594Y1180885I141J142D01*
G01Y1182662D01*
G02X197653Y1182803I200J-1D01*
G01X198458Y1183608D01*
G02X198599Y1183666I141J-142D01*
G01X267480D01*
G02X267621Y1183608I0J-200D01*
G01X268393Y1182836D01*
G02X268452Y1182695I-141J-142D01*
G01Y1181127D01*
G02X268393Y1180986I-200J1D01*
G37*
G36*
G01X275710Y498050D02*
G02Y505454I0J3702D01*
G01X283010D01*
G02Y498050I0J-3702D01*
G01X275710D01*
G37*
G36*
G01X320382Y323056D02*
G02X321359Y321649I-525J-1407D01*
G02X318355I-1502J0D01*
G01Y321650D01*
G02X318406Y322036I1502J-2D01*
G01X318413Y322062D01*
X318424Y322102D01*
X318419Y322142D01*
X318414Y322185D01*
X318222Y322507D01*
X318157Y322554D01*
X318116Y322563D01*
G02X316706Y324322I392J1759D01*
G02X318508Y326124I1802J0D01*
G02X320310Y324322I0J-1802D01*
G02X320172Y323632I-1802J2D01*
G01X320171Y323630D01*
X320153Y323583D01*
G03X320141Y323479I186J-74D01*
G01X320145Y323453D01*
X320282Y323129D01*
X320312Y323101D01*
X320343Y323071D01*
X320382Y323056D01*
G37*
G36*
G01X366552Y454543D02*
G02X365762Y456034I1012J1491D01*
G02X369366I1802J0D01*
G02X368561Y454531I-1806J0D01*
G01X368521Y454505D01*
X368475Y454424D01*
X368455Y454058D01*
G03X368471Y453967I200J-12D01*
G01X368481Y453945D01*
X368508Y453909D01*
X368526Y453894D01*
G02X369066Y452740I-963J-1154D01*
G02X366062I-1502J0D01*
G02X366602Y453894I1503J0D01*
G01X366620Y453909D01*
X366647Y453945D01*
X366657Y453967D01*
G03X366673Y454059I-184J79D01*
G01X366656Y454372D01*
G03X366598Y454502I-200J-11D01*
G01X366568Y454532D01*
X366552Y454543D01*
G37*
G36*
G01X370234Y466834D02*
Y466542D01*
G03X370299Y466394I200J0D01*
G02X370784Y465289I-1017J-1105D01*
G01Y465288D01*
G02X367780I-1502J0D01*
G01Y465289D01*
G02X368265Y466394I1502J0D01*
G03X368330Y466542I-135J148D01*
G01Y466834D01*
G03X368265Y466982I-200J0D01*
G02X367780Y468087I1017J1105D01*
G01Y468088D01*
G02X370784I1502J0D01*
G01Y468087D01*
G02X370299Y466982I-1502J0D01*
G03X370234Y466834I135J-148D01*
G37*
G36*
G01X375059Y471133D02*
G02X376046Y471503I987J-1131D01*
G02Y468499I0J-1502D01*
G02X375060Y468868I0J1502D01*
G03X375058Y468870I-142J-140D01*
G03X374928Y468918I-130J-152D01*
G01X374664D01*
G03X374534Y468870I0J-200D01*
G01X374533Y468869D01*
G02X373546Y468499I-987J1131D01*
G02Y471503I0J1502D01*
G02X374532Y471134I0J-1502D01*
G03X374534Y471132I142J140D01*
G03X374664Y471084I130J152D01*
G01X374928D01*
G03X375058Y471132I0J200D01*
G01X375059Y471133D01*
G37*
G36*
G01X322796Y469606D02*
Y468406D01*
G03X322866Y468254I200J0D01*
G01X323130Y468029D01*
X323214Y468005D01*
X323257Y468012D01*
G02X323489Y468030I232J-1484D01*
G02Y465026I0J-1502D01*
G02X322266Y465655I0J1503D01*
G01X322244Y465686D01*
X322183Y465726D01*
X322030Y465760D01*
G03X321960Y465763I-43J-195D01*
G01X321917Y465757D01*
X321882Y465737D01*
G02X320993Y465502I-890J1568D01*
G02X320102Y465738I1J1803D01*
G01X320069Y465757D01*
X319997Y465768D01*
X319803Y465726D01*
X319742Y465686D01*
X319720Y465655D01*
G02X318497Y465026I-1223J874D01*
G02Y468030I0J1502D01*
G02X318729Y468012I0J-1502D01*
G01X318772Y468005D01*
X318856Y468029D01*
X319120Y468254D01*
G03X319190Y468406I-130J152D01*
G01Y469606D01*
G03X319120Y469758I-200J0D01*
G01X318856Y469983D01*
X318772Y470007D01*
X318729Y470000D01*
G02X318497Y469982I-232J1484D01*
G02Y472986I0J1502D01*
G02X319702Y472379I0J-1500D01*
G01X319703Y472378D01*
X319723Y472352D01*
G03X319839Y472277I160J120D01*
G01X319987Y472243D01*
X320019Y472246D01*
X320064Y472250D01*
G02X320993Y472508I929J-1545D01*
G02X321883Y472272I-2J-1803D01*
G01X321884D01*
G03X321972Y472246I99J173D01*
G01X322001Y472244D01*
X322143Y472276D01*
G03X322240Y472330I-45J195D01*
G01X322269Y472359D01*
X322278Y472371D01*
G02X323489Y472986I1211J-885D01*
G02Y469982I0J-1502D01*
G02X323257Y470000I0J1502D01*
G01X323214Y470007D01*
X323130Y469983D01*
X322866Y469758D01*
G03X322796Y469606I130J-152D01*
G37*
G36*
G01X329592Y475518D02*
Y476718D01*
G03X329522Y476870I-200J0D01*
G01X329258Y477095D01*
X329174Y477119D01*
X329131Y477112D01*
G02X328899Y477094I-232J1484D01*
G02Y480098I0J1502D01*
G01X328900D01*
G02X330104Y479493I-1J-1502D01*
G01X330105Y479492D01*
X330126Y479464D01*
G03X330241Y479390I159J121D01*
G01X330361Y479363D01*
X330397Y479355D01*
X330469Y479365D01*
X330504Y479384D01*
X330505Y479385D01*
G02X331395Y479620I890J-1567D01*
G02X332285Y479385I0J-1802D01*
G01X332286Y479384D01*
X332321Y479365D01*
X332393Y479355D01*
X332429Y479363D01*
X332544Y479389D01*
G03X332642Y479443I-44J195D01*
G01X332671Y479472D01*
X332680Y479484D01*
G02X333890Y480098I1211J-888D01*
G01X333891D01*
G02Y477094I0J-1502D01*
G02X333659Y477112I0J1502D01*
G01X333616Y477119D01*
X333532Y477095D01*
X333268Y476870D01*
G03X333198Y476718I130J-152D01*
G01Y475518D01*
G03X333268Y475366I200J0D01*
G01X333532Y475141D01*
X333616Y475117D01*
X333659Y475124D01*
G02X333891Y475142I232J-1484D01*
G02Y472138I0J-1502D01*
G01X333890D01*
G02X332686Y472743I1J1502D01*
G01X332685Y472744D01*
X332664Y472772D01*
G03X332549Y472846I-159J-121D01*
G01X332429Y472873D01*
X332393Y472881D01*
X332321Y472871D01*
X332286Y472852D01*
X332285Y472851D01*
G02X331395Y472616I-890J1567D01*
G02X330505Y472851I0J1802D01*
G01X330504Y472852D01*
X330469Y472871D01*
X330397Y472881D01*
X330361Y472873D01*
X330246Y472847D01*
G03X330148Y472793I44J-195D01*
G01X330119Y472764D01*
X330110Y472752D01*
G02X328900Y472138I-1211J888D01*
G01X328899D01*
G02Y475142I0J1502D01*
G02X329131Y475124I0J-1502D01*
G01X329174Y475117D01*
X329258Y475141D01*
X329522Y475366D01*
G03X329592Y475518I-130J152D01*
G37*
G36*
G01X373345Y486712D02*
G02X375318Y486713I987J-1131D01*
G03X375320Y486711I142J140D01*
G03X375450Y486663I130J152D01*
G01X375714D01*
G03X375844Y486711I0J200D01*
G01X375845Y486712D01*
G02X376832Y487082I987J-1131D01*
G02Y484078I0J-1502D01*
G02X375846Y484447I0J1502D01*
G03X375844Y484449I-142J-140D01*
G03X375714Y484497I-130J-152D01*
G01X375450D01*
G03X375320Y484449I0J-200D01*
G01X375319Y484448D01*
G02X373346Y484447I-987J1131D01*
G03X373344Y484449I-142J-140D01*
G03X373214Y484497I-130J-152D01*
G01X372950D01*
G03X372820Y484449I0J-200D01*
G01X372819Y484448D01*
G02X371832Y484078I-987J1131D01*
G02Y487082I0J1502D01*
G02X372818Y486713I0J-1502D01*
G03X372820Y486711I142J140D01*
G03X372950Y486663I130J152D01*
G01X373214D01*
G03X373344Y486711I0J200D01*
G01X373345Y486712D01*
G37*
G36*
G01X319190Y482579D02*
Y483779D01*
G03X319120Y483931I-200J0D01*
G01X318856Y484156D01*
X318772Y484180D01*
X318729Y484173D01*
G02X318497Y484155I-232J1484D01*
G02Y487159I0J1502D01*
G01X318498D01*
G02X319702Y486554I-1J-1502D01*
G01X319703Y486553D01*
X319724Y486525D01*
G03X319839Y486451I159J121D01*
G01X319959Y486424D01*
X319995Y486416D01*
X320067Y486426D01*
X320102Y486445D01*
X320104Y486446D01*
G02X320993Y486682I892J-1566D01*
G02X321882Y486446I-3J-1802D01*
G01X321884Y486445D01*
X321919Y486426D01*
X321991Y486416D01*
X322027Y486424D01*
X322142Y486450D01*
G03X322240Y486504I-44J195D01*
G01X322269Y486533D01*
X322278Y486545D01*
G02X323488Y487159I1211J-888D01*
G01X323489D01*
G02Y484155I0J-1502D01*
G02X323257Y484173I0J1502D01*
G01X323214Y484180D01*
X323130Y484156D01*
X322866Y483931D01*
G03X322796Y483779I130J-152D01*
G01Y482579D01*
G03X322866Y482427I200J0D01*
G01X323130Y482202D01*
X323214Y482178D01*
X323257Y482185D01*
G02X323489Y482203I232J-1484D01*
G02Y479199I0J-1502D01*
G01X323488D01*
G02X322284Y479804I1J1502D01*
G01X322283Y479805D01*
X322262Y479833D01*
G03X322147Y479907I-159J-121D01*
G01X322027Y479934D01*
X321991Y479942D01*
X321919Y479932D01*
X321884Y479913D01*
X321882Y479912D01*
G02X320993Y479676I-892J1566D01*
G02X320104Y479912I3J1802D01*
G01X320102Y479913D01*
X320067Y479932D01*
X319995Y479942D01*
X319959Y479934D01*
X319844Y479908D01*
G03X319746Y479854I44J-195D01*
G01X319717Y479825D01*
X319708Y479813D01*
G02X318498Y479199I-1211J888D01*
G01X318497D01*
G02Y482203I0J1502D01*
G02X318729Y482185I0J-1502D01*
G01X318772Y482178D01*
X318856Y482202D01*
X319120Y482427D01*
G03X319190Y482579I-130J152D01*
G37*
G36*
G01X386902Y486708D02*
X387102Y486428D01*
X387181Y486385D01*
X387227Y486382D01*
G02X388643Y484882I-86J-1500D01*
G02X387141Y483380I-1502J0D01*
G02X385639Y484882I0J1502D01*
G02X385654Y485087I1502J-7D01*
G01X385656Y485101D01*
Y485103D01*
X385658Y485118D01*
Y485155D01*
G03X385606Y485289I-200J-1D01*
G01X385400Y485517D01*
G03X385328Y485568I-149J-134D01*
G03X385240Y485583I-77J-185D01*
G02X385131Y485580I-104J1799D01*
G02X383329Y487382I0J1802D01*
G02X386933I1802J0D01*
G01Y487379D01*
G02X386872Y486915I-1802J1D01*
G01X386865Y486889D01*
Y486824D01*
G03X386902Y486708I200J0D01*
G37*
G36*
G01X364199Y489084D02*
G02X363830Y490070I1133J986D01*
G02X366834I1502J0D01*
G02X366465Y489084I-1502J0D01*
G01X366464Y489083D01*
X366463Y489082D01*
G03X366415Y488952I152J-130D01*
G01Y488688D01*
G03X366463Y488558I200J0D01*
G01X366464Y488557D01*
X366465Y488556D01*
G02X366834Y487570I-1133J-986D01*
G02X363830I-1502J0D01*
G02X364199Y488556I1502J0D01*
G01X364200Y488557D01*
X364201Y488558D01*
G03X364249Y488688I-152J130D01*
G01Y488952D01*
G03X364201Y489082I-200J0D01*
G01X364200Y489083D01*
X364199Y489084D01*
G37*
G36*
G01X329592Y489691D02*
Y490891D01*
G03X329522Y491043I-200J0D01*
G01X329258Y491268D01*
X329174Y491292D01*
X329131Y491285D01*
G02X328899Y491267I-232J1484D01*
G02Y494271I0J1502D01*
G01X328900D01*
G02X330104Y493666I-1J-1502D01*
G01X330105Y493665D01*
X330126Y493637D01*
G03X330241Y493563I159J121D01*
G01X330361Y493536D01*
X330397Y493528D01*
X330469Y493538D01*
X330504Y493557D01*
X330506Y493558D01*
G02X331395Y493794I892J-1566D01*
G02X332284Y493558I-3J-1802D01*
G01X332286Y493557D01*
X332321Y493538D01*
X332393Y493528D01*
X332429Y493536D01*
X332544Y493562D01*
G03X332642Y493616I-44J195D01*
G01X332671Y493645D01*
X332680Y493657D01*
G02X333890Y494271I1211J-888D01*
G01X333891D01*
G02Y491267I0J-1502D01*
G02X333659Y491285I0J1502D01*
G01X333616Y491292D01*
X333532Y491268D01*
X333268Y491043D01*
G03X333198Y490891I130J-152D01*
G01Y489691D01*
G03X333268Y489539I200J0D01*
G01X333532Y489314D01*
X333616Y489290D01*
X333659Y489297D01*
G02X333891Y489315I232J-1484D01*
G02Y486311I0J-1502D01*
G01X333890D01*
G02X332686Y486916I1J1502D01*
G01X332685Y486917D01*
X332664Y486945D01*
G03X332549Y487019I-159J-121D01*
G01X332429Y487046D01*
X332393Y487054D01*
X332321Y487044D01*
X332286Y487025D01*
X332284Y487024D01*
G02X331395Y486788I-892J1566D01*
G02X330506Y487024I3J1802D01*
G01X330504Y487025D01*
X330469Y487044D01*
X330397Y487054D01*
X330361Y487046D01*
X330246Y487020D01*
G03X330148Y486966I44J-195D01*
G01X330119Y486937D01*
X330110Y486925D01*
G02X328900Y486311I-1211J888D01*
G01X328899D01*
G02Y489315I0J1502D01*
G02X329131Y489297I0J-1502D01*
G01X329174Y489290D01*
X329258Y489314D01*
X329522Y489539D01*
G03X329592Y489691I-130J152D01*
G37*
G36*
G01X377159Y494382D02*
Y494090D01*
G03X377224Y493942I200J0D01*
G02X377709Y492837I-1017J-1105D01*
G01Y492836D01*
G02X374705I-1502J0D01*
G01Y492837D01*
G02X375190Y493942I1502J0D01*
G03X375255Y494090I-135J148D01*
G01Y494382D01*
G03X375190Y494530I-200J0D01*
G02X374705Y495635I1017J1105D01*
G01Y495636D01*
G02X377709I1502J0D01*
G01Y495635D01*
G02X377224Y494530I-1502J0D01*
G03X377159Y494382I135J-148D01*
G37*
G36*
G01X360754Y495272D02*
G02X360385Y496258I1133J986D01*
G02X363389I1502J0D01*
G02X363020Y495272I-1502J0D01*
G01X363019Y495271D01*
X363018Y495270D01*
G03X362970Y495140I152J-130D01*
G01Y494876D01*
G03X363018Y494746I200J0D01*
G01X363019Y494745D01*
X363020Y494744D01*
G02X363389Y493758I-1133J-986D01*
G02X361887Y492256I-1502J0D01*
G02X361337Y492361I2J1503D01*
G01X361332Y492363D01*
X361324Y492366D01*
G03X361136Y492342I-72J-187D01*
G01X360860Y492144D01*
G03X360777Y491981I117J-162D01*
G01Y491955D01*
Y491949D01*
G02X360780Y491870I-1498J-96D01*
G01Y491869D01*
G02X359278Y490368I-1502J1D01*
G02X358292Y490737I0J1502D01*
G03X358290Y490739I-142J-140D01*
G03X358160Y490787I-130J-152D01*
G01X357896D01*
G03X357766Y490739I0J-200D01*
G01X357765Y490738D01*
G02X356778Y490368I-987J1131D01*
G02X355741Y490783I0J1503D01*
G01X355705Y490818D01*
X355606Y490844D01*
X355231Y490753D01*
G03X355089Y490625I47J-194D01*
G01Y490624D01*
G02X354803Y490132I-1418J495D01*
G01X354802Y490131D01*
X354801Y490130D01*
G03X354753Y490000I152J-130D01*
G01Y489736D01*
G03X354801Y489606I200J0D01*
G01X354802Y489605D01*
X354803Y489604D01*
G02X355172Y488618I-1133J-986D01*
G02X352168I-1502J0D01*
G02X352537Y489604I1502J0D01*
G01X352538Y489605D01*
X352539Y489606D01*
G03X352587Y489736I-152J130D01*
G01Y490000D01*
G03X352539Y490130I-200J0D01*
G01X352538Y490131D01*
X352537Y490132D01*
G02Y492104I1132J986D01*
G01X352538Y492105D01*
X352539Y492106D01*
G03X352587Y492236I-152J130D01*
G01Y492500D01*
G03X352539Y492630I-200J0D01*
G01X352538Y492631D01*
X352537Y492632D01*
G02Y494604I1132J986D01*
G01X352538Y494605D01*
X352539Y494606D01*
G03X352587Y494736I-152J130D01*
G01Y495000D01*
G03X352539Y495130I-200J0D01*
G01X352538Y495131D01*
X352537Y495132D01*
G02X352168Y496118I1133J986D01*
G02X355172I1502J0D01*
G02X354803Y495132I-1502J0D01*
G01X354802Y495131D01*
X354801Y495130D01*
G03X354753Y495000I152J-130D01*
G01Y494736D01*
G03X354801Y494606I200J0D01*
G01X354802Y494605D01*
X354803Y494604D01*
G02Y492632I-1132J-986D01*
G01X354802Y492631D01*
X354801Y492630D01*
G03X354753Y492500I152J-130D01*
G01Y492236D01*
G03X354801Y492106I200J0D01*
G01X354802Y492105D01*
G02X354920Y491950I-1133J-985D01*
G03X355286Y492039I167J111D01*
G02X356778Y493372I1492J-168D01*
G02X357764Y493003I0J-1502D01*
G03X357766Y493001I142J140D01*
G03X357896Y492953I130J152D01*
G01X358160D01*
G03X358290Y493001I0J200D01*
G01X358291Y493002D01*
G02X359278Y493372I987J-1131D01*
G02X359828Y493267I-2J-1503D01*
G01X359833Y493265D01*
X359841Y493262D01*
G03X360029Y493286I72J187D01*
G01X360304Y493484D01*
G03X360329Y493505I-116J163D01*
G01X360358Y493534D01*
X360391Y493615D01*
X360388Y493659D01*
Y493673D01*
Y493679D01*
G02X360385Y493758I1498J96D01*
G01Y493759D01*
G02X360754Y494744I1501J-1D01*
G01X360755Y494745D01*
X360756Y494746D01*
G03X360804Y494876I-152J130D01*
G01Y495140D01*
G03X360756Y495270I-200J0D01*
G01X360755Y495271D01*
X360754Y495272D01*
G37*
G36*
G01X316943Y357580D02*
X316991D01*
X317073Y357619D01*
X317101Y357654D01*
G02X318500Y358321I1399J-1134D01*
G02X320302Y356519I0J-1802D01*
G01Y356518D01*
G02X320055Y355607I-1802J0D01*
G01X320027Y355559D01*
Y355450D01*
X320266Y355055D01*
X320363Y355004D01*
X320418Y355007D01*
G02X320481Y355008I55J-1501D01*
G01X320484D01*
G02X321985Y353506I-1J-1502D01*
G02X320483Y352004I-1502J0D01*
G02X319247Y352650I0J1505D01*
G01X319219Y352691D01*
X319131Y352736D01*
X318718Y352733D01*
X318646Y352702D01*
X318618Y352674D01*
X318587Y352643D01*
X318576Y352627D01*
G02X317333Y351968I-1243J843D01*
G02X315831Y353470I0J1502D01*
G02X316826Y354884I1502J0D01*
G01X316871Y354900D01*
X316935Y354966D01*
X317061Y355359D01*
X317048Y355450D01*
X317021Y355489D01*
G02X316975Y355559I1483J1024D01*
G01X316951Y355598D01*
X316875Y355647D01*
X316475Y355695D01*
X316390Y355667D01*
X316357Y355635D01*
G02X315310Y355210I-1047J1077D01*
G02X314117Y355799I0J1503D01*
G01X314089Y355836D01*
X314007Y355877D01*
X313599Y355882D01*
X313516Y355843D01*
X313487Y355807D01*
G02X312316Y355245I-1171J939D01*
G02X310961Y356099I0J1502D01*
G01X310936Y356150D01*
X310845Y356210D01*
X310435Y356226D01*
G03X310330Y356201I-8J-200D01*
G03X310254Y356127I97J-175D01*
G01Y356126D01*
G02X308952Y355373I-1302J749D01*
G02Y358377I0J1502D01*
G02X310307Y357523I0J-1502D01*
G01X310332Y357472D01*
X310423Y357412D01*
X310833Y357396D01*
G03X310938Y357421I8J200D01*
G03X311014Y357495I-97J175D01*
G01Y357496D01*
G02X312316Y358249I1302J-749D01*
G02X313509Y357660I0J-1503D01*
G01X313537Y357623D01*
X313619Y357582D01*
X314027Y357577D01*
X314110Y357616D01*
X314139Y357652D01*
G02X315310Y358214I1171J-939D01*
G02X316479Y357655I0J-1502D01*
G01X316507Y357620D01*
X316589Y357581D01*
X316943Y357580D01*
G37*
G36*
G01X237388Y340513D02*
X237394Y340507D01*
X237395Y340506D01*
G02X237851Y339428I-1046J-1078D01*
G02X236619Y337950I-1503J0D01*
G01X236566Y337940D01*
X236486Y337873D01*
X236347Y337500D01*
G03X236379Y337304I187J-70D01*
G01X236380Y337303D01*
G02X236788Y336161I-1394J-1142D01*
G02X233184I-1802J0D01*
G02X234816Y337955I1802J0D01*
G01X234818D01*
G03X234979Y338070I-20J199D01*
G01X235147Y338429D01*
X235143Y338481D01*
X235139Y338536D01*
X235109Y338581D01*
X235108Y338582D01*
G02X234847Y339427I1241J846D01*
G01Y339428D01*
G02X235248Y340449I1502J-1D01*
G01X235278Y340481D01*
X235305Y340560D01*
X235271Y340934D01*
X235241Y340997D01*
X235216Y341022D01*
X235194Y341044D01*
X235183Y341053D01*
G02X234462Y342494I1081J1442D01*
G02X236264Y344296I1802J0D01*
G02X238066Y342494I0J-1802D01*
G02X237413Y341106I-1802J0D01*
G03X237341Y340960I128J-154D01*
G01X237330Y340661D01*
G03X237388Y340513I200J-7D01*
G37*
G36*
G01X302785Y330773D02*
G03Y330111I224J-331D01*
G02X303445Y328867I-842J-1244D01*
G02X300441I-1502J0D01*
G02X301101Y330111I1502J0D01*
G03Y330773I-224J331D01*
G02X300441Y332017I842J1244D01*
G02X303445I1502J0D01*
G02X302785Y330773I-1502J0D01*
G37*
G36*
G01X229340Y313888D02*
G02X229365Y314160I1502J-1D01*
G03X228927Y314629I-393J72D01*
G02X228760Y314620I-164J1493D01*
G02X227258Y316122I0J1502D01*
G02X228760Y317624I1502J0D01*
G02X230262Y316122I0J-1502D01*
G02X230237Y315850I-1502J1D01*
G03X230675Y315381I393J-72D01*
G02X230842Y315390I164J-1493D01*
G02X232344Y313888I0J-1502D01*
G02X230842Y312386I-1502J0D01*
G02X229340Y313888I0J1502D01*
G37*
G36*
G01X298000Y410803D02*
G02X299233Y410315I0J-1803D01*
G01X299261Y410288D01*
X299331Y410261D01*
X299394D01*
G03X299535Y410319I0J200D01*
G01X300343Y411126D01*
G02X300485Y411185I142J-141D01*
G01X302534D01*
G03X302655Y411226I0J200D01*
G02X303196Y411410I542J-706D01*
G01X304050D01*
G02X304233Y411292I0J-201D01*
G01X304257Y411238D01*
X304356Y411174D01*
X305336D01*
G03X305481Y411236I0J200D01*
G02X306858Y411826I1377J-1312D01*
G01X309258D01*
G02X311160Y409924I0J-1902D01*
G02X310200Y408272I-1902J0D01*
G01X310164Y408252D01*
X310139Y408218D01*
G03X310098Y408098I159J-121D01*
G01Y407750D01*
G03X310157Y407608I200J0D01*
G01X310176Y407589D01*
G02X311160Y405924I-918J-1666D01*
G02X310200Y404272I-1902J0D01*
G01X310164Y404252D01*
X310139Y404218D01*
G03X310098Y404098I159J-121D01*
G01Y403750D01*
G03X310157Y403608I200J0D01*
G01X310176Y403589D01*
G02X311160Y401924I-918J-1666D01*
G02X309258Y400022I-1902J0D01*
G01X306858D01*
G02X306300Y400106I1J1902D01*
G03X305783Y399724I-117J-383D01*
G01Y396658D01*
G02X305768Y396582I-200J0D01*
G01X305742Y396522D01*
Y396480D01*
Y396370D01*
G03X305801Y396228I200J0D01*
G01X306245Y395784D01*
X306346Y395756D01*
X306397Y395769D01*
G02X306858Y395826I462J-1845D01*
G01X309258D01*
G02X311160Y393924I0J-1902D01*
G02X310190Y392266I-1902J0D01*
G03X310088Y392092I98J-174D01*
G01Y391744D01*
G03X310190Y391570I200J0D01*
G02X311160Y389912I-932J-1658D01*
G02X310200Y388260I-1902J0D01*
G01X310164Y388240D01*
X310139Y388206D01*
G03X310098Y388086I159J-121D01*
G01Y387738D01*
G03X310157Y387596I200J0D01*
G01X310176Y387577D01*
G02X311160Y385912I-918J-1666D01*
G02X309258Y384010I-1902J0D01*
G01X307144D01*
G03X307002Y383951I0J-200D01*
G01X305636Y382585D01*
G03X305577Y382443I141J-142D01*
G01Y376732D01*
G02X305518Y376590I-200J0D01*
G01X305427Y376499D01*
G02X305285Y376440I-142J141D01*
G01X304250D01*
Y376426D01*
X303193D01*
G02X303055Y376437I2J891D01*
G01X303039Y376440D01*
X301490D01*
G02X301314Y376546I0J199D01*
G03X301137Y376651I-176J-95D01*
G01X300370D01*
G03X300233Y376597I0J-200D01*
G02X299000Y376109I-1233J1314D01*
G02X297197Y377912I0J1803D01*
G02X299000Y379715I1803J0D01*
G02X299219Y379701I-5J-1803D01*
G03X299385Y379758I25J198D01*
G01X299386Y379759D01*
X299638Y380008D01*
X299669Y380094D01*
X299664Y380138D01*
Y380143D01*
X299663Y380153D01*
G02X299655Y380305I1495J155D01*
G01Y380307D01*
G02X300050Y381323I1504J0D01*
G01X300105Y381383D01*
X300101Y381543D01*
X299989Y381655D01*
G02X299930Y381797I141J142D01*
G01Y383823D01*
G03X299873Y383963I-200J0D01*
G01X299872Y383964D01*
X299197Y384639D01*
G03X299128Y384684I-141J-141D01*
G01X299090Y384699D01*
X299048Y384698D01*
G02X299001Y384697I-62J1802D01*
G01X298999D01*
G02X297197Y386500I1J1803D01*
G02X297546Y387566I1803J0D01*
G01X297588Y387623D01*
X297582Y387762D01*
X297535Y387816D01*
G03X297525Y387827I-153J-129D01*
G01X295704Y389648D01*
G02X295645Y389790I141J142D01*
G01Y392397D01*
G03X295445Y392597I-200J0D01*
G01X293728D01*
G03X293591Y392543I0J-200D01*
G02X292358Y392055I-1233J1314D01*
G02Y395661I0J1803D01*
G02X293591Y395173I0J-1802D01*
G03X293728Y395119I137J146D01*
G01X295445D01*
G03X295645Y395319I0J200D01*
G01Y397146D01*
G03X295540Y397322I-200J0D01*
G01X295370D01*
G03X295233Y397268I0J-200D01*
G02X294000Y396780I-1233J1314D01*
G02X292197Y398583I0J1803D01*
G02X294000Y400386I1803J0D01*
G02X295039Y400056I-1J-1803D01*
G01X295099Y400014D01*
X295244Y400026D01*
X296220Y401003D01*
G03X296279Y401145I-141J142D01*
G01Y401272D01*
G03X296264Y401348I-200J0D01*
G01X296148Y401629D01*
X296047Y401697D01*
X295987D01*
G02X294471Y402544I13J1803D01*
G03X294299Y402638I-170J-106D01*
G01X293907Y402634D01*
X293818Y402583D01*
X293791Y402537D01*
G02X292500Y401804I-1291J770D01*
G02Y404810I0J1503D01*
G02X293690Y404225I0J-1503D01*
G01X293698Y404215D01*
X293720Y404193D01*
G03X293883Y404135I142J141D01*
G01X294268Y404176D01*
X294353Y404235D01*
X294375Y404283D01*
G02X295942Y405302I1624J-783D01*
G01X295981Y405303D01*
X296051Y405334D01*
X297411Y406694D01*
G03X297286Y407344I-283J283D01*
G02X296197Y409000I715J1656D01*
G02X298000Y410803I1803J0D01*
G37*
G36*
G01X292884Y385869D02*
G02X294023Y384410I-365J-1459D01*
G02X292520Y382907I-1503J0D01*
G02X292320Y382920I-3J1503D01*
G02X291063Y384041I200J1490D01*
G01X291057Y384068D01*
X291030Y384117D01*
X290685Y384461D01*
X289966Y385180D01*
G03X289964Y385182I-142J-140D01*
G03X289824Y385239I-140J-143D01*
G01X289561D01*
G02X289419Y385298I0J200D01*
G01X288550Y386167D01*
X288482Y386197D01*
X288443Y386198D01*
G02X287267Y386685I57J1802D01*
G03X287130Y386739I-137J-146D01*
G01X285468D01*
G03X285068Y386327I0J-400D01*
G01X285071Y386224D01*
G03X285097Y386131I200J6D01*
G01X285110Y386108D01*
X285140Y386075D01*
X285159Y386062D01*
G02X285976Y384500I-1085J-1562D01*
G01Y381500D01*
G02X285953Y381198I-1901J-7D01*
G01X285946Y381155D01*
X285970Y381071D01*
X286173Y380832D01*
G03X286177Y380828I143J139D01*
G03X286253Y380775I149J133D01*
G01X286289Y380761D01*
X292546D01*
G03X292686Y380818I0J200D01*
G01X292687Y380819D01*
X293865Y381996D01*
X293896Y382066D01*
X293897Y382105D01*
G02X295699Y383850I1802J-58D01*
G02X297502Y382047I0J-1803D01*
G02X295757Y380245I-1803J0D01*
G01X295718Y380244D01*
X295648Y380213D01*
X293733Y378298D01*
G02X293591Y378239I-142J141D01*
G01X289728D01*
G03X289705Y378238I-3J-200D01*
G03X289561Y378150I23J-199D01*
G03X289546Y378122I168J-108D01*
G01X289381Y377763D01*
X289397Y377648D01*
X289436Y377603D01*
G02X286765Y370692I-3186J-2740D01*
G01X286764D01*
G03X286617Y370595I26J-199D01*
G01X286432Y370280D01*
X286425Y370189D01*
X286443Y370145D01*
G02X286712Y368760I-3433J-1385D01*
G02X283010Y365058I-3702J0D01*
G01X275710D01*
G02Y372462I0J3702D01*
G01X282158D01*
X282249Y372512D01*
X282276Y372556D01*
X282435Y372810D01*
G03X282454Y372849I-169J106D01*
G03X282464Y372888I-188J69D01*
G01X282466Y372903D01*
Y373035D01*
X282447Y373076D01*
G02X283064Y377603I3803J1787D01*
G01X283103Y377648D01*
X283119Y377763D01*
X282954Y378122D01*
G03X282939Y378150I-183J-80D01*
G03X282795Y378238I-167J-111D01*
G03X282772Y378239I-20J-199D01*
G01X282061D01*
G02X281919Y378298I0J200D01*
G01X279723Y380494D01*
G02X279664Y380636I141J142D01*
G01Y383159D01*
G03X279585Y383239I-176J-95D01*
G01X278749D01*
G03X278628Y383198I0J-200D01*
G02X278087Y383014I-542J706D01*
G01X277234D01*
G02X277052Y383132I0J200D01*
G01X277027Y383186D01*
X276929Y383250D01*
X276011D01*
Y383249D01*
X275842D01*
G03X275686Y383145I20J-198D01*
G01Y382384D01*
G03X275687Y382363I200J-1D01*
G01X275691Y382328D01*
X275704Y382287D01*
X275716Y382268D01*
G02X275928Y381500I-1291J-770D01*
G02X274425Y379997I-1503J0D01*
G02X272922Y381500I0J1503D01*
G02X273127Y382254I1502J-4D01*
G03X273129Y382258I-178J91D01*
G02X273132Y382263I173J-100D01*
G03X273156Y382315I-168J109D01*
G03X273164Y382372I-192J56D01*
G01Y383393D01*
X273151Y383442D01*
X273138Y383465D01*
G02X273022Y383911I776J440D01*
G01Y385089D01*
G02X273363Y385796I891J6D01*
G01X273400Y385826D01*
X273440Y385912D01*
X273427Y386326D01*
X273382Y386409D01*
X273343Y386436D01*
G02X272524Y388000I1084J1564D01*
G01Y390502D01*
G02X274425Y392402I1901J-1D01*
G02X275508Y392062I-2J-1901D01*
G02X275675Y391932I-1082J-1563D01*
G01X275720Y391893D01*
X275836Y391876D01*
X276197Y392041D01*
G03X276314Y392223I-83J182D01*
G01Y393714D01*
G03X276260Y393851I-200J0D01*
G02X275772Y395084I1314J1233D01*
G02X279378I1803J0D01*
G02X278890Y393851I-1802J0D01*
G03X278836Y393714I146J-137D01*
G01Y389341D01*
G03X278915Y389261I176J95D01*
G01X279751D01*
G03X279872Y389302I0J200D01*
G02X280413Y389486I542J-706D01*
G01X281266D01*
G02X281448Y389368I0J-200D01*
G01X281473Y389314D01*
X281571Y389250D01*
X283334D01*
G03X283534Y389450I0J200D01*
G01Y389486D01*
X284587D01*
G02X285128Y389302I-1J-890D01*
G03X285249Y389261I121J159D01*
G01X287130D01*
G03X287267Y389315I0J200D01*
G02X288500Y389803I1233J-1314D01*
G02X290302Y388058I0J-1803D01*
G01X290303Y388019D01*
X290334Y387949D01*
X290434Y387849D01*
X290435D01*
X290464Y387820D01*
G03X290606Y387761I142J141D01*
G01X290869D01*
G02X291011Y387702I0J-200D01*
G01X292811Y385902D01*
X292857Y385876D01*
X292884Y385869D01*
G37*
G36*
G01X250132Y84108D02*
Y84460D01*
X250104Y84529D01*
X250078Y84557D01*
G02X249672Y85584I1096J1027D01*
G02X252676I1502J0D01*
G02X252270Y84557I-1502J0D01*
G01X252244Y84529D01*
X252216Y84460D01*
Y84108D01*
X252244Y84039D01*
X252270Y84011D01*
G02Y81957I-1096J-1027D01*
G01X252244Y81929D01*
X252216Y81860D01*
Y81508D01*
X252244Y81439D01*
X252270Y81411D01*
G02Y79357I-1096J-1027D01*
G01X252244Y79329D01*
X252216Y79260D01*
Y78908D01*
X252244Y78839D01*
X252270Y78811D01*
G02Y76757I-1096J-1027D01*
G01X252244Y76729D01*
X252216Y76660D01*
Y76308D01*
X252244Y76239D01*
X252270Y76211D01*
G02X252676Y75184I-1096J-1027D01*
G02X249672I-1502J0D01*
G02X250078Y76211I1502J0D01*
G01X250104Y76239D01*
X250132Y76308D01*
Y76660D01*
X250104Y76729D01*
X250078Y76757D01*
G02Y78811I1096J1027D01*
G01X250104Y78839D01*
X250132Y78908D01*
Y79260D01*
X250104Y79329D01*
X250078Y79357D01*
G02Y81411I1096J1027D01*
G01X250104Y81439D01*
X250132Y81508D01*
Y81860D01*
X250104Y81929D01*
X250078Y81957D01*
G02Y84011I1096J1027D01*
G01X250104Y84039D01*
X250132Y84108D01*
G37*
G36*
G01X259610Y101516D02*
X259646Y101900D01*
X259619Y101981D01*
X259590Y102013D01*
G02X259186Y103037I1098J1025D01*
G02X262190I1502J0D01*
G02X261723Y101948I-1503J0D01*
G01X261691Y101918D01*
X261659Y101839D01*
X261672Y101454D01*
X261710Y101377D01*
X261743Y101350D01*
G02X262397Y99961I-1148J-1389D01*
G02X258793I-1802J0D01*
G02X259533Y101417I1802J0D01*
G01X259568Y101442D01*
X259610Y101516D01*
G37*
G36*
G01X279575Y116195D02*
X279694Y116168D01*
G03X279837Y116189I44J195D01*
G02X280729Y116426I893J-1566D01*
G02X281621Y116189I-1J-1803D01*
G03X281764Y116168I99J174D01*
G01X281883Y116195D01*
G03X282002Y116274I-44J195D01*
G02X283225Y116903I1222J-873D01*
G02Y113899I0J-1502D01*
G02X282993Y113917I0J1502D01*
G01X282950Y113924D01*
X282866Y113900D01*
X282601Y113674D01*
G03X282532Y113522I131J-151D01*
G01Y112324D01*
G03X282601Y112172I200J-1D01*
G01X282866Y111946D01*
X282950Y111922D01*
X282993Y111929D01*
G02X283225Y111947I232J-1484D01*
G02Y108943I0J-1502D01*
G02X282002Y109572I-1J1502D01*
G03X281883Y109651I-163J-116D01*
G01X281764Y109678D01*
G03X281621Y109657I-44J-195D01*
G02X280729Y109420I-893J1566D01*
G02X279837Y109657I1J1803D01*
G03X279694Y109678I-99J-174D01*
G01X279575Y109651D01*
G03X279456Y109572I44J-195D01*
G02X278233Y108943I-1222J873D01*
G02Y111947I0J1502D01*
G02X278465Y111929I0J-1502D01*
G01X278508Y111922D01*
X278592Y111946D01*
X278857Y112172D01*
G03X278926Y112324I-131J151D01*
G01Y113522D01*
G03X278857Y113674I-200J1D01*
G01X278592Y113900D01*
X278508Y113924D01*
X278465Y113917D01*
G02X278233Y113899I-232J1484D01*
G02Y116903I0J1502D01*
G02X279456Y116274I1J-1502D01*
G03X279575Y116195I163J116D01*
G37*
G36*
G01Y130368D02*
X279694Y130341D01*
G03X279837Y130362I44J195D01*
G02X280729Y130598I892J-1566D01*
G02X281621Y130362I0J-1802D01*
G03X281764Y130341I99J174D01*
G01X281883Y130368D01*
G03X282002Y130447I-44J195D01*
G02X283225Y131076I1222J-873D01*
G02Y128072I0J-1502D01*
G02X282993Y128090I0J1502D01*
G01X282950Y128097D01*
X282866Y128073D01*
X282601Y127847D01*
G03X282532Y127695I131J-151D01*
G01Y126497D01*
G03X282601Y126345I200J-1D01*
G01X282866Y126119D01*
X282950Y126095D01*
X282993Y126102D01*
G02X283225Y126120I232J-1484D01*
G02Y123116I0J-1502D01*
G02X282002Y123745I-1J1502D01*
G03X281883Y123824I-163J-116D01*
G01X281764Y123851D01*
G03X281621Y123830I-44J-195D01*
G02X280729Y123594I-892J1566D01*
G02X279837Y123830I0J1802D01*
G03X279694Y123851I-99J-174D01*
G01X279575Y123824D01*
G03X279456Y123745I44J-195D01*
G02X278233Y123116I-1222J873D01*
G02Y126120I0J1502D01*
G02X278465Y126102I0J-1502D01*
G01X278508Y126095D01*
X278592Y126119D01*
X278857Y126345D01*
G03X278926Y126497I-131J151D01*
G01Y127695D01*
G03X278857Y127847I-200J1D01*
G01X278592Y128073D01*
X278508Y128097D01*
X278465Y128090D01*
G02X278233Y128072I-232J1484D01*
G02Y131076I0J1502D01*
G02X279456Y130447I1J-1502D01*
G03X279575Y130368I163J116D01*
G37*
G36*
G01X252424Y146496D02*
X252117D01*
G02Y153898I0J3701D01*
G01X259417D01*
G02Y146496I0J-3701D01*
G01X259110D01*
G03X258910Y146296I0J-200D01*
G01Y146236D01*
X258943Y146186D01*
G02X252591I-3176J-2091D01*
G01X252607Y146211D01*
X252624Y146266D01*
Y146296D01*
G03X252424Y146496I-200J0D01*
G37*
G36*
G01X252238Y92655D02*
X252233Y92709D01*
G02X252226Y92849I1495J145D01*
G02X255230I1502J0D01*
G02X255227Y92747I-1502J-7D01*
G01X255223Y92696D01*
X255262Y92607D01*
X255600Y92340D01*
X255695Y92322D01*
X255743Y92337D01*
G02X256274Y92417I531J-1722D01*
G02X254472Y90615I0J-1802D01*
G02X254498Y90917I1802J-3D01*
G01X254506Y90967D01*
X254476Y91059D01*
X254167Y91359D01*
X254074Y91386D01*
X254024Y91377D01*
G02X253728Y91347I-299J1472D01*
G02X253255Y91424I2J1502D01*
G01X253203Y91441D01*
X253101Y91420D01*
X252760Y91124D01*
X252725Y91026D01*
X252735Y90972D01*
G02X252764Y90650I-1773J-322D01*
G02X250962Y92452I-1802J0D01*
G02X251676Y92305I1J-1802D01*
G01X251725Y92283D01*
X251829Y92295D01*
X252195Y92560D01*
X252238Y92655D01*
G37*
G36*
G01X276992Y100457D02*
G02X276332Y101701I842J1244D01*
G02X279336I1502J0D01*
G02X278676Y100457I-1502J0D01*
G03Y99795I224J-331D01*
G02X279336Y98551I-842J-1244D01*
G02X276332I-1502J0D01*
G02X276992Y99795I1502J0D01*
G03Y100457I-224J331D01*
G37*
G36*
G01X269404Y108025D02*
G02X268822Y107908I-581J1385D01*
G02Y110912I0J1502D01*
G02X270310Y109616I0J-1502D01*
G01X270316Y109569D01*
X270369Y109492D01*
X270728Y109290D01*
X270821Y109285D01*
X270865Y109304D01*
G02X271580Y109452I715J-1655D01*
G02X273382Y107649I-1J-1803D01*
G01Y104249D01*
G02X271580Y102446I-1802J-1D01*
G02X270877Y102589I1J1803D01*
G01X270832Y102608D01*
X270735Y102601D01*
X270374Y102375D01*
X270324Y102291D01*
X270322Y102242D01*
G02X268822Y100821I-1500J81D01*
G02Y103825I0J1502D01*
G02X269263Y103759I1J-1502D01*
G01X269310Y103744D01*
X269406Y103762D01*
X269741Y104023D01*
X269782Y104112D01*
X269780Y104161D01*
G02X269778Y104249I1800J85D01*
G01Y107649D01*
G02X269781Y107759I1802J6D01*
G03X269696Y107935I-200J12D01*
G01X269596Y108005D01*
G03X269404Y108025I-114J-164D01*
G37*
G36*
G01X352494Y84108D02*
Y84460D01*
X352466Y84529D01*
X352440Y84557D01*
G02X352034Y85584I1096J1027D01*
G02X355038I1502J0D01*
G02X354632Y84557I-1502J0D01*
G01X354606Y84529D01*
X354578Y84460D01*
Y84108D01*
X354606Y84039D01*
X354632Y84011D01*
G02Y81957I-1096J-1027D01*
G01X354606Y81929D01*
X354578Y81860D01*
Y81508D01*
X354606Y81439D01*
X354632Y81411D01*
G02Y79357I-1096J-1027D01*
G01X354606Y79329D01*
X354578Y79260D01*
Y78908D01*
X354606Y78839D01*
X354632Y78811D01*
G02Y76757I-1096J-1027D01*
G01X354606Y76729D01*
X354578Y76660D01*
Y76308D01*
X354606Y76239D01*
X354632Y76211D01*
G02X355038Y75184I-1096J-1027D01*
G02X352034I-1502J0D01*
G02X352440Y76211I1502J0D01*
G01X352466Y76239D01*
X352494Y76308D01*
Y76660D01*
X352466Y76729D01*
X352440Y76757D01*
G02Y78811I1096J1027D01*
G01X352466Y78839D01*
X352494Y78908D01*
Y79260D01*
X352466Y79329D01*
X352440Y79357D01*
G02Y81411I1096J1027D01*
G01X352466Y81439D01*
X352494Y81508D01*
Y81860D01*
X352466Y81929D01*
X352440Y81957D01*
G02Y84011I1096J1027D01*
G01X352466Y84039D01*
X352494Y84108D01*
G37*
G36*
G01X361972Y101516D02*
X362008Y101900D01*
X361981Y101981D01*
X361952Y102013D01*
G02X361548Y103037I1098J1025D01*
G02X364552I1502J0D01*
G02X364085Y101948I-1503J0D01*
G01X364053Y101918D01*
X364021Y101839D01*
X364034Y101454D01*
X364072Y101377D01*
X364105Y101350D01*
G02X364759Y99961I-1148J-1389D01*
G02X361155I-1802J0D01*
G02X361895Y101417I1802J0D01*
G01X361930Y101442D01*
X361972Y101516D01*
G37*
G36*
G01X381937Y116195D02*
X382056Y116168D01*
G03X382199Y116189I44J195D01*
G02X383091Y116426I893J-1566D01*
G02X383983Y116189I-1J-1803D01*
G03X384126Y116168I99J174D01*
G01X384245Y116195D01*
G03X384364Y116274I-44J195D01*
G02X385587Y116903I1222J-873D01*
G02Y113899I0J-1502D01*
G02X385355Y113917I0J1502D01*
G01X385312Y113924D01*
X385228Y113900D01*
X384963Y113674D01*
G03X384894Y113522I131J-151D01*
G01Y112324D01*
G03X384963Y112172I200J-1D01*
G01X385228Y111946D01*
X385312Y111922D01*
X385355Y111929D01*
G02X385587Y111947I232J-1484D01*
G02Y108943I0J-1502D01*
G02X384364Y109572I-1J1502D01*
G03X384245Y109651I-163J-116D01*
G01X384126Y109678D01*
G03X383983Y109657I-44J-195D01*
G02X383091Y109420I-893J1566D01*
G02X382199Y109657I1J1803D01*
G03X382056Y109678I-99J-174D01*
G01X381937Y109651D01*
G03X381818Y109572I44J-195D01*
G02X380595Y108943I-1222J873D01*
G02Y111947I0J1502D01*
G02X380827Y111929I0J-1502D01*
G01X380870Y111922D01*
X380954Y111946D01*
X381219Y112172D01*
G03X381288Y112324I-131J151D01*
G01Y113522D01*
G03X381219Y113674I-200J1D01*
G01X380954Y113900D01*
X380870Y113924D01*
X380827Y113917D01*
G02X380595Y113899I-232J1484D01*
G02Y116903I0J1502D01*
G02X381818Y116274I1J-1502D01*
G03X381937Y116195I163J116D01*
G37*
G36*
G01Y130368D02*
X382056Y130341D01*
G03X382199Y130362I44J195D01*
G02X383091Y130598I892J-1566D01*
G02X383983Y130362I0J-1802D01*
G03X384126Y130341I99J174D01*
G01X384245Y130368D01*
G03X384364Y130447I-44J195D01*
G02X385587Y131076I1222J-873D01*
G02Y128072I0J-1502D01*
G02X385355Y128090I0J1502D01*
G01X385312Y128097D01*
X385228Y128073D01*
X384963Y127847D01*
G03X384894Y127695I131J-151D01*
G01Y126497D01*
G03X384963Y126345I200J-1D01*
G01X385228Y126119D01*
X385312Y126095D01*
X385355Y126102D01*
G02X385587Y126120I232J-1484D01*
G02Y123116I0J-1502D01*
G02X384364Y123745I-1J1502D01*
G03X384245Y123824I-163J-116D01*
G01X384126Y123851D01*
G03X383983Y123830I-44J-195D01*
G02X383091Y123594I-892J1566D01*
G02X382199Y123830I0J1802D01*
G03X382056Y123851I-99J-174D01*
G01X381937Y123824D01*
G03X381818Y123745I44J-195D01*
G02X380595Y123116I-1222J873D01*
G02Y126120I0J1502D01*
G02X380827Y126102I0J-1502D01*
G01X380870Y126095D01*
X380954Y126119D01*
X381219Y126345D01*
G03X381288Y126497I-131J151D01*
G01Y127695D01*
G03X381219Y127847I-200J1D01*
G01X380954Y128073D01*
X380870Y128097D01*
X380827Y128090D01*
G02X380595Y128072I-232J1484D01*
G02Y131076I0J1502D01*
G02X381818Y130447I1J-1502D01*
G03X381937Y130368I163J116D01*
G37*
G36*
G01X354786Y146496D02*
X354479D01*
G02Y153898I0J3701D01*
G01X361779D01*
G02Y146496I0J-3701D01*
G01X361472D01*
G03X361272Y146296I0J-200D01*
G01Y146236D01*
X361305Y146186D01*
G02X354953I-3176J-2091D01*
G01X354969Y146211D01*
X354986Y146266D01*
Y146296D01*
G03X354786Y146496I-200J0D01*
G37*
G36*
G01X354600Y92655D02*
X354595Y92709D01*
G02X354588Y92849I1495J145D01*
G02X357592I1502J0D01*
G02X357589Y92747I-1502J-7D01*
G01X357585Y92696D01*
X357624Y92607D01*
X357962Y92340D01*
X358057Y92322D01*
X358105Y92337D01*
G02X358636Y92417I531J-1722D01*
G02X356834Y90615I0J-1802D01*
G02X356860Y90917I1802J-3D01*
G01X356868Y90967D01*
X356838Y91059D01*
X356529Y91359D01*
X356436Y91386D01*
X356386Y91377D01*
G02X356090Y91347I-299J1472D01*
G02X355617Y91424I2J1502D01*
G01X355565Y91441D01*
X355463Y91420D01*
X355122Y91124D01*
X355087Y91026D01*
X355097Y90972D01*
G02X355126Y90650I-1773J-322D01*
G02X353324Y92452I-1802J0D01*
G02X354038Y92305I1J-1802D01*
G01X354087Y92283D01*
X354191Y92295D01*
X354557Y92560D01*
X354600Y92655D01*
G37*
G36*
G01X379354Y100457D02*
G02X378694Y101701I842J1244D01*
G02X381698I1502J0D01*
G02X381038Y100457I-1502J0D01*
G03Y99795I224J-331D01*
G02X381698Y98551I-842J-1244D01*
G02X378694I-1502J0D01*
G02X379354Y99795I1502J0D01*
G03Y100457I-224J331D01*
G37*
G36*
G01X371766Y108025D02*
G02X371184Y107908I-581J1385D01*
G02Y110912I0J1502D01*
G02X372672Y109616I0J-1502D01*
G01X372678Y109569D01*
X372731Y109492D01*
X373090Y109290D01*
X373183Y109285D01*
X373227Y109304D01*
G02X373942Y109452I715J-1655D01*
G02X375744Y107649I-1J-1803D01*
G01Y104249D01*
G02X373942Y102446I-1802J-1D01*
G02X373239Y102589I1J1803D01*
G01X373194Y102608D01*
X373097Y102601D01*
X372736Y102375D01*
X372686Y102291D01*
X372684Y102242D01*
G02X371184Y100821I-1500J81D01*
G02Y103825I0J1502D01*
G02X371625Y103759I1J-1502D01*
G01X371672Y103744D01*
X371768Y103762D01*
X372103Y104023D01*
X372144Y104112D01*
X372142Y104161D01*
G02X372140Y104249I1800J85D01*
G01Y107649D01*
G02X372143Y107759I1802J6D01*
G03X372058Y107935I-200J12D01*
G01X371958Y108005D01*
G03X371766Y108025I-114J-164D01*
G37*
G36*
G01X392107Y379082D02*
X392407Y379353D01*
X392441Y379437D01*
X392438Y379483D01*
G02X392435Y379591I1799J104D01*
G02X394237Y377789I1802J0D01*
G02X393745Y377857I-2J1802D01*
G01X393701Y377870D01*
X393612Y377855D01*
X393283Y377620D01*
X393239Y377541D01*
X393237Y377495D01*
G02X391737Y376079I-1500J86D01*
G02Y379083I0J1502D01*
G02X391975Y379064I0J-1502D01*
G01X392021Y379057D01*
X392107Y379082D01*
G37*
G36*
G01X432239Y434358D02*
X432048Y434652D01*
X431986Y434697D01*
X431949Y434706D01*
G02X430808Y436164I361J1458D01*
G02X433812I1502J0D01*
G02X433787Y435893I-1502J2D01*
G01X433781Y435856D01*
X433795Y435781D01*
X433986Y435487D01*
X434048Y435442D01*
X434085Y435433D01*
G02X435226Y433975I-361J-1458D01*
G02X434114Y432525I-1501J0D01*
G01X434070Y432513D01*
X434001Y432454D01*
X433839Y432083D01*
X433843Y431993D01*
X433864Y431952D01*
G02X434072Y431112I-1594J-840D01*
G02X430468I-1802J0D01*
G02X432008Y432895I1802J0D01*
G01X432053Y432902D01*
X432128Y432952D01*
X432332Y433302D01*
X432339Y433391D01*
X432323Y433434D01*
G02X432222Y433975I1401J541D01*
G02X432247Y434246I1502J-2D01*
G01X432253Y434283D01*
X432239Y434358D01*
G37*
G36*
G01X425946Y934150D02*
X389782D01*
G02X389641Y934208I0J200D01*
G01X388671Y935178D01*
G02X388612Y935319I141J142D01*
G01Y940983D01*
G02X388671Y941124I200J-1D01*
G01X389641Y942094D01*
G02X389782Y942152I141J-142D01*
G01X425446D01*
G02X425587Y942094I0J-200D01*
G01X427057Y940624D01*
G02X427116Y940483I-141J-142D01*
G01Y935319D01*
G02X427057Y935178I-200J1D01*
G01X426087Y934208D01*
G02X425946Y934150I-141J142D01*
G37*
G36*
G01X413084Y963303D02*
X413436D01*
X413505Y963331D01*
X413533Y963357D01*
G02X415587I1027J-1096D01*
G01X415615Y963331D01*
X415684Y963303D01*
X416036D01*
X416105Y963331D01*
X416133Y963357D01*
G02X417160Y963763I1027J-1096D01*
G02Y960759I0J-1502D01*
G02X416133Y961165I0J1502D01*
G01X416105Y961191D01*
X416036Y961219D01*
X415684D01*
X415615Y961191D01*
X415587Y961165D01*
G02X413533I-1027J1096D01*
G01X413505Y961191D01*
X413436Y961219D01*
X413084D01*
X413015Y961191D01*
X412987Y961165D01*
G02X411960Y960759I-1027J1096D01*
G02Y963763I0J1502D01*
G02X412987Y963357I0J-1502D01*
G01X413015Y963331D01*
X413084Y963303D01*
G37*
G36*
G01X401961Y950514D02*
G02X401313Y951750I855J1236D01*
G02X404317I1502J0D01*
G02X403564Y950448I-1502J0D01*
G03X403536Y949772I199J-347D01*
G02X404184Y948536I-855J-1236D01*
G02X401180I-1502J0D01*
G02X401933Y949838I1502J0D01*
G03X401961Y950514I-199J347D01*
G37*
G36*
G01X448342Y645680D02*
X453088Y650426D01*
G02X454687Y651088I1599J-1600D01*
G01X461626D01*
G02X463888Y648827I1J-2261D01*
G01Y646438D01*
G03X463961Y646283I200J-1D01*
G01X464238Y646058D01*
X464324Y646037D01*
X464369Y646047D01*
G02X464776Y646088I403J-1960D01*
G02X466778Y644087I1J-2001D01*
G01Y636506D01*
G02X466191Y635091I-2002J1D01*
G01X449075Y617975D01*
G02X447660Y617388I-1416J1415D01*
G01X430351D01*
G02X428936Y617975I1J2002D01*
G01X422548Y624363D01*
G02X421962Y625778I1415J1415D01*
G02X423963Y627780I2001J1D01*
G02X425378Y627193I-1J-2002D01*
G01X431121Y621450D01*
G03X431263Y621392I141J142D01*
G01X446748D01*
G03X446890Y621450I1J200D01*
G01X462716Y637276D01*
G03X462774Y637418I-142J141D01*
G01Y641533D01*
G03X462694Y641693I-200J0D01*
G01X462400Y641914D01*
X462308Y641930D01*
X462262Y641917D01*
G02X461626Y641826I-635J2170D01*
G02X459364Y644087I-1J2261D01*
G01Y646366D01*
G03X459164Y646566I-200J0D01*
G01X455707D01*
G03X455565Y646507I0J-200D01*
G01X450819Y641761D01*
G02X449220Y641098I-1600J1599D01*
G01X446987D01*
G02Y645622I0J2262D01*
G01X448200D01*
G03X448342Y645680I1J200D01*
G37*
G36*
G01X435372Y713482D02*
X435708D01*
X435775Y713507D01*
X435803Y713531D01*
G02X437777I987J-1131D01*
G01X437805Y713507D01*
X437872Y713482D01*
X438208D01*
X438275Y713507D01*
X438303Y713531D01*
G02X439290Y713901I987J-1131D01*
G02X440792Y712399I0J-1502D01*
G02X440386Y711372I-1502J0D01*
G01X440360Y711344D01*
X440332Y711275D01*
Y710923D01*
X440360Y710854D01*
X440386Y710826D01*
G02X440792Y709799I-1096J-1027D01*
G02X439290Y708297I-1502J0D01*
G02X438303Y708667I0J1501D01*
G01X438275Y708691D01*
X438208Y708716D01*
X437872D01*
X437805Y708691D01*
X437777Y708667D01*
G02X435803I-987J1131D01*
G01X435775Y708691D01*
X435708Y708716D01*
X435372D01*
X435305Y708691D01*
X435277Y708667D01*
G02X433303I-987J1131D01*
G01X433275Y708691D01*
X433208Y708716D01*
X432872D01*
X432805Y708691D01*
X432777Y708667D01*
G02X430803I-987J1131D01*
G01X430775Y708691D01*
X430708Y708716D01*
X430372D01*
X430305Y708691D01*
X430277Y708667D01*
G02X429290Y708297I-987J1131D01*
G02X428246Y708719I0J1502D01*
G01X428217Y708747D01*
X428145Y708776D01*
X427782Y708771D01*
X427710Y708740D01*
X427682Y708711D01*
G02X426607Y708258I-1075J1049D01*
G02X425105Y709760I0J1502D01*
G02X425511Y710787I1502J0D01*
G01X425537Y710815D01*
X425565Y710884D01*
Y711236D01*
X425537Y711305D01*
X425511Y711333D01*
G02X425105Y712360I1096J1027D01*
G02X426607Y713862I1502J0D01*
G02X427651Y713440I0J-1502D01*
G01X427680Y713412D01*
X427752Y713383D01*
X428115Y713388D01*
X428187Y713419D01*
X428215Y713448D01*
G02X429290Y713901I1075J-1049D01*
G02X430277Y713531I0J-1501D01*
G01X430305Y713507D01*
X430372Y713482D01*
X430708D01*
X430775Y713507D01*
X430803Y713531D01*
G02X432777I987J-1131D01*
G01X432805Y713507D01*
X432872Y713482D01*
X433208D01*
X433275Y713507D01*
X433303Y713531D01*
G02X435277I987J-1131D01*
G01X435305Y713507D01*
X435372Y713482D01*
G37*
G36*
G01X403385Y1535080D02*
X401347Y1533042D01*
G02X401206Y1532984I-141J142D01*
G01X398998D01*
G02X398857Y1533042I0J200D01*
G01X398193Y1533706D01*
G02X398134Y1533847I141J142D01*
G01Y1550109D01*
G02X398193Y1550250I200J-1D01*
G01X400179Y1552236D01*
G02X400320Y1552294I141J-142D01*
G01X413553D01*
G02X413694Y1552236I0J-200D01*
G01X415144Y1550786D01*
G02X415202Y1550645I-142J-141D01*
G01Y1537234D01*
G02X415144Y1537093I-200J0D01*
G01X413248Y1535197D01*
G02X413107Y1535138I-142J141D01*
G01X403527D01*
G03X403385Y1535080I-1J-200D01*
G37*
G36*
G01X488769Y988657D02*
X488362Y988667D01*
X488278Y988629D01*
X488249Y988593D01*
G02X487091Y988048I-1158J958D01*
G02Y991052I0J1502D01*
G02X488267Y990485I0J-1503D01*
G01X488295Y990449D01*
X488378Y990409D01*
X488785Y990411D01*
X488867Y990452D01*
X488896Y990489D01*
G02X490143Y991100I1247J-967D01*
G02X491349Y990539I-1J-1579D01*
G01X491378Y990505D01*
X491457Y990468D01*
X491849Y990466D01*
X491928Y990502D01*
X491957Y990535D01*
G02X493091Y991052I1134J-985D01*
G02Y988048I0J-1502D01*
G02X491977Y988543I0J1501D01*
G01X491947Y988576D01*
X491867Y988610D01*
X491475Y988600D01*
X491397Y988561D01*
X491369Y988527D01*
G02X490143Y987942I-1227J994D01*
G02X488878Y988577I1J1579D01*
G01X488850Y988614D01*
X488769Y988657D01*
G37*
G36*
G01X451189Y999792D02*
X450839Y999796D01*
X450770Y999770D01*
X450741Y999744D01*
G02X449731Y999353I-1011J1111D01*
G02Y1002357I0J1502D01*
G02X450764Y1001945I0J-1501D01*
G01X450792Y1001919D01*
X450861Y1001891D01*
X451211Y1001887D01*
X451280Y1001913D01*
X451309Y1001939D01*
G02X452319Y1002330I1011J-1111D01*
G02Y999326I0J-1502D01*
G02X451286Y999738I0J1501D01*
G01X451258Y999764D01*
X451189Y999792D01*
G37*
G36*
G01X502495Y84108D02*
Y84460D01*
X502467Y84529D01*
X502441Y84557D01*
G02X502035Y85584I1096J1027D01*
G02X505039I1502J0D01*
G02X504633Y84557I-1502J0D01*
G01X504607Y84529D01*
X504579Y84460D01*
Y84108D01*
X504607Y84039D01*
X504633Y84011D01*
G02Y81957I-1096J-1027D01*
G01X504607Y81929D01*
X504579Y81860D01*
Y81508D01*
X504607Y81439D01*
X504633Y81411D01*
G02Y79357I-1096J-1027D01*
G01X504607Y79329D01*
X504579Y79260D01*
Y78908D01*
X504607Y78839D01*
X504633Y78811D01*
G02Y76757I-1096J-1027D01*
G01X504607Y76729D01*
X504579Y76660D01*
Y76308D01*
X504607Y76239D01*
X504633Y76211D01*
G02X505039Y75184I-1096J-1027D01*
G02X502035I-1502J0D01*
G02X502441Y76211I1502J0D01*
G01X502467Y76239D01*
X502495Y76308D01*
Y76660D01*
X502467Y76729D01*
X502441Y76757D01*
G02Y78811I1096J1027D01*
G01X502467Y78839D01*
X502495Y78908D01*
Y79260D01*
X502467Y79329D01*
X502441Y79357D01*
G02Y81411I1096J1027D01*
G01X502467Y81439D01*
X502495Y81508D01*
Y81860D01*
X502467Y81929D01*
X502441Y81957D01*
G02Y84011I1096J1027D01*
G01X502467Y84039D01*
X502495Y84108D01*
G37*
G36*
G01X511973Y101516D02*
X512009Y101900D01*
X511982Y101981D01*
X511953Y102013D01*
G02X511549Y103037I1098J1025D01*
G02X514553I1502J0D01*
G02X514086Y101948I-1503J0D01*
G01X514054Y101918D01*
X514022Y101839D01*
X514035Y101454D01*
X514073Y101377D01*
X514106Y101350D01*
G02X514760Y99961I-1148J-1389D01*
G02X511156I-1802J0D01*
G02X511896Y101417I1802J0D01*
G01X511931Y101442D01*
X511973Y101516D01*
G37*
G36*
G01X531938Y116195D02*
X532057Y116168D01*
G03X532200Y116189I44J195D01*
G02X533092Y116426I893J-1566D01*
G02X533984Y116189I-1J-1803D01*
G03X534127Y116168I99J174D01*
G01X534246Y116195D01*
G03X534365Y116274I-44J195D01*
G02X535588Y116903I1222J-873D01*
G02Y113899I0J-1502D01*
G02X535356Y113917I0J1502D01*
G01X535313Y113924D01*
X535229Y113900D01*
X534964Y113674D01*
G03X534894Y113522I130J-152D01*
G01Y112324D01*
G03X534964Y112172I200J0D01*
G01X535229Y111946D01*
X535313Y111922D01*
X535356Y111929D01*
G02X535588Y111947I232J-1484D01*
G02Y108943I0J-1502D01*
G02X534365Y109572I-1J1502D01*
G03X534246Y109651I-163J-116D01*
G01X534127Y109678D01*
G03X533984Y109657I-44J-195D01*
G02X533092Y109420I-893J1566D01*
G02X532200Y109657I1J1803D01*
G03X532057Y109678I-99J-174D01*
G01X531938Y109651D01*
G03X531819Y109572I44J-195D01*
G02X530596Y108943I-1222J873D01*
G02Y111947I0J1502D01*
G02X530828Y111929I0J-1502D01*
G01X530871Y111922D01*
X530955Y111946D01*
X531220Y112172D01*
G03X531290Y112324I-130J152D01*
G01Y113522D01*
G03X531220Y113674I-200J0D01*
G01X530955Y113900D01*
X530871Y113924D01*
X530828Y113917D01*
G02X530596Y113899I-232J1484D01*
G02Y116903I0J1502D01*
G02X531819Y116274I1J-1502D01*
G03X531938Y116195I163J116D01*
G37*
G36*
G01X542340Y123307D02*
X542459Y123280D01*
G03X542602Y123301I44J195D01*
G02X543494Y123538I893J-1566D01*
G02X544386Y123301I-1J-1803D01*
G03X544529Y123280I99J174D01*
G01X544648Y123307D01*
G03X544767Y123386I-44J195D01*
G02X545990Y124015I1222J-873D01*
G02Y121011I0J-1502D01*
G02X545758Y121029I0J1502D01*
G01X545715Y121036D01*
X545631Y121012D01*
X545366Y120786D01*
G03X545296Y120634I130J-152D01*
G01Y119436D01*
G03X545366Y119284I200J0D01*
G01X545631Y119058D01*
X545715Y119034D01*
X545758Y119041D01*
G02X545990Y119059I232J-1484D01*
G02Y116055I0J-1502D01*
G02X544767Y116684I-1J1502D01*
G03X544648Y116763I-163J-116D01*
G01X544529Y116790D01*
G03X544386Y116769I-44J-195D01*
G02X543494Y116532I-893J1566D01*
G02X542602Y116769I1J1803D01*
G03X542459Y116790I-99J-174D01*
G01X542340Y116763D01*
G03X542221Y116684I44J-195D01*
G02X540998Y116055I-1222J873D01*
G02Y119059I0J1502D01*
G02X541230Y119041I0J-1502D01*
G01X541273Y119034D01*
X541357Y119058D01*
X541622Y119284D01*
G03X541692Y119436I-130J152D01*
G01Y120634D01*
G03X541622Y120786I-200J0D01*
G01X541357Y121012D01*
X541273Y121036D01*
X541230Y121029D01*
G02X540998Y121011I-232J1484D01*
G02Y124015I0J1502D01*
G02X542221Y123386I1J-1502D01*
G03X542340Y123307I163J116D01*
G37*
G36*
G01X531938Y130368D02*
X532057Y130341D01*
G03X532200Y130362I44J195D01*
G02X533092Y130598I892J-1566D01*
G02X533984Y130362I0J-1802D01*
G03X534127Y130341I99J174D01*
G01X534246Y130368D01*
G03X534365Y130447I-44J195D01*
G02X535588Y131076I1222J-873D01*
G02Y128072I0J-1502D01*
G02X535356Y128090I0J1502D01*
G01X535313Y128097D01*
X535229Y128073D01*
X534964Y127847D01*
G03X534894Y127695I130J-152D01*
G01Y126497D01*
G03X534964Y126345I200J0D01*
G01X535229Y126119D01*
X535313Y126095D01*
X535356Y126102D01*
G02X535588Y126120I232J-1484D01*
G02Y123116I0J-1502D01*
G02X534365Y123745I-1J1502D01*
G03X534246Y123824I-163J-116D01*
G01X534127Y123851D01*
G03X533984Y123830I-44J-195D01*
G02X533092Y123594I-892J1566D01*
G02X532200Y123830I0J1802D01*
G03X532057Y123851I-99J-174D01*
G01X531938Y123824D01*
G03X531819Y123745I44J-195D01*
G02X530596Y123116I-1222J873D01*
G02Y126120I0J1502D01*
G02X530828Y126102I0J-1502D01*
G01X530871Y126095D01*
X530955Y126119D01*
X531220Y126345D01*
G03X531290Y126497I-130J152D01*
G01Y127695D01*
G03X531220Y127847I-200J0D01*
G01X530955Y128073D01*
X530871Y128097D01*
X530828Y128090D01*
G02X530596Y128072I-232J1484D01*
G02Y131076I0J1502D01*
G02X531819Y130447I1J-1502D01*
G03X531938Y130368I163J116D01*
G37*
G36*
G01X542340Y137481D02*
X542459Y137454D01*
G03X542602Y137475I44J195D01*
G02X543494Y137712I893J-1566D01*
G02X544386Y137475I-1J-1803D01*
G03X544529Y137454I99J174D01*
G01X544648Y137481D01*
G03X544767Y137560I-44J195D01*
G02X545990Y138189I1222J-873D01*
G02Y135185I0J-1502D01*
G02X545758Y135203I0J1502D01*
G01X545715Y135210D01*
X545631Y135186D01*
X545366Y134960D01*
G03X545296Y134808I130J-152D01*
G01Y133610D01*
G03X545366Y133458I200J0D01*
G01X545631Y133232D01*
X545715Y133208D01*
X545758Y133215D01*
G02X545990Y133233I232J-1484D01*
G02Y130229I0J-1502D01*
G02X544767Y130858I-1J1502D01*
G03X544648Y130937I-163J-116D01*
G01X544529Y130964D01*
G03X544386Y130943I-44J-195D01*
G02X543494Y130706I-893J1566D01*
G02X542602Y130943I1J1803D01*
G03X542459Y130964I-99J-174D01*
G01X542340Y130937D01*
G03X542221Y130858I44J-195D01*
G02X540998Y130229I-1222J873D01*
G02Y133233I0J1502D01*
G02X541230Y133215I0J-1502D01*
G01X541273Y133208D01*
X541357Y133232D01*
X541622Y133458D01*
G03X541692Y133610I-130J152D01*
G01Y134808D01*
G03X541622Y134960I-200J0D01*
G01X541357Y135186D01*
X541273Y135210D01*
X541230Y135203D01*
G02X540998Y135185I-232J1484D01*
G02Y138189I0J1502D01*
G02X542221Y137560I1J-1502D01*
G03X542340Y137481I163J116D01*
G37*
G36*
G01X504787Y146496D02*
X504480D01*
G02Y153898I0J3701D01*
G01X511780D01*
G02Y146496I0J-3701D01*
G01X511473D01*
G03X511273Y146296I0J-200D01*
G01Y146236D01*
X511306Y146186D01*
G02X504954I-3176J-2091D01*
G01X504970Y146211D01*
X504987Y146266D01*
Y146296D01*
G03X504787Y146496I-200J0D01*
G37*
G36*
G01X504601Y92655D02*
X504596Y92709D01*
G02X504589Y92849I1495J145D01*
G02X507593I1502J0D01*
G02X507590Y92747I-1502J-7D01*
G01X507586Y92696D01*
X507625Y92607D01*
X507963Y92340D01*
X508058Y92322D01*
X508106Y92337D01*
G02X508637Y92417I531J-1722D01*
G02X506835Y90615I0J-1802D01*
G02X506861Y90917I1802J-3D01*
G01X506869Y90967D01*
X506839Y91059D01*
X506530Y91359D01*
X506437Y91386D01*
X506387Y91377D01*
G02X506091Y91347I-299J1472D01*
G02X505618Y91424I2J1502D01*
G01X505566Y91441D01*
X505464Y91420D01*
X505123Y91124D01*
X505088Y91026D01*
X505098Y90972D01*
G02X505127Y90650I-1773J-322D01*
G02X503325Y92452I-1802J0D01*
G02X504039Y92305I1J-1802D01*
G01X504088Y92283D01*
X504192Y92295D01*
X504558Y92560D01*
X504601Y92655D01*
G37*
G36*
G01X529355Y100457D02*
G02X528695Y101701I842J1244D01*
G02X531699I1502J0D01*
G02X531039Y100457I-1502J0D01*
G03Y99795I224J-331D01*
G02X531699Y98551I-842J-1244D01*
G02X528695I-1502J0D01*
G02X529355Y99795I1502J0D01*
G03Y100457I-224J331D01*
G37*
G36*
G01X521767Y108025D02*
G02X521185Y107908I-581J1385D01*
G02Y110912I0J1502D01*
G02X522673Y109616I0J-1502D01*
G01X522679Y109569D01*
X522732Y109492D01*
X523091Y109290D01*
X523184Y109285D01*
X523228Y109304D01*
G02X523943Y109452I715J-1655D01*
G02X525746Y107649I0J-1803D01*
G01Y104249D01*
G02X523943Y102446I-1803J0D01*
G02X523240Y102589I1J1803D01*
G01X523195Y102608D01*
X523098Y102601D01*
X522737Y102375D01*
X522687Y102291D01*
X522685Y102242D01*
G02X521185Y100821I-1500J81D01*
G02Y103825I0J1502D01*
G02X521626Y103759I1J-1502D01*
G01X521673Y103744D01*
X521769Y103762D01*
X522104Y104023D01*
X522145Y104112D01*
X522143Y104161D01*
G02X522140Y104249I1799J105D01*
G01Y107649D01*
G02X522144Y107759I1803J-10D01*
G03X522059Y107935I-200J12D01*
G01X521959Y108005D01*
G03X521767Y108025I-114J-164D01*
G37*
G36*
G01X511050Y477244D02*
X511078Y477592D01*
X511056Y477663D01*
X511032Y477693D01*
G02X510708Y478625I1178J932D01*
G02X513712I1502J0D01*
G02X513388Y477693I-1502J0D01*
G01X513364Y477663D01*
X513342Y477592D01*
X513370Y477244D01*
X513402Y477177D01*
X513431Y477151D01*
G02X514012Y475825I-1221J-1325D01*
G02X510408I-1802J0D01*
G02X510989Y477151I1802J1D01*
G01X511018Y477177D01*
X511050Y477244D01*
G37*
G36*
G01X526895Y479987D02*
X527127Y480294D01*
X527146Y480375D01*
X527138Y480418D01*
G02X527110Y480705I1474J289D01*
G02X528612Y482207I1502J0D01*
G02X529718Y481722I1J-1502D01*
G03X529865Y481657I148J135D01*
G01X530159D01*
G03X530306Y481722I-1J200D01*
G02X531412Y482207I1105J-1017D01*
G02Y479203I0J-1502D01*
G02X530306Y479688I-1J1502D01*
G03X530159Y479753I-148J-135D01*
G01X529865D01*
G03X529718Y479688I1J-200D01*
G02X528736Y479208I-1105J1017D01*
G01X528693Y479205D01*
X528619Y479164D01*
X528387Y478857D01*
X528368Y478776D01*
X528376Y478733D01*
G02X528404Y478446I-1474J-289D01*
G02X528034Y477459I-1501J0D01*
G01X528010Y477431D01*
X527985Y477364D01*
Y477028D01*
X528010Y476961D01*
X528034Y476933D01*
G02X528404Y475946I-1131J-987D01*
G02X525400I-1502J0D01*
G02X525770Y476933I1501J0D01*
G01X525794Y476961D01*
X525819Y477028D01*
Y477364D01*
X525794Y477431D01*
X525770Y477459D01*
G02X525400Y478446I1131J987D01*
G02X526778Y479943I1502J0D01*
G01X526821Y479946D01*
X526895Y479987D01*
G37*
G36*
G01X533987Y482119D02*
X533959Y482467D01*
X533927Y482534D01*
X533898Y482560D01*
G02X533317Y483886I1221J1325D01*
G02X536921I1802J0D01*
G02X536340Y482560I-1802J-1D01*
G01X536311Y482534D01*
X536279Y482467D01*
X536251Y482119D01*
X536273Y482048D01*
X536297Y482018D01*
G02X536621Y481086I-1178J-932D01*
G02X536251Y480099I-1501J0D01*
G01X536227Y480071D01*
X536202Y480004D01*
Y479668D01*
X536227Y479601D01*
X536251Y479573D01*
G02Y477599I-1131J-987D01*
G01X536227Y477571D01*
X536202Y477504D01*
Y477168D01*
X536227Y477101D01*
X536251Y477073D01*
G02X536621Y476086I-1131J-987D01*
G02X533617I-1502J0D01*
G02X533987Y477073I1501J0D01*
G01X534011Y477101D01*
X534036Y477168D01*
Y477504D01*
X534011Y477571D01*
X533987Y477599D01*
G02Y479573I1131J987D01*
G01X534011Y479601D01*
X534036Y479668D01*
Y480004D01*
X534011Y480071D01*
X533987Y480099D01*
G02X533617Y481086I1131J987D01*
G02X533941Y482018I1502J0D01*
G01X533965Y482048D01*
X533987Y482119D01*
G37*
G36*
G01X522374Y483216D02*
Y483552D01*
X522349Y483619D01*
X522325Y483647D01*
G02X521955Y484634I1131J987D01*
G02X524959I1502J0D01*
G02X524589Y483647I-1501J0D01*
G01X524565Y483619D01*
X524540Y483552D01*
Y483216D01*
X524565Y483149D01*
X524589Y483121D01*
G02X524959Y482134I-1131J-987D01*
G02X521955I-1502J0D01*
G02X522325Y483121I1501J0D01*
G01X522349Y483149D01*
X522374Y483216D01*
G37*
G36*
G01X509407Y486221D02*
X509743D01*
X509810Y486246D01*
X509838Y486270D01*
G02X511812I987J-1131D01*
G01X511840Y486246D01*
X511907Y486221D01*
X512243D01*
X512310Y486246D01*
X512338Y486270D01*
G02X513325Y486640I987J-1131D01*
G02X514827Y485138I0J-1502D01*
G02X514560Y484283I-1502J0D01*
G01X514536Y484249D01*
X514520Y484168D01*
X514599Y483801D01*
X514647Y483734D01*
X514683Y483713D01*
G02X515412Y482425I-773J-1288D01*
G02X512408I-1502J0D01*
G02X512675Y483280I1502J0D01*
G01X512699Y483314D01*
X512715Y483395D01*
X512636Y483762D01*
X512588Y483829D01*
X512552Y483850D01*
G02X512338Y484006I774J1287D01*
G01X512310Y484030D01*
X512243Y484055D01*
X511907D01*
X511840Y484030D01*
X511812Y484006D01*
G02X509838I-987J1131D01*
G01X509810Y484030D01*
X509743Y484055D01*
X509407D01*
X509340Y484030D01*
X509312Y484006D01*
G02X508325Y483636I-987J1131D01*
G02X507204Y484139I0J1501D01*
G01X507175Y484171D01*
X507097Y484206D01*
X506711Y484205D01*
X506633Y484169D01*
X506604Y484137D01*
G02X505476Y483626I-1129J991D01*
G02Y486630I0J1502D01*
G02X506597Y486127I0J-1501D01*
G01X506626Y486095D01*
X506704Y486060D01*
X507090Y486061D01*
X507168Y486097D01*
X507197Y486129D01*
G02X508325Y486640I1129J-991D01*
G02X509312Y486270I0J-1501D01*
G01X509340Y486246D01*
X509407Y486221D01*
G37*
G36*
G01X571723Y1519752D02*
X571667Y1520126D01*
X571623Y1520196D01*
X571588Y1520220D01*
G02X570930Y1521462I843J1242D01*
G02X573934I1502J0D01*
G02X573606Y1520525I-1502J0D01*
G01X573579Y1520492D01*
X573558Y1520412D01*
X573614Y1520038D01*
X573658Y1519968D01*
X573693Y1519944D01*
G02X574351Y1518702I-843J-1242D01*
G02X571347I-1502J0D01*
G02X571675Y1519639I1502J0D01*
G01X571702Y1519672D01*
X571723Y1519752D01*
G37*
G36*
G01X604857Y84108D02*
Y84460D01*
X604829Y84529D01*
X604803Y84557D01*
G02X604397Y85584I1096J1027D01*
G02X607401I1502J0D01*
G02X606995Y84557I-1502J0D01*
G01X606969Y84529D01*
X606941Y84460D01*
Y84108D01*
X606969Y84039D01*
X606995Y84011D01*
G02Y81957I-1096J-1027D01*
G01X606969Y81929D01*
X606941Y81860D01*
Y81508D01*
X606969Y81439D01*
X606995Y81411D01*
G02Y79357I-1096J-1027D01*
G01X606969Y79329D01*
X606941Y79260D01*
Y78908D01*
X606969Y78839D01*
X606995Y78811D01*
G02Y76757I-1096J-1027D01*
G01X606969Y76729D01*
X606941Y76660D01*
Y76308D01*
X606969Y76239D01*
X606995Y76211D01*
G02X607401Y75184I-1096J-1027D01*
G02X604397I-1502J0D01*
G02X604803Y76211I1502J0D01*
G01X604829Y76239D01*
X604857Y76308D01*
Y76660D01*
X604829Y76729D01*
X604803Y76757D01*
G02Y78811I1096J1027D01*
G01X604829Y78839D01*
X604857Y78908D01*
Y79260D01*
X604829Y79329D01*
X604803Y79357D01*
G02Y81411I1096J1027D01*
G01X604829Y81439D01*
X604857Y81508D01*
Y81860D01*
X604829Y81929D01*
X604803Y81957D01*
G02Y84011I1096J1027D01*
G01X604829Y84039D01*
X604857Y84108D01*
G37*
G36*
G01X614335Y101516D02*
X614371Y101900D01*
X614344Y101981D01*
X614315Y102013D01*
G02X613911Y103037I1098J1025D01*
G02X616915I1502J0D01*
G02X616448Y101948I-1503J0D01*
G01X616416Y101918D01*
X616384Y101839D01*
X616397Y101454D01*
X616435Y101377D01*
X616468Y101350D01*
G02X617122Y99961I-1148J-1389D01*
G02X613518I-1802J0D01*
G02X614258Y101417I1802J0D01*
G01X614293Y101442D01*
X614335Y101516D01*
G37*
G36*
G01X634300Y116195D02*
X634419Y116168D01*
G03X634562Y116189I44J195D01*
G02X635454Y116426I893J-1566D01*
G02X636346Y116189I-1J-1803D01*
G03X636489Y116168I99J174D01*
G01X636608Y116195D01*
G03X636727Y116274I-44J195D01*
G02X637950Y116903I1222J-873D01*
G02Y113899I0J-1502D01*
G02X637718Y113917I0J1502D01*
G01X637675Y113924D01*
X637591Y113900D01*
X637326Y113674D01*
G03X637256Y113522I130J-152D01*
G01Y112324D01*
G03X637326Y112172I200J0D01*
G01X637591Y111946D01*
X637675Y111922D01*
X637718Y111929D01*
G02X637950Y111947I232J-1484D01*
G02Y108943I0J-1502D01*
G02X636727Y109572I-1J1502D01*
G03X636608Y109651I-163J-116D01*
G01X636489Y109678D01*
G03X636346Y109657I-44J-195D01*
G02X635454Y109420I-893J1566D01*
G02X634562Y109657I1J1803D01*
G03X634419Y109678I-99J-174D01*
G01X634300Y109651D01*
G03X634181Y109572I44J-195D01*
G02X632958Y108943I-1222J873D01*
G02Y111947I0J1502D01*
G02X633190Y111929I0J-1502D01*
G01X633233Y111922D01*
X633317Y111946D01*
X633582Y112172D01*
G03X633652Y112324I-130J152D01*
G01Y113522D01*
G03X633582Y113674I-200J0D01*
G01X633317Y113900D01*
X633233Y113924D01*
X633190Y113917D01*
G02X632958Y113899I-232J1484D01*
G02Y116903I0J1502D01*
G02X634181Y116274I1J-1502D01*
G03X634300Y116195I163J116D01*
G37*
G36*
G01X644702Y123307D02*
X644821Y123280D01*
G03X644964Y123301I44J195D01*
G02X645856Y123538I893J-1566D01*
G02X646748Y123301I-1J-1803D01*
G03X646891Y123280I99J174D01*
G01X647010Y123307D01*
G03X647129Y123386I-44J195D01*
G02X648352Y124015I1222J-873D01*
G02Y121011I0J-1502D01*
G02X648120Y121029I0J1502D01*
G01X648077Y121036D01*
X647993Y121012D01*
X647728Y120786D01*
G03X647658Y120634I130J-152D01*
G01Y119436D01*
G03X647728Y119284I200J0D01*
G01X647993Y119058D01*
X648077Y119034D01*
X648120Y119041D01*
G02X648352Y119059I232J-1484D01*
G02Y116055I0J-1502D01*
G02X647129Y116684I-1J1502D01*
G03X647010Y116763I-163J-116D01*
G01X646891Y116790D01*
G03X646748Y116769I-44J-195D01*
G02X645856Y116532I-893J1566D01*
G02X644964Y116769I1J1803D01*
G03X644821Y116790I-99J-174D01*
G01X644702Y116763D01*
G03X644583Y116684I44J-195D01*
G02X643360Y116055I-1222J873D01*
G02Y119059I0J1502D01*
G02X643592Y119041I0J-1502D01*
G01X643635Y119034D01*
X643719Y119058D01*
X643984Y119284D01*
G03X644054Y119436I-130J152D01*
G01Y120634D01*
G03X643984Y120786I-200J0D01*
G01X643719Y121012D01*
X643635Y121036D01*
X643592Y121029D01*
G02X643360Y121011I-232J1484D01*
G02Y124015I0J1502D01*
G02X644583Y123386I1J-1502D01*
G03X644702Y123307I163J116D01*
G37*
G36*
G01X634300Y130368D02*
X634419Y130341D01*
G03X634562Y130362I44J195D01*
G02X635454Y130598I892J-1566D01*
G02X636346Y130362I0J-1802D01*
G03X636489Y130341I99J174D01*
G01X636608Y130368D01*
G03X636727Y130447I-44J195D01*
G02X637950Y131076I1222J-873D01*
G02Y128072I0J-1502D01*
G02X637718Y128090I0J1502D01*
G01X637675Y128097D01*
X637591Y128073D01*
X637326Y127847D01*
G03X637256Y127695I130J-152D01*
G01Y126497D01*
G03X637326Y126345I200J0D01*
G01X637591Y126119D01*
X637675Y126095D01*
X637718Y126102D01*
G02X637950Y126120I232J-1484D01*
G02Y123116I0J-1502D01*
G02X636727Y123745I-1J1502D01*
G03X636608Y123824I-163J-116D01*
G01X636489Y123851D01*
G03X636346Y123830I-44J-195D01*
G02X635454Y123594I-892J1566D01*
G02X634562Y123830I0J1802D01*
G03X634419Y123851I-99J-174D01*
G01X634300Y123824D01*
G03X634181Y123745I44J-195D01*
G02X632958Y123116I-1222J873D01*
G02Y126120I0J1502D01*
G02X633190Y126102I0J-1502D01*
G01X633233Y126095D01*
X633317Y126119D01*
X633582Y126345D01*
G03X633652Y126497I-130J152D01*
G01Y127695D01*
G03X633582Y127847I-200J0D01*
G01X633317Y128073D01*
X633233Y128097D01*
X633190Y128090D01*
G02X632958Y128072I-232J1484D01*
G02Y131076I0J1502D01*
G02X634181Y130447I1J-1502D01*
G03X634300Y130368I163J116D01*
G37*
G36*
G01X644702Y137481D02*
X644821Y137454D01*
G03X644964Y137475I44J195D01*
G02X645856Y137712I893J-1566D01*
G02X646748Y137475I-1J-1803D01*
G03X646891Y137454I99J174D01*
G01X647010Y137481D01*
G03X647129Y137560I-44J195D01*
G02X648352Y138189I1222J-873D01*
G02Y135185I0J-1502D01*
G02X648120Y135203I0J1502D01*
G01X648077Y135210D01*
X647993Y135186D01*
X647728Y134960D01*
G03X647658Y134808I130J-152D01*
G01Y133610D01*
G03X647728Y133458I200J0D01*
G01X647993Y133232D01*
X648077Y133208D01*
X648120Y133215D01*
G02X648352Y133233I232J-1484D01*
G02Y130229I0J-1502D01*
G02X647129Y130858I-1J1502D01*
G03X647010Y130937I-163J-116D01*
G01X646891Y130964D01*
G03X646748Y130943I-44J-195D01*
G02X645856Y130706I-893J1566D01*
G02X644964Y130943I1J1803D01*
G03X644821Y130964I-99J-174D01*
G01X644702Y130937D01*
G03X644583Y130858I44J-195D01*
G02X643360Y130229I-1222J873D01*
G02Y133233I0J1502D01*
G02X643592Y133215I0J-1502D01*
G01X643635Y133208D01*
X643719Y133232D01*
X643984Y133458D01*
G03X644054Y133610I-130J152D01*
G01Y134808D01*
G03X643984Y134960I-200J0D01*
G01X643719Y135186D01*
X643635Y135210D01*
X643592Y135203D01*
G02X643360Y135185I-232J1484D01*
G02Y138189I0J1502D01*
G02X644583Y137560I1J-1502D01*
G03X644702Y137481I163J116D01*
G37*
G36*
G01X607149Y146496D02*
X606842D01*
G02Y153898I0J3701D01*
G01X614142D01*
G02Y146496I0J-3701D01*
G01X613835D01*
G03X613635Y146296I0J-200D01*
G01Y146236D01*
X613668Y146186D01*
G02X607316I-3176J-2091D01*
G01X607332Y146211D01*
X607349Y146266D01*
Y146296D01*
G03X607149Y146496I-200J0D01*
G37*
G36*
G01X606963Y92655D02*
X606958Y92709D01*
G02X606951Y92849I1495J145D01*
G02X609955I1502J0D01*
G02X609952Y92747I-1502J-7D01*
G01X609948Y92696D01*
X609987Y92607D01*
X610325Y92340D01*
X610420Y92322D01*
X610468Y92337D01*
G02X610999Y92417I531J-1722D01*
G02X609197Y90615I0J-1802D01*
G02X609223Y90917I1802J-3D01*
G01X609231Y90967D01*
X609201Y91059D01*
X608892Y91359D01*
X608799Y91386D01*
X608749Y91377D01*
G02X608453Y91347I-299J1472D01*
G02X607980Y91424I2J1502D01*
G01X607928Y91441D01*
X607826Y91420D01*
X607485Y91124D01*
X607450Y91026D01*
X607460Y90972D01*
G02X607489Y90650I-1773J-322D01*
G02X605687Y92452I-1802J0D01*
G02X606401Y92305I1J-1802D01*
G01X606450Y92283D01*
X606554Y92295D01*
X606920Y92560D01*
X606963Y92655D01*
G37*
G36*
G01X631717Y100457D02*
G02X631057Y101701I842J1244D01*
G02X634061I1502J0D01*
G02X633401Y100457I-1502J0D01*
G03Y99795I224J-331D01*
G02X634061Y98551I-842J-1244D01*
G02X631057I-1502J0D01*
G02X631717Y99795I1502J0D01*
G03Y100457I-224J331D01*
G37*
G36*
G01X624129Y108025D02*
G02X623547Y107908I-581J1385D01*
G02Y110912I0J1502D01*
G02X625035Y109616I0J-1502D01*
G01X625041Y109569D01*
X625094Y109492D01*
X625453Y109290D01*
X625546Y109285D01*
X625590Y109304D01*
G02X626305Y109452I715J-1655D01*
G02X628108Y107649I0J-1803D01*
G01Y104249D01*
G02X626305Y102446I-1803J0D01*
G02X625602Y102589I1J1803D01*
G01X625557Y102608D01*
X625460Y102601D01*
X625099Y102375D01*
X625049Y102291D01*
X625047Y102242D01*
G02X623547Y100821I-1500J81D01*
G02Y103825I0J1502D01*
G02X623988Y103759I1J-1502D01*
G01X624035Y103744D01*
X624131Y103762D01*
X624466Y104023D01*
X624507Y104112D01*
X624505Y104161D01*
G02X624502Y104249I1799J105D01*
G01Y107649D01*
G02X624506Y107759I1803J-10D01*
G03X624421Y107935I-200J12D01*
G01X624321Y108005D01*
G03X624129Y108025I-114J-164D01*
G37*
G36*
G01X650337Y1146928D02*
X649270D01*
X649244Y1146921D01*
G02X648917Y1146877I-329J1208D01*
G02Y1149381I0J1252D01*
G02X649244Y1149337I-2J-1252D01*
G01X649270Y1149330D01*
X650337D01*
G02X650788Y1148879I0J-451D01*
G01Y1147379D01*
G02X650337Y1146928I-451J0D01*
G37*
G36*
G01X647716Y1155963D02*
Y1157030D01*
G02X648167Y1157482I451J1D01*
G01X649667D01*
G02X650118Y1157030I-1J-452D01*
G01Y1155963D01*
X650125Y1155937D01*
G02X650169Y1155610I-1208J-329D01*
G02X647665I-1252J0D01*
G02X647709Y1155937I1252J-2D01*
G01X647716Y1155963D01*
G37*
G36*
G01X651456Y1157930D02*
Y1158997D01*
X651449Y1159023D01*
G02X651405Y1159350I1208J329D01*
G02X653909I1252J0D01*
G02X653865Y1159023I-1252J2D01*
G01X653858Y1158997D01*
Y1157930D01*
G02X653407Y1157478I-451J-1D01*
G01X651907D01*
G02X651456Y1157930I1J452D01*
G37*
G36*
G01X658936D02*
Y1158997D01*
X658930Y1159023D01*
G02X658886Y1159350I1208J329D01*
G02X661390I1252J0D01*
G02X661346Y1159023I-1252J2D01*
G01X661340Y1158997D01*
Y1157930D01*
G02X660888Y1157478I-452J0D01*
G01X659388D01*
G02X658936Y1157930I0J452D01*
G37*
G36*
G01X673896D02*
Y1158997D01*
X673890Y1159023D01*
G02X673846Y1159350I1208J329D01*
G02X676350I1252J0D01*
G02X676306Y1159023I-1252J2D01*
G01X676300Y1158997D01*
Y1157930D01*
G02X675848Y1157478I-452J0D01*
G01X674348D01*
G02X673896Y1157930I0J452D01*
G37*
G36*
G01X692598D02*
Y1158997D01*
X692591Y1159023D01*
G02X692547Y1159350I1208J329D01*
G02X695051I1252J0D01*
G02X695007Y1159023I-1252J2D01*
G01X695000Y1158997D01*
Y1157930D01*
G02X694549Y1157478I-451J-1D01*
G01X693049D01*
G02X692598Y1157930I1J452D01*
G37*
G36*
G01X707558D02*
Y1158997D01*
X707552Y1159023D01*
G02X707508Y1159350I1208J329D01*
G02X710012I1252J0D01*
G02X709968Y1159023I-1252J2D01*
G01X709962Y1158997D01*
Y1157930D01*
G02X709510Y1157478I-452J0D01*
G01X708010D01*
G02X707558Y1157930I0J452D01*
G37*
G36*
G01X663278Y1160891D02*
Y1163691D01*
G02X663729Y1164142I451J0D01*
G01X666929D01*
G02X667380Y1163691I0J-451D01*
G01Y1161809D01*
G03X667439Y1161668I200J1D01*
G01X668362Y1160746D01*
G02X668667Y1160077I-744J-743D01*
G03X668694Y1159990I199J14D01*
G02X668870Y1159350I-1076J-640D01*
G02X668826Y1159023I-1252J2D01*
G01X668820Y1158997D01*
Y1157930D01*
G02X668368Y1157478I-452J0D01*
G01X666868D01*
G02X666416Y1157930I0J452D01*
G01Y1158997D01*
X666410Y1159023D01*
G02X666366Y1159350I1208J329D01*
G02X666393Y1159611I1252J2D01*
G01X666404Y1159661D01*
X666376Y1159757D01*
X665752Y1160381D01*
G03X665611Y1160440I-142J-141D01*
G01X663729D01*
G02X663278Y1160891I0J451D01*
G37*
G36*
G01X678238D02*
Y1163691D01*
G02X678690Y1164142I452J-1D01*
G01X681890D01*
G02X682342Y1163691I1J-451D01*
G01Y1161809D01*
G03X682400Y1161668I200J0D01*
G01X683323Y1160746D01*
G02X683628Y1160077I-744J-743D01*
G03X683655Y1159990I199J14D01*
G02X683831Y1159350I-1076J-640D01*
G02X683787Y1159023I-1252J2D01*
G01X683780Y1158997D01*
Y1157930D01*
G02X683329Y1157478I-451J-1D01*
G01X681829D01*
G02X681378Y1157930I1J452D01*
G01Y1158997D01*
X681371Y1159023D01*
G02X681327Y1159350I1208J329D01*
G02X681354Y1159611I1252J2D01*
G01X681365Y1159661D01*
X681337Y1159757D01*
X680713Y1160381D01*
G03X680572Y1160440I-142J-141D01*
G01X678690D01*
G02X678238Y1160891I-1J451D01*
G37*
G36*
G01X696940D02*
Y1163691D01*
G02X697391Y1164142I451J0D01*
G01X700591D01*
G02X701042Y1163691I0J-451D01*
G01Y1161809D01*
G03X701101Y1161668I200J1D01*
G01X702023Y1160747D01*
G02X702328Y1160077I-744J-743D01*
G03X702355Y1159989I200J13D01*
G02X702531Y1159350I-1076J-640D01*
G02X702487Y1159023I-1252J2D01*
G01X702480Y1158997D01*
Y1157930D01*
G02X702029Y1157478I-451J-1D01*
G01X700529D01*
G02X700078Y1157930I1J452D01*
G01Y1158997D01*
X700071Y1159023D01*
G02X700027Y1159350I1208J329D01*
G02X700055Y1159611I1252J-2D01*
G01X700065Y1159662D01*
X700037Y1159758D01*
X699414Y1160381D01*
G03X699273Y1160440I-142J-141D01*
G01X697391D01*
G02X696940Y1160891I0J451D01*
G37*
G36*
G01X650417Y1165628D02*
X649270D01*
X649244Y1165622D01*
G02X648917Y1165578I-329J1208D01*
G02Y1168082I0J1252D01*
G02X649244Y1168038I-2J-1252D01*
G01X649270Y1168032D01*
X650417D01*
G02X650868Y1167580I-1J-452D01*
G01Y1166080D01*
G02X650417Y1165628I-451J-1D01*
G37*
G36*
G01X657898D02*
X656751D01*
X656725Y1165622D01*
G02X656398Y1165578I-329J1208D01*
G02Y1168082I0J1252D01*
G02X656725Y1168038I-2J-1252D01*
G01X656751Y1168032D01*
X657898D01*
G02X658350Y1167580I0J-452D01*
G01Y1166080D01*
G02X657898Y1165628I-452J0D01*
G37*
G36*
G01X665378D02*
X664231D01*
X664205Y1165622D01*
G02X663878Y1165578I-329J1208D01*
G02Y1168082I0J1252D01*
G02X664205Y1168038I-2J-1252D01*
G01X664231Y1168032D01*
X665378D01*
G02X665830Y1167580I0J-452D01*
G01Y1166080D01*
G02X665378Y1165628I-452J0D01*
G37*
G36*
G01X672858D02*
X671711D01*
X671685Y1165622D01*
G02X671358Y1165578I-329J1208D01*
G02Y1168082I0J1252D01*
G02X671685Y1168038I-2J-1252D01*
G01X671711Y1168032D01*
X672858D01*
G02X673310Y1167580I0J-452D01*
G01Y1166080D01*
G02X672858Y1165628I-452J0D01*
G37*
G36*
G01X680339D02*
X679192D01*
X679166Y1165622D01*
G02X678839Y1165578I-329J1208D01*
G02Y1168082I0J1252D01*
G02X679166Y1168038I-2J-1252D01*
G01X679192Y1168032D01*
X680339D01*
G02X680790Y1167580I-1J-452D01*
G01Y1166080D01*
G02X680339Y1165628I-451J-1D01*
G37*
G36*
G01X687819D02*
X686672D01*
X686646Y1165622D01*
G02X686319Y1165578I-329J1208D01*
G02Y1168082I0J1252D01*
G02X686646Y1168038I-2J-1252D01*
G01X686672Y1168032D01*
X687819D01*
G02X688270Y1167580I-1J-452D01*
G01Y1166080D01*
G02X687819Y1165628I-451J-1D01*
G37*
G36*
G01X695299Y1168032D02*
X696499D01*
G02X696835Y1167882I0J-451D01*
G01X696859D01*
G02X697539Y1168082I679J-1052D01*
G02X698219Y1167882I1J-1252D01*
G01X698243D01*
G02X698579Y1168032I336J-301D01*
G01X699779D01*
G02X700230Y1167580I-1J-452D01*
G01Y1166080D01*
G02X699779Y1165628I-451J-1D01*
G01X698579D01*
G02X698243Y1165778I0J451D01*
G01X698219D01*
G02X697539Y1165578I-679J1052D01*
G02X696859Y1165778I-1J1252D01*
G01X696835D01*
G02X696499Y1165628I-336J301D01*
G01X695299D01*
G02X694848Y1166080I1J452D01*
G01Y1167580D01*
G02X695299Y1168032I451J1D01*
G37*
G36*
G01X706520Y1165628D02*
X705373D01*
X705347Y1165622D01*
G02X705020Y1165578I-329J1208D01*
G02Y1168082I0J1252D01*
G02X705347Y1168038I-2J-1252D01*
G01X705373Y1168032D01*
X706520D01*
G02X706972Y1167580I0J-452D01*
G01Y1166080D01*
G02X706520Y1165628I-452J0D01*
G37*
G36*
G01X714000D02*
X712853D01*
X712827Y1165622D01*
G02X712500Y1165578I-329J1208D01*
G02Y1168082I0J1252D01*
G02X712827Y1168038I-2J-1252D01*
G01X712853Y1168032D01*
X714000D01*
G02X714452Y1167580I0J-452D01*
G01Y1166080D01*
G02X714000Y1165628I-452J0D01*
G37*
G36*
G01X651456Y1170923D02*
Y1171990D01*
G02X651907Y1172442I451J1D01*
G01X653407D01*
G02X653858Y1171990I-1J-452D01*
G01Y1170923D01*
X653865Y1170897D01*
G02X653909Y1170570I-1208J-329D01*
G02X651405I-1252J0D01*
G02X651449Y1170897I1252J-2D01*
G01X651456Y1170923D01*
G37*
G36*
G01X658936D02*
Y1171990D01*
G02X659388Y1172442I452J0D01*
G01X660888D01*
G02X661340Y1171990I0J-452D01*
G01Y1170923D01*
X661346Y1170897D01*
G02X661390Y1170570I-1208J-329D01*
G02X658886I-1252J0D01*
G02X658930Y1170897I1252J-2D01*
G01X658936Y1170923D01*
G37*
G36*
G01X666416D02*
Y1171990D01*
G02X666868Y1172442I452J0D01*
G01X668368D01*
G02X668820Y1171990I0J-452D01*
G01Y1170923D01*
X668826Y1170897D01*
G02X668870Y1170570I-1208J-329D01*
G02X666366I-1252J0D01*
G02X666410Y1170897I1252J-2D01*
G01X666416Y1170923D01*
G37*
G36*
G01X673896D02*
Y1171990D01*
G02X674348Y1172442I452J0D01*
G01X675848D01*
G02X676300Y1171990I0J-452D01*
G01Y1170923D01*
X676306Y1170897D01*
G02X676350Y1170570I-1208J-329D01*
G02X673846I-1252J0D01*
G02X673890Y1170897I1252J-2D01*
G01X673896Y1170923D01*
G37*
G36*
G01X681378D02*
Y1171990D01*
G02X681829Y1172442I451J1D01*
G01X683329D01*
G02X683780Y1171990I-1J-452D01*
G01Y1170923D01*
X683787Y1170897D01*
G02X683831Y1170570I-1208J-329D01*
G02X681327I-1252J0D01*
G02X681371Y1170897I1252J-2D01*
G01X681378Y1170923D01*
G37*
G36*
G01X692598D02*
Y1171990D01*
G02X693049Y1172442I451J1D01*
G01X694549D01*
G02X695000Y1171990I-1J-452D01*
G01Y1170923D01*
X695007Y1170897D01*
G02X695051Y1170570I-1208J-329D01*
G02X692547I-1252J0D01*
G02X692591Y1170897I1252J-2D01*
G01X692598Y1170923D01*
G37*
G36*
G01X700078D02*
Y1171990D01*
G02X700529Y1172442I451J1D01*
G01X702029D01*
G02X702480Y1171990I-1J-452D01*
G01Y1170923D01*
X702487Y1170897D01*
G02X702531Y1170570I-1208J-329D01*
G02X700027I-1252J0D01*
G02X700071Y1170897I1252J-2D01*
G01X700078Y1170923D01*
G37*
G36*
G01X707558D02*
Y1171990D01*
G02X708010Y1172442I452J0D01*
G01X709510D01*
G02X709962Y1171990I0J-452D01*
G01Y1170923D01*
X709968Y1170897D01*
G02X710012Y1170570I-1208J-329D01*
G02X707508I-1252J0D01*
G02X707552Y1170897I1252J-2D01*
G01X707558Y1170923D01*
G37*
G36*
G01X647716Y1172890D02*
Y1173957D01*
X647709Y1173983D01*
G02X647665Y1174310I1208J329D01*
G02X650169I1252J0D01*
G02X650125Y1173983I-1252J2D01*
G01X650118Y1173957D01*
Y1172890D01*
G02X649667Y1172438I-451J-1D01*
G01X648167D01*
G02X647716Y1172890I1J452D01*
G37*
G36*
G01X650337Y1180590D02*
X649270D01*
X649244Y1180583D01*
G02X648917Y1180539I-329J1208D01*
G02Y1183043I0J1252D01*
G02X649244Y1182999I-2J-1252D01*
G01X649270Y1182992D01*
X650337D01*
G02X650788Y1182541I0J-451D01*
G01Y1181041D01*
G02X650337Y1180590I-451J0D01*
G37*
G36*
G01X656645Y1150022D02*
X656769Y1150146D01*
G02X657619Y1150498I850J-849D01*
G01X723955D01*
G02X724805Y1150146I0J-1201D01*
G01X725186Y1149765D01*
G02X725538Y1148915I-849J-850D01*
G01Y1147878D01*
G02X725356Y1147242I-1202J0D01*
G01X724392Y1146278D01*
G02X723756Y1146096I-636J1019D01*
G01X657719D01*
G02X656869Y1146448I0J1201D01*
G01X656471Y1146846D01*
X656401Y1146876D01*
X656363Y1146877D01*
G02X655146Y1148129I36J1252D01*
G02X656251Y1149372I1252J0D01*
G01X656305Y1149379D01*
X656391Y1149444D01*
X656602Y1149956D01*
G02X656645Y1150022I186J-74D01*
G37*
G36*
G01X724046Y1156819D02*
X724071Y1156812D01*
X727109D01*
X727134Y1156819D01*
G02X727460Y1156862I325J-1209D01*
G02Y1154358I0J-1252D01*
G02X727134Y1154401I-1J1252D01*
G01X727109Y1154408D01*
X724071D01*
X724046Y1154401D01*
G02X723720Y1154358I-325J1209D01*
G02Y1156862I0J1252D01*
G02X724046Y1156819I1J-1252D01*
G37*
G36*
G01X654682Y1181299D02*
Y1182248D01*
G02X655034Y1183098I1201J0D01*
G01X655250Y1183314D01*
G02X656100Y1183666I850J-849D01*
G01X724153D01*
G02X725003Y1183314I0J-1201D01*
G01X725186Y1183131D01*
G02X725538Y1182281I-849J-850D01*
G01Y1181541D01*
G02X725186Y1180691I-1201J0D01*
G01X725185D01*
X724235Y1179741D01*
Y1179740D01*
G02X723385Y1179388I-850J849D01*
G01X656593D01*
G02X655743Y1179740I0J1201D01*
G01X655034Y1180449D01*
G02X654682Y1181299I849J850D01*
G37*
G36*
G01X707219Y84108D02*
Y84460D01*
X707191Y84529D01*
X707165Y84557D01*
G02X706759Y85584I1096J1027D01*
G02X709763I1502J0D01*
G02X709357Y84557I-1502J0D01*
G01X709331Y84529D01*
X709303Y84460D01*
Y84108D01*
X709331Y84039D01*
X709357Y84011D01*
G02Y81957I-1096J-1027D01*
G01X709331Y81929D01*
X709303Y81860D01*
Y81508D01*
X709331Y81439D01*
X709357Y81411D01*
G02Y79357I-1096J-1027D01*
G01X709331Y79329D01*
X709303Y79260D01*
Y78908D01*
X709331Y78839D01*
X709357Y78811D01*
G02Y76757I-1096J-1027D01*
G01X709331Y76729D01*
X709303Y76660D01*
Y76308D01*
X709331Y76239D01*
X709357Y76211D01*
G02X709763Y75184I-1096J-1027D01*
G02X706759I-1502J0D01*
G02X707165Y76211I1502J0D01*
G01X707191Y76239D01*
X707219Y76308D01*
Y76660D01*
X707191Y76729D01*
X707165Y76757D01*
G02Y78811I1096J1027D01*
G01X707191Y78839D01*
X707219Y78908D01*
Y79260D01*
X707191Y79329D01*
X707165Y79357D01*
G02Y81411I1096J1027D01*
G01X707191Y81439D01*
X707219Y81508D01*
Y81860D01*
X707191Y81929D01*
X707165Y81957D01*
G02Y84011I1096J1027D01*
G01X707191Y84039D01*
X707219Y84108D01*
G37*
G36*
G01X716697Y101516D02*
X716733Y101900D01*
X716706Y101981D01*
X716677Y102013D01*
G02X716273Y103037I1098J1025D01*
G02X719277I1502J0D01*
G02X718810Y101948I-1503J0D01*
G01X718778Y101918D01*
X718746Y101839D01*
X718759Y101454D01*
X718797Y101377D01*
X718830Y101350D01*
G02X719484Y99961I-1148J-1389D01*
G02X715880I-1802J0D01*
G02X716620Y101417I1802J0D01*
G01X716655Y101442D01*
X716697Y101516D01*
G37*
G36*
G01X736662Y116195D02*
X736781Y116168D01*
G03X736924Y116189I44J195D01*
G02X737816Y116426I893J-1566D01*
G02X738708Y116189I-1J-1803D01*
G03X738851Y116168I99J174D01*
G01X738970Y116195D01*
G03X739089Y116274I-44J195D01*
G02X740312Y116903I1222J-873D01*
G02Y113899I0J-1502D01*
G02X740080Y113917I0J1502D01*
G01X740037Y113924D01*
X739953Y113900D01*
X739688Y113674D01*
G03X739618Y113522I130J-152D01*
G01Y112324D01*
G03X739688Y112172I200J0D01*
G01X739953Y111946D01*
X740037Y111922D01*
X740080Y111929D01*
G02X740312Y111947I232J-1484D01*
G02Y108943I0J-1502D01*
G02X739089Y109572I-1J1502D01*
G03X738970Y109651I-163J-116D01*
G01X738851Y109678D01*
G03X738708Y109657I-44J-195D01*
G02X737816Y109420I-893J1566D01*
G02X736924Y109657I1J1803D01*
G03X736781Y109678I-99J-174D01*
G01X736662Y109651D01*
G03X736543Y109572I44J-195D01*
G02X735320Y108943I-1222J873D01*
G02Y111947I0J1502D01*
G02X735552Y111929I0J-1502D01*
G01X735595Y111922D01*
X735679Y111946D01*
X735944Y112172D01*
G03X736014Y112324I-130J152D01*
G01Y113522D01*
G03X735944Y113674I-200J0D01*
G01X735679Y113900D01*
X735595Y113924D01*
X735552Y113917D01*
G02X735320Y113899I-232J1484D01*
G02Y116903I0J1502D01*
G02X736543Y116274I1J-1502D01*
G03X736662Y116195I163J116D01*
G37*
G36*
G01X747064Y123307D02*
X747183Y123280D01*
G03X747326Y123301I44J195D01*
G02X748218Y123538I893J-1566D01*
G02X749110Y123301I-1J-1803D01*
G03X749253Y123280I99J174D01*
G01X749372Y123307D01*
G03X749491Y123386I-44J195D01*
G02X750714Y124015I1222J-873D01*
G02Y121011I0J-1502D01*
G02X750482Y121029I0J1502D01*
G01X750439Y121036D01*
X750355Y121012D01*
X750090Y120786D01*
G03X750020Y120634I130J-152D01*
G01Y119436D01*
G03X750090Y119284I200J0D01*
G01X750355Y119058D01*
X750439Y119034D01*
X750482Y119041D01*
G02X750714Y119059I232J-1484D01*
G02Y116055I0J-1502D01*
G02X749491Y116684I-1J1502D01*
G03X749372Y116763I-163J-116D01*
G01X749253Y116790D01*
G03X749110Y116769I-44J-195D01*
G02X748218Y116532I-893J1566D01*
G02X747326Y116769I1J1803D01*
G03X747183Y116790I-99J-174D01*
G01X747064Y116763D01*
G03X746945Y116684I44J-195D01*
G02X745722Y116055I-1222J873D01*
G02Y119059I0J1502D01*
G02X745954Y119041I0J-1502D01*
G01X745997Y119034D01*
X746081Y119058D01*
X746346Y119284D01*
G03X746416Y119436I-130J152D01*
G01Y120634D01*
G03X746346Y120786I-200J0D01*
G01X746081Y121012D01*
X745997Y121036D01*
X745954Y121029D01*
G02X745722Y121011I-232J1484D01*
G02Y124015I0J1502D01*
G02X746945Y123386I1J-1502D01*
G03X747064Y123307I163J116D01*
G37*
G36*
G01X736662Y130368D02*
X736781Y130341D01*
G03X736924Y130362I44J195D01*
G02X737816Y130598I892J-1566D01*
G02X738708Y130362I0J-1802D01*
G03X738851Y130341I99J174D01*
G01X738970Y130368D01*
G03X739089Y130447I-44J195D01*
G02X740312Y131076I1222J-873D01*
G02Y128072I0J-1502D01*
G02X740080Y128090I0J1502D01*
G01X740037Y128097D01*
X739953Y128073D01*
X739688Y127847D01*
G03X739618Y127695I130J-152D01*
G01Y126497D01*
G03X739688Y126345I200J0D01*
G01X739953Y126119D01*
X740037Y126095D01*
X740080Y126102D01*
G02X740312Y126120I232J-1484D01*
G02Y123116I0J-1502D01*
G02X739089Y123745I-1J1502D01*
G03X738970Y123824I-163J-116D01*
G01X738851Y123851D01*
G03X738708Y123830I-44J-195D01*
G02X737816Y123594I-892J1566D01*
G02X736924Y123830I0J1802D01*
G03X736781Y123851I-99J-174D01*
G01X736662Y123824D01*
G03X736543Y123745I44J-195D01*
G02X735320Y123116I-1222J873D01*
G02Y126120I0J1502D01*
G02X735552Y126102I0J-1502D01*
G01X735595Y126095D01*
X735679Y126119D01*
X735944Y126345D01*
G03X736014Y126497I-130J152D01*
G01Y127695D01*
G03X735944Y127847I-200J0D01*
G01X735679Y128073D01*
X735595Y128097D01*
X735552Y128090D01*
G02X735320Y128072I-232J1484D01*
G02Y131076I0J1502D01*
G02X736543Y130447I1J-1502D01*
G03X736662Y130368I163J116D01*
G37*
G36*
G01X747064Y137481D02*
X747183Y137454D01*
G03X747326Y137475I44J195D01*
G02X748218Y137712I893J-1566D01*
G02X749110Y137475I-1J-1803D01*
G03X749253Y137454I99J174D01*
G01X749372Y137481D01*
G03X749491Y137560I-44J195D01*
G02X750714Y138189I1222J-873D01*
G02Y135185I0J-1502D01*
G02X750482Y135203I0J1502D01*
G01X750439Y135210D01*
X750355Y135186D01*
X750090Y134960D01*
G03X750020Y134808I130J-152D01*
G01Y133610D01*
G03X750090Y133458I200J0D01*
G01X750355Y133232D01*
X750439Y133208D01*
X750482Y133215D01*
G02X750714Y133233I232J-1484D01*
G02Y130229I0J-1502D01*
G02X749491Y130858I-1J1502D01*
G03X749372Y130937I-163J-116D01*
G01X749253Y130964D01*
G03X749110Y130943I-44J-195D01*
G02X748218Y130706I-893J1566D01*
G02X747326Y130943I1J1803D01*
G03X747183Y130964I-99J-174D01*
G01X747064Y130937D01*
G03X746945Y130858I44J-195D01*
G02X745722Y130229I-1222J873D01*
G02Y133233I0J1502D01*
G02X745954Y133215I0J-1502D01*
G01X745997Y133208D01*
X746081Y133232D01*
X746346Y133458D01*
G03X746416Y133610I-130J152D01*
G01Y134808D01*
G03X746346Y134960I-200J0D01*
G01X746081Y135186D01*
X745997Y135210D01*
X745954Y135203D01*
G02X745722Y135185I-232J1484D01*
G02Y138189I0J1502D01*
G02X746945Y137560I1J-1502D01*
G03X747064Y137481I163J116D01*
G37*
G36*
G01X709511Y146496D02*
X709204D01*
G02Y153898I0J3701D01*
G01X716504D01*
G02Y146496I0J-3701D01*
G01X716197D01*
G03X715997Y146296I0J-200D01*
G01Y146236D01*
X716030Y146186D01*
G02X709678I-3176J-2091D01*
G01X709694Y146211D01*
X709711Y146266D01*
Y146296D01*
G03X709511Y146496I-200J0D01*
G37*
G36*
G01X709325Y92655D02*
X709320Y92709D01*
G02X709313Y92849I1495J145D01*
G02X712317I1502J0D01*
G02X712314Y92747I-1502J-7D01*
G01X712310Y92696D01*
X712349Y92607D01*
X712687Y92340D01*
X712782Y92322D01*
X712830Y92337D01*
G02X713361Y92417I531J-1722D01*
G02X711559Y90615I0J-1802D01*
G02X711585Y90917I1802J-3D01*
G01X711593Y90967D01*
X711563Y91059D01*
X711254Y91359D01*
X711161Y91386D01*
X711111Y91377D01*
G02X710815Y91347I-299J1472D01*
G02X710342Y91424I2J1502D01*
G01X710290Y91441D01*
X710188Y91420D01*
X709847Y91124D01*
X709812Y91026D01*
X709822Y90972D01*
G02X709851Y90650I-1773J-322D01*
G02X708049Y92452I-1802J0D01*
G02X708763Y92305I1J-1802D01*
G01X708812Y92283D01*
X708916Y92295D01*
X709282Y92560D01*
X709325Y92655D01*
G37*
G36*
G01X734079Y100457D02*
G02X733419Y101701I842J1244D01*
G02X736423I1502J0D01*
G02X735763Y100457I-1502J0D01*
G03Y99795I224J-331D01*
G02X736423Y98551I-842J-1244D01*
G02X733419I-1502J0D01*
G02X734079Y99795I1502J0D01*
G03Y100457I-224J331D01*
G37*
G36*
G01X726491Y108025D02*
G02X725909Y107908I-581J1385D01*
G02Y110912I0J1502D01*
G02X727397Y109616I0J-1502D01*
G01X727403Y109569D01*
X727456Y109492D01*
X727815Y109290D01*
X727908Y109285D01*
X727952Y109304D01*
G02X728667Y109452I715J-1655D01*
G02X730470Y107649I0J-1803D01*
G01Y104249D01*
G02X728667Y102446I-1803J0D01*
G02X727964Y102589I1J1803D01*
G01X727919Y102608D01*
X727822Y102601D01*
X727461Y102375D01*
X727411Y102291D01*
X727409Y102242D01*
G02X725909Y100821I-1500J81D01*
G02Y103825I0J1502D01*
G02X726350Y103759I1J-1502D01*
G01X726397Y103744D01*
X726493Y103762D01*
X726828Y104023D01*
X726869Y104112D01*
X726867Y104161D01*
G02X726864Y104249I1799J105D01*
G01Y107649D01*
G02X726868Y107759I1803J-10D01*
G03X726783Y107935I-200J12D01*
G01X726683Y108005D01*
G03X726491Y108025I-114J-164D01*
G37*
G36*
G01X777203Y1621301D02*
G02X776543Y1622545I842J1244D01*
G02X779547I1502J0D01*
G02X778887Y1621301I-1502J0D01*
G03Y1620639I224J-331D01*
G02X779547Y1619395I-842J-1244D01*
G02X776543I-1502J0D01*
G02X777203Y1620639I1502J0D01*
G03Y1621301I-224J331D01*
G37*
G36*
G01X830000Y481663D02*
X830336D01*
X830403Y481688D01*
X830431Y481712D01*
G02X832405I987J-1131D01*
G01X832433Y481688D01*
X832500Y481663D01*
X832836D01*
X832903Y481688D01*
X832931Y481712D01*
G02X833918Y482082I987J-1131D01*
G02Y479078I0J-1502D01*
G02X832931Y479448I0J1501D01*
G01X832903Y479472D01*
X832836Y479497D01*
X832500D01*
X832433Y479472D01*
X832405Y479448D01*
G02X830431I-987J1131D01*
G01X830403Y479472D01*
X830336Y479497D01*
X830000D01*
X829933Y479472D01*
X829905Y479448D01*
G02X828918Y479078I-987J1131D01*
G02Y482082I0J1502D01*
G02X829905Y481712I0J-1501D01*
G01X829933Y481688D01*
X830000Y481663D01*
G37*
G36*
G01X821335Y483652D02*
Y483988D01*
X821310Y484055D01*
X821286Y484083D01*
G02X820916Y485070I1131J987D01*
G02X823920I1502J0D01*
G02X823550Y484083I-1501J0D01*
G01X823526Y484055D01*
X823501Y483988D01*
Y483652D01*
X823526Y483585D01*
X823550Y483557D01*
G02X823920Y482570I-1131J-987D01*
G02X820916I-1502J0D01*
G02X821286Y483557I1501J0D01*
G01X821310Y483585D01*
X821335Y483652D01*
G37*
G36*
G01X832341Y489089D02*
Y489383D01*
G03X832276Y489530I-200J-1D01*
G02X831791Y490636I1017J1105D01*
G02X834795I1502J0D01*
G02X834310Y489530I-1502J-1D01*
G03X834245Y489383I135J-148D01*
G01Y489089D01*
G03X834310Y488942I200J1D01*
G02X834795Y487836I-1017J-1105D01*
G02X831791I-1502J0D01*
G02X832276Y488942I1502J1D01*
G03X832341Y489089I-135J148D01*
G37*
G36*
G01X842433Y480881D02*
G02X840974Y482382I43J1501D01*
G02X843978I1502J0D01*
G02X843902Y481909I-1502J-1D01*
G03X844270Y481383I380J-126D01*
G02X845729Y479882I-43J-1501D01*
G02X842725I-1502J0D01*
G02X842801Y480355I1502J1D01*
G03X842433Y480881I-380J126D01*
G37*
G36*
G01X832331Y483240D02*
G02X831057Y482534I-1274J796D01*
G02Y485538I0J1502D01*
G02X832277Y484912I0J-1502D01*
G03X832941Y484934I325J234D01*
G02X834215Y485640I1274J-796D01*
G02Y482636I0J-1502D01*
G02X832995Y483262I0J1502D01*
G03X832331Y483240I-325J-234D01*
G37*
G36*
G01X817865Y490243D02*
X817841Y490271D01*
G02X817471Y491258I1131J987D01*
G02X820475I1502J0D01*
G02X820105Y490271I-1501J0D01*
G01X820081Y490243D01*
X820056Y490176D01*
Y489840D01*
X820081Y489773D01*
X820105Y489745D01*
G02X820475Y488758I-1131J-987D01*
G02X818973Y487256I-1502J0D01*
G02X818411Y487365I0J1503D01*
G01X818363Y487385D01*
X818262Y487372D01*
X817903Y487112D01*
X817859Y487020D01*
X817863Y486968D01*
G02X817866Y486870I-1499J-95D01*
G02X816364Y485368I-1502J0D01*
G02X815377Y485738I0J1501D01*
G01X815349Y485762D01*
X815282Y485787D01*
X814946D01*
X814879Y485762D01*
X814851Y485738D01*
G02X813864Y485368I-987J1131D01*
G02X812828Y485782I0J1503D01*
G01X812791Y485818D01*
X812693Y485844D01*
X812267Y485741D01*
X812191Y485672D01*
X812175Y485624D01*
G02X811888Y485131I-1418J496D01*
G01X811864Y485103D01*
X811839Y485036D01*
Y484700D01*
X811864Y484633D01*
X811888Y484605D01*
G02X812258Y483618I-1131J-987D01*
G02X809254I-1502J0D01*
G02X809624Y484605I1501J0D01*
G01X809648Y484633D01*
X809673Y484700D01*
Y485036D01*
X809648Y485103D01*
X809624Y485131D01*
G02Y487105I1131J987D01*
G01X809648Y487133D01*
X809673Y487200D01*
Y487536D01*
X809648Y487603D01*
X809624Y487631D01*
G02Y489605I1131J987D01*
G01X809648Y489633D01*
X809673Y489700D01*
Y490036D01*
X809648Y490103D01*
X809624Y490131D01*
G02X809254Y491118I1131J987D01*
G02X812258I1502J0D01*
G02X811888Y490131I-1501J0D01*
G01X811864Y490103D01*
X811839Y490036D01*
Y489700D01*
X811864Y489633D01*
X811888Y489605D01*
G02Y487631I-1131J-987D01*
G01X811864Y487603D01*
X811839Y487536D01*
Y487200D01*
X811864Y487133D01*
X811888Y487105D01*
G02X812006Y486950I-1133J-985D01*
G03X812372Y487039I167J111D01*
G02X813864Y488372I1492J-168D01*
G02X814851Y488002I0J-1501D01*
G01X814879Y487978D01*
X814946Y487953D01*
X815282D01*
X815349Y487978D01*
X815377Y488002D01*
G02X816364Y488372I987J-1131D01*
G02X816926Y488263I0J-1503D01*
G01X816974Y488243D01*
X817075Y488256D01*
X817434Y488516D01*
X817478Y488608D01*
X817474Y488660D01*
G02X817471Y488758I1499J95D01*
G02X817841Y489745I1501J0D01*
G01X817865Y489773D01*
X817890Y489840D01*
Y490176D01*
X817865Y490243D01*
G37*
G36*
G01X809581Y84108D02*
Y84460D01*
X809553Y84529D01*
X809527Y84557D01*
G02X809121Y85584I1096J1027D01*
G02X812125I1502J0D01*
G02X811719Y84557I-1502J0D01*
G01X811693Y84529D01*
X811665Y84460D01*
Y84108D01*
X811693Y84039D01*
X811719Y84011D01*
G02Y81957I-1096J-1027D01*
G01X811693Y81929D01*
X811665Y81860D01*
Y81508D01*
X811693Y81439D01*
X811719Y81411D01*
G02Y79357I-1096J-1027D01*
G01X811693Y79329D01*
X811665Y79260D01*
Y78908D01*
X811693Y78839D01*
X811719Y78811D01*
G02Y76757I-1096J-1027D01*
G01X811693Y76729D01*
X811665Y76660D01*
Y76308D01*
X811693Y76239D01*
X811719Y76211D01*
G02X812125Y75184I-1096J-1027D01*
G02X809121I-1502J0D01*
G02X809527Y76211I1502J0D01*
G01X809553Y76239D01*
X809581Y76308D01*
Y76660D01*
X809553Y76729D01*
X809527Y76757D01*
G02Y78811I1096J1027D01*
G01X809553Y78839D01*
X809581Y78908D01*
Y79260D01*
X809553Y79329D01*
X809527Y79357D01*
G02Y81411I1096J1027D01*
G01X809553Y81439D01*
X809581Y81508D01*
Y81860D01*
X809553Y81929D01*
X809527Y81957D01*
G02Y84011I1096J1027D01*
G01X809553Y84039D01*
X809581Y84108D01*
G37*
G36*
G01X819059Y101516D02*
X819095Y101900D01*
X819068Y101981D01*
X819039Y102013D01*
G02X818635Y103037I1098J1025D01*
G02X821639I1502J0D01*
G02X821172Y101948I-1503J0D01*
G01X821140Y101918D01*
X821108Y101839D01*
X821121Y101454D01*
X821159Y101377D01*
X821192Y101350D01*
G02X821846Y99961I-1148J-1389D01*
G02X818242I-1802J0D01*
G02X818982Y101417I1802J0D01*
G01X819017Y101442D01*
X819059Y101516D01*
G37*
G36*
G01X839024Y116195D02*
X839143Y116168D01*
G03X839286Y116189I44J195D01*
G02X840178Y116426I893J-1566D01*
G02X841070Y116189I-1J-1803D01*
G03X841213Y116168I99J174D01*
G01X841332Y116195D01*
G03X841451Y116274I-44J195D01*
G02X842674Y116903I1222J-873D01*
G02Y113899I0J-1502D01*
G02X842442Y113917I0J1502D01*
G01X842399Y113924D01*
X842315Y113900D01*
X842050Y113674D01*
G03X841980Y113522I130J-152D01*
G01Y112324D01*
G03X842050Y112172I200J0D01*
G01X842315Y111946D01*
X842399Y111922D01*
X842442Y111929D01*
G02X842674Y111947I232J-1484D01*
G02Y108943I0J-1502D01*
G02X841451Y109572I-1J1502D01*
G03X841332Y109651I-163J-116D01*
G01X841213Y109678D01*
G03X841070Y109657I-44J-195D01*
G02X840178Y109420I-893J1566D01*
G02X839286Y109657I1J1803D01*
G03X839143Y109678I-99J-174D01*
G01X839024Y109651D01*
G03X838905Y109572I44J-195D01*
G02X837682Y108943I-1222J873D01*
G02Y111947I0J1502D01*
G02X837914Y111929I0J-1502D01*
G01X837957Y111922D01*
X838041Y111946D01*
X838306Y112172D01*
G03X838376Y112324I-130J152D01*
G01Y113522D01*
G03X838306Y113674I-200J0D01*
G01X838041Y113900D01*
X837957Y113924D01*
X837914Y113917D01*
G02X837682Y113899I-232J1484D01*
G02Y116903I0J1502D01*
G02X838905Y116274I1J-1502D01*
G03X839024Y116195I163J116D01*
G37*
G36*
G01Y130368D02*
X839143Y130341D01*
G03X839286Y130362I44J195D01*
G02X840178Y130598I892J-1566D01*
G02X841070Y130362I0J-1802D01*
G03X841213Y130341I99J174D01*
G01X841332Y130368D01*
G03X841451Y130447I-44J195D01*
G02X842674Y131076I1222J-873D01*
G02Y128072I0J-1502D01*
G02X842442Y128090I0J1502D01*
G01X842399Y128097D01*
X842315Y128073D01*
X842050Y127847D01*
G03X841980Y127695I130J-152D01*
G01Y126497D01*
G03X842050Y126345I200J0D01*
G01X842315Y126119D01*
X842399Y126095D01*
X842442Y126102D01*
G02X842674Y126120I232J-1484D01*
G02Y123116I0J-1502D01*
G02X841451Y123745I-1J1502D01*
G03X841332Y123824I-163J-116D01*
G01X841213Y123851D01*
G03X841070Y123830I-44J-195D01*
G02X840178Y123594I-892J1566D01*
G02X839286Y123830I0J1802D01*
G03X839143Y123851I-99J-174D01*
G01X839024Y123824D01*
G03X838905Y123745I44J-195D01*
G02X837682Y123116I-1222J873D01*
G02Y126120I0J1502D01*
G02X837914Y126102I0J-1502D01*
G01X837957Y126095D01*
X838041Y126119D01*
X838306Y126345D01*
G03X838376Y126497I-130J152D01*
G01Y127695D01*
G03X838306Y127847I-200J0D01*
G01X838041Y128073D01*
X837957Y128097D01*
X837914Y128090D01*
G02X837682Y128072I-232J1484D01*
G02Y131076I0J1502D01*
G02X838905Y130447I1J-1502D01*
G03X839024Y130368I163J116D01*
G37*
G36*
G01X818393Y146186D02*
G02X815217Y140292I-3176J-2091D01*
G01X815216D01*
G02X812040Y146186I0J3803D01*
G01X812056Y146211D01*
X812073Y146266D01*
Y146296D01*
G03X811873Y146496I-200J0D01*
G01X811566D01*
G02Y153898I0J3701D01*
G01X818866D01*
G02Y146496I0J-3701D01*
G01X818560D01*
G03X818360Y146296I0J-200D01*
G01Y146236D01*
X818393Y146186D01*
G37*
G36*
G01X811687Y92655D02*
X811682Y92709D01*
G02X811675Y92849I1495J145D01*
G02X814679I1502J0D01*
G02X814676Y92747I-1502J-7D01*
G01X814672Y92696D01*
X814711Y92607D01*
X815049Y92340D01*
X815144Y92322D01*
X815192Y92337D01*
G02X815723Y92417I531J-1722D01*
G02X813921Y90615I0J-1802D01*
G02X813947Y90917I1802J-3D01*
G01X813955Y90967D01*
X813925Y91059D01*
X813616Y91359D01*
X813523Y91386D01*
X813473Y91377D01*
G02X813177Y91347I-299J1472D01*
G02X812704Y91424I2J1502D01*
G01X812652Y91441D01*
X812550Y91420D01*
X812209Y91124D01*
X812174Y91026D01*
X812184Y90972D01*
G02X812213Y90650I-1773J-322D01*
G02X810411Y92452I-1802J0D01*
G02X811125Y92305I1J-1802D01*
G01X811174Y92283D01*
X811278Y92295D01*
X811644Y92560D01*
X811687Y92655D01*
G37*
G36*
G01X836441Y100457D02*
G02X835781Y101701I842J1244D01*
G02X838785I1502J0D01*
G02X838125Y100457I-1502J0D01*
G03Y99795I224J-331D01*
G02X838785Y98551I-842J-1244D01*
G02X835781I-1502J0D01*
G02X836441Y99795I1502J0D01*
G03Y100457I-224J331D01*
G37*
G36*
G01X828853Y108025D02*
G02X828271Y107908I-581J1385D01*
G02Y110912I0J1502D01*
G02X829759Y109616I0J-1502D01*
G01X829765Y109569D01*
X829818Y109492D01*
X830177Y109290D01*
X830270Y109285D01*
X830314Y109304D01*
G02X831029Y109452I715J-1655D01*
G02X832832Y107649I0J-1803D01*
G01Y104249D01*
G02X831029Y102446I-1803J0D01*
G02X830326Y102589I1J1803D01*
G01X830281Y102608D01*
X830184Y102601D01*
X829823Y102375D01*
X829773Y102291D01*
X829771Y102242D01*
G02X828271Y100821I-1500J81D01*
G02Y103825I0J1502D01*
G02X828712Y103759I1J-1502D01*
G01X828759Y103744D01*
X828855Y103762D01*
X829190Y104023D01*
X829231Y104112D01*
X829229Y104161D01*
G02X829226Y104249I1799J105D01*
G01Y107649D01*
G02X829230Y107759I1803J-10D01*
G03X829145Y107935I-200J12D01*
G01X829045Y108005D01*
G03X828853Y108025I-114J-164D01*
G37*
G36*
G01X867364Y416678D02*
G02X866128Y416030I-1236J855D01*
G02Y419034I0J1502D01*
G02X867430Y418281I0J-1502D01*
G03X868106Y418253I347J199D01*
G02X869342Y418901I1236J-855D01*
G02Y415897I0J-1502D01*
G02X868040Y416650I0J1502D01*
G03X867364Y416678I-347J-199D01*
G37*
G36*
G01X907729Y1095154D02*
X907755Y1095528D01*
X907727Y1095606D01*
X907699Y1095636D01*
G02X907297Y1096659I1101J1023D01*
G02X910301I1502J0D01*
G02X909899Y1095636I-1503J0D01*
G01X909871Y1095606D01*
X909843Y1095528D01*
X909869Y1095154D01*
X909907Y1095081D01*
X909939Y1095054D01*
G02X910601Y1093659I-1139J-1395D01*
G02X906997I-1802J0D01*
G02X907659Y1095054I1801J0D01*
G01X907691Y1095081D01*
X907729Y1095154D01*
G37*
G36*
G01X887970Y1264141D02*
X888306D01*
X888373Y1264166D01*
X888401Y1264190D01*
G02X890375I987J-1131D01*
G01X890403Y1264166D01*
X890470Y1264141D01*
X890806D01*
X890873Y1264166D01*
X890901Y1264190D01*
G02X891888Y1264560I987J-1131D01*
G02X893390Y1263058I0J-1502D01*
G02X893020Y1262071I-1501J0D01*
G01X892996Y1262043D01*
X892971Y1261976D01*
Y1261640D01*
X892996Y1261573D01*
X893020Y1261545D01*
G02X893390Y1260558I-1131J-987D01*
G02X891888Y1259056I-1502J0D01*
G02X890901Y1259426I0J1501D01*
G01X890873Y1259450D01*
X890806Y1259475D01*
X890470D01*
X890403Y1259450D01*
X890375Y1259426D01*
G02X888401I-987J1131D01*
G01X888373Y1259450D01*
X888306Y1259475D01*
X887970D01*
X887903Y1259450D01*
X887875Y1259426D01*
G02X886888Y1259056I-987J1131D01*
G02X885386Y1260558I0J1502D01*
G02X885756Y1261545I1501J0D01*
G01X885780Y1261573D01*
X885805Y1261640D01*
Y1261976D01*
X885780Y1262043D01*
X885756Y1262071D01*
G02X885386Y1263058I1131J987D01*
G02X886888Y1264560I1502J0D01*
G02X887875Y1264190I0J-1501D01*
G01X887903Y1264166D01*
X887970Y1264141D01*
G37*
G36*
G01X951947D02*
X952283D01*
X952350Y1264166D01*
X952378Y1264190D01*
G02X954352I987J-1131D01*
G01X954380Y1264166D01*
X954447Y1264141D01*
X954783D01*
X954850Y1264166D01*
X954878Y1264190D01*
G02X955865Y1264560I987J-1131D01*
G02X957367Y1263058I0J-1502D01*
G02X956997Y1262071I-1501J0D01*
G01X956973Y1262043D01*
X956948Y1261976D01*
Y1261640D01*
X956973Y1261573D01*
X956997Y1261545D01*
G02X957367Y1260558I-1131J-987D01*
G02X955865Y1259056I-1502J0D01*
G02X954878Y1259426I0J1501D01*
G01X954850Y1259450D01*
X954783Y1259475D01*
X954447D01*
X954380Y1259450D01*
X954352Y1259426D01*
G02X952378I-987J1131D01*
G01X952350Y1259450D01*
X952283Y1259475D01*
X951947D01*
X951880Y1259450D01*
X951852Y1259426D01*
G02X950865Y1259056I-987J1131D01*
G02X949363Y1260558I0J1502D01*
G02X949733Y1261545I1501J0D01*
G01X949757Y1261573D01*
X949782Y1261640D01*
Y1261976D01*
X949757Y1262043D01*
X949733Y1262071D01*
G02X949363Y1263058I1131J987D01*
G02X950865Y1264560I1502J0D01*
G02X951852Y1264190I0J-1501D01*
G01X951880Y1264166D01*
X951947Y1264141D01*
G37*
G36*
G01X904457Y1226579D02*
X904819Y1226941D01*
X904846Y1226988D01*
X904853Y1227015D01*
G02X906309Y1228149I1456J-368D01*
G02X907811Y1226647I0J-1502D01*
G02X907284Y1225505I-1501J0D01*
G01X907236Y1225463D01*
X907205Y1225343D01*
X907356Y1224931D01*
G03X907544Y1224800I188J69D01*
G01X910633D01*
G02X912634Y1222804I0J-2001D01*
G01X912635Y1222754D01*
X912682Y1222665D01*
X913046Y1222426D01*
X913146Y1222418D01*
X913192Y1222437D01*
G02X913784Y1222559I593J-1380D01*
G02Y1219555I0J-1502D01*
G02X912300Y1220824I0J1502D01*
G01X912292Y1220874D01*
X912232Y1220954D01*
X911836Y1221135D01*
X911736Y1221128D01*
X911693Y1221101D01*
G02X910633Y1220798I-1059J1698D01*
G01X906451D01*
G03X906309Y1220739I0J-200D01*
G01X904722Y1219152D01*
G03X904664Y1219010I142J-141D01*
G01Y1217981D01*
G03X904797Y1217792I200J-1D01*
G01X905214Y1217647D01*
X905336Y1217682D01*
X905376Y1217732D01*
G02X906784Y1218409I1408J-1126D01*
G02Y1214805I0J-1802D01*
G02X905376Y1215482I0J1803D01*
G01X905336Y1215532D01*
X905214Y1215567D01*
X904797Y1215422D01*
G03X904664Y1215233I67J-188D01*
G01Y1211442D01*
G02X904077Y1210027I-2002J1D01*
G01X904008Y1209957D01*
G03Y1209674I141J-141D01*
G01X904033Y1209650D01*
X904096Y1209620D01*
X904130Y1209617D01*
G02X905761Y1207823I-171J-1794D01*
G02X903959Y1206021I-1802J0D01*
G02X902225Y1207333I0J1802D01*
G01X902210Y1207384D01*
X902135Y1207458D01*
X901749Y1207559D01*
G03X901557Y1207507I-51J-194D01*
G01X898104Y1204054D01*
G02X896689Y1203468I-1415J1415D01*
G01X877506D01*
G02X876091Y1204054I0J2001D01*
G01X873906Y1206239D01*
G02X873320Y1207654I1415J1415D01*
G02X875321Y1209656I2001J1D01*
G02X876736Y1209069I-1J-2002D01*
G01X878276Y1207529D01*
G03X878418Y1207470I142J141D01*
G01X895777D01*
G03X895919Y1207529I0J200D01*
G01X900602Y1212212D01*
G03X900660Y1212354I-142J141D01*
G01Y1212468D01*
G03X900547Y1212649I-200J1D01*
G01X900169Y1212829D01*
X900055Y1212816D01*
X900009Y1212779D01*
G02X898878Y1212380I-1131J1403D01*
G02Y1215984I0J1802D01*
G02X900009Y1215585I0J-1802D01*
G01X900055Y1215548D01*
X900169Y1215535D01*
X900547Y1215715D01*
G03X900660Y1215896I-87J180D01*
G01Y1217494D01*
G03X900566Y1217664I-200J1D01*
G01X900233Y1217871D01*
X900130Y1217876D01*
X900084Y1217853D01*
G02X899286Y1217667I-797J1616D01*
G02Y1221271I0J1802D01*
G02X900390Y1220893I0J-1801D01*
G01X900423Y1220867D01*
X900505Y1220847D01*
X900880Y1220913D01*
X900950Y1220959D01*
X900972Y1220995D01*
G02X901247Y1221337I1688J-1076D01*
G01X903566Y1223656D01*
G03X903609Y1223874I-142J141D01*
G01X903586Y1223931D01*
X903486Y1223998D01*
X898537D01*
G03X898401Y1223944I1J-200D01*
G02X897169Y1223457I-1232J1315D01*
G02Y1227061I0J1802D01*
G02X898401Y1226574I0J-1802D01*
G03X898537Y1226520I137J146D01*
G01X904316D01*
G03X904457Y1226579I-1J200D01*
G37*
G36*
G01X971083Y1233034D02*
X972261D01*
G02X972704Y1232919I5J-890D01*
G01X972727Y1232906D01*
X972775Y1232894D01*
X977022D01*
G02X977914Y1232524I-1J-1262D01*
G01X978545Y1231893D01*
G02X978914Y1231001I-892J-891D01*
G01Y1222683D01*
G03X979003Y1222517I200J0D01*
G02X979671Y1221268I-834J-1249D01*
G02X978169Y1219766I-1502J0D01*
G02X976709Y1220914I0J1502D01*
G03X976671Y1220993I-195J-45D01*
G02X976392Y1221784I982J791D01*
G01Y1230170D01*
G03X976192Y1230370I-200J0D01*
G01X973122D01*
G03X972922Y1230170I0J-200D01*
G01Y1229224D01*
G03X973122Y1229024I200J0D01*
G01X973158D01*
Y1227970D01*
G02X972975Y1227430I-890J1D01*
G03X972934Y1227309I159J-121D01*
G01Y1225348D01*
G03X972970Y1225232I200J-2D01*
G02X973134Y1224719I-726J-515D01*
G01Y1223866D01*
G02X972934Y1223666I-200J0D01*
G01X972898D01*
Y1222714D01*
G03X972966Y1222563I200J-1D01*
G02X973650Y1221057I-1318J-1507D01*
G02X971648Y1219056I-2002J1D01*
G01X968840D01*
G03X968640Y1218856I1J-200D01*
G01Y1217981D01*
G03X968774Y1217792I200J0D01*
G01X969191Y1217647D01*
X969313Y1217682D01*
X969353Y1217732D01*
G02X970761Y1218409I1408J-1126D01*
G02Y1214805I0J-1802D01*
G02X969353Y1215482I0J1803D01*
G01X969313Y1215532D01*
X969191Y1215567D01*
X968774Y1215422D01*
G03X968640Y1215233I66J-189D01*
G01Y1211442D01*
G02X968054Y1210027I-2001J0D01*
G01X967985Y1209957D01*
G03Y1209674I141J-141D01*
G01X968010Y1209650D01*
X968073Y1209620D01*
X968107Y1209617D01*
G02X969738Y1207823I-171J-1794D01*
G02X967936Y1206021I-1802J0D01*
G02X966202Y1207333I0J1802D01*
G01X966187Y1207384D01*
X966112Y1207458D01*
X965726Y1207559D01*
G03X965534Y1207507I-51J-194D01*
G01X962081Y1204054D01*
G02X960666Y1203468I-1415J1415D01*
G01X941483D01*
G02X940068Y1204054I0J2001D01*
G01X937883Y1206239D01*
G02X937296Y1207654I1415J1416D01*
G02X939298Y1209656I2002J0D01*
G02X940713Y1209069I-1J-2002D01*
G01X942253Y1207529D01*
G03X942395Y1207470I142J141D01*
G01X959754D01*
G03X959896Y1207529I0J200D01*
G01X964579Y1212212D01*
G03X964638Y1212354I-141J142D01*
G01Y1212468D01*
G03X964524Y1212649I-200J0D01*
G01X964146Y1212829D01*
X964032Y1212816D01*
X963986Y1212779D01*
G02X962855Y1212380I-1131J1403D01*
G02Y1215984I0J1802D01*
G02X963986Y1215585I0J-1802D01*
G01X964032Y1215548D01*
X964146Y1215535D01*
X964524Y1215715D01*
G03X964638Y1215896I-86J181D01*
G01Y1217494D01*
G03X964543Y1217664I-200J0D01*
G01X964210Y1217871D01*
X964107Y1217876D01*
X964061Y1217853D01*
G02X963263Y1217667I-797J1616D01*
G02Y1221271I0J1802D01*
G02X964367Y1220893I0J-1801D01*
G01X964400Y1220867D01*
X964482Y1220847D01*
X964857Y1220913D01*
X964927Y1220959D01*
X964949Y1220995D01*
G02X965224Y1221337I1688J-1076D01*
G01X966359Y1222472D01*
G02X966393Y1222506I1432J-1398D01*
G03X966444Y1222719I-137J145D01*
G01X966409Y1222814D01*
G03X966221Y1222946I-188J-68D01*
G01X962198D01*
G02X961306Y1223315I-1J1261D01*
G01X961194Y1223427D01*
X961126Y1223457D01*
X961087Y1223458D01*
G02X959344Y1225259I59J1801D01*
G02X961146Y1227061I1802J0D01*
G02X962910Y1225628I0J-1802D01*
G01X962925Y1225558D01*
X963034Y1225468D01*
X970210D01*
G03X970410Y1225668I0J200D01*
G01Y1227309D01*
G03X970369Y1227430I-200J0D01*
G02X970186Y1227970I707J541D01*
G01Y1228824D01*
G02X970386Y1229024I201J0D01*
G01X970422D01*
Y1230890D01*
G03X970222Y1231090I-199J1D01*
G01X970186D01*
Y1232144D01*
G02X971083Y1233034I890J0D01*
G37*
G36*
G01X913715Y355116D02*
G02X913914Y354917I0J-199D01*
G01Y354423D01*
G03X913944Y354318I200J0D01*
G02X914016Y354186I-1280J-784D01*
G01X914042Y354134D01*
X914138Y354074D01*
X914150D01*
Y353751D01*
X914152Y353737D01*
G02X914166Y353532I-1487J-205D01*
G02X914152Y353327I-1501J0D01*
G01X914150Y353313D01*
Y353020D01*
G02X913254Y352130I-890J0D01*
G01X913205D01*
X913172Y352119D01*
G02X912665Y352030I-509J1413D01*
G01X910040D01*
G02Y355034I0J1502D01*
G01X911332D01*
X911357Y355058D01*
G02X911498Y355116I141J-142D01*
G01X913715D01*
G37*
G36*
G01X926355Y373240D02*
X928377D01*
G03X928519Y373299I0J200D01*
G01X928881Y373662D01*
G02X929943Y374102I1062J-1062D01*
G02X931444Y372600I-1J-1502D01*
G02X931005Y371538I-1501J-1D01*
G01X930144Y370677D01*
G02X929776Y370408I-1060J1064D01*
G01X929741Y370389D01*
X929691Y370331D01*
X929578Y369992D01*
X929583Y369916D01*
X929600Y369880D01*
G02X929718Y369361I-1083J-519D01*
G01Y357740D01*
G02X929366Y356890I-1201J0D01*
G01X929365D01*
X928442Y355967D01*
Y355966D01*
G02X927592Y355614I-850J849D01*
G01X922655D01*
G03X922532Y355571I1J-200D01*
G02X921793Y355316I-740J947D01*
G01X920777D01*
G02X919930Y355667I2J1201D01*
G01X919834Y355763D01*
G03X919692Y355822I-142J-141D01*
G01X917689D01*
G03X917547Y355763I0J-200D01*
G01X917151Y355367D01*
Y355366D01*
G02X916301Y355014I-850J849D01*
G01X915579D01*
G02X914729Y355366I0J1201D01*
G01Y355367D01*
X913701Y356395D01*
X913700D01*
G02X913348Y357245I849J850D01*
G01Y368867D01*
G02X913700Y369717I1201J0D01*
G01X913701D01*
X914597Y370613D01*
Y370614D01*
G02X915447Y370966I850J-849D01*
G01X924570D01*
G03X924770Y371166I0J200D01*
G01Y372788D01*
G02X924970Y372988I200J0D01*
G01X925464D01*
G03X925569Y373018I0J200D01*
G02X925701Y373090I784J-1280D01*
G01X925753Y373116D01*
X925814Y373212D01*
Y373224D01*
X926136D01*
X926150Y373226D01*
G02X926355Y373240I205J-1487D01*
G37*
G36*
G01X971706Y1095154D02*
X971732Y1095528D01*
X971704Y1095606D01*
X971676Y1095636D01*
G02X971274Y1096659I1101J1023D01*
G02X974278I1502J0D01*
G02X973876Y1095636I-1503J0D01*
G01X973848Y1095606D01*
X973820Y1095528D01*
X973846Y1095154D01*
X973884Y1095081D01*
X973916Y1095054D01*
G02X974578Y1093659I-1139J-1395D01*
G02X970974I-1802J0D01*
G02X971636Y1095054I1801J0D01*
G01X971668Y1095081D01*
X971706Y1095154D01*
G37*
G36*
G01X979886Y1103413D02*
X979852Y1103437D01*
G02X979224Y1104659I875J1222D01*
G02X982228I1502J0D01*
G02X981885Y1103703I-1502J-1D01*
G01X981858Y1103671D01*
X981835Y1103592D01*
X981884Y1103219D01*
X981927Y1103148D01*
X981961Y1103124D01*
G02X982589Y1101902I-875J-1222D01*
G02X981761Y1100560I-1502J0D01*
G01X981713Y1100536D01*
X981655Y1100449D01*
X981623Y1099999D01*
X981668Y1099905D01*
X981712Y1099875D01*
G02X982354Y1098643I-861J-1232D01*
G02X979350I-1502J0D01*
G02X980178Y1099985I1502J0D01*
G01X980226Y1100009D01*
X980284Y1100096D01*
X980316Y1100546D01*
X980271Y1100640D01*
X980227Y1100670D01*
G02X979585Y1101902I861J1232D01*
G02X979928Y1102858I1502J1D01*
G01X979955Y1102890D01*
X979978Y1102969D01*
X979929Y1103342D01*
X979886Y1103413D01*
G37*
G36*
G01X1092205Y1581239D02*
X1092372Y1581611D01*
X1092370Y1581701D01*
X1092348Y1581742D01*
G02X1092180Y1582433I1334J690D01*
G02X1095184I1502J0D01*
G02X1094212Y1581027I-1503J0D01*
G01X1094168Y1581011D01*
X1094106Y1580946D01*
X1093982Y1580557D01*
X1093995Y1580468D01*
X1094021Y1580430D01*
G02X1094329Y1579422I-1494J-1008D01*
G02X1090725I-1802J0D01*
G02X1092090Y1581170I1802J0D01*
G01X1092136Y1581182D01*
X1092205Y1581239D01*
G37*
G36*
G01X1098493Y1588590D02*
X1098297Y1588910D01*
X1098231Y1588956D01*
X1098189Y1588965D01*
G02X1096996Y1590435I309J1470D01*
G02X1100000I1502J0D01*
G02X1099988Y1590247I-1502J1D01*
G01X1099983Y1590205D01*
X1100005Y1590127D01*
X1100243Y1589838D01*
X1100315Y1589801D01*
X1100357Y1589798D01*
G02X1102035Y1588000I-124J-1798D01*
G02X1098431I-1802J0D01*
G02X1098493Y1588469I1802J0D01*
G01X1098504Y1588510D01*
X1098493Y1588590D01*
G37*
G36*
G01X1092536Y1598221D02*
X1092174Y1598182D01*
X1092104Y1598143D01*
X1092079Y1598112D01*
G02X1090904Y1597545I-1175J934D01*
G02Y1600549I0J1502D01*
G02X1091671Y1600338I-1J-1502D01*
G01X1091706Y1600318D01*
X1091784Y1600307D01*
X1092137Y1600398D01*
X1092201Y1600446D01*
X1092221Y1600481D01*
G02X1093778Y1601376I1557J-907D01*
G02Y1597772I0J-1802D01*
G02X1092644Y1598174I0J1802D01*
G01X1092613Y1598199D01*
X1092536Y1598221D01*
G37*
G36*
G01X959581Y84108D02*
Y84460D01*
X959553Y84529D01*
X959527Y84557D01*
G02X959121Y85584I1096J1027D01*
G02X962125I1502J0D01*
G02X961719Y84557I-1502J0D01*
G01X961693Y84529D01*
X961665Y84460D01*
Y84108D01*
X961693Y84039D01*
X961719Y84011D01*
G02Y81957I-1096J-1027D01*
G01X961693Y81929D01*
X961665Y81860D01*
Y81508D01*
X961693Y81439D01*
X961719Y81411D01*
G02Y79357I-1096J-1027D01*
G01X961693Y79329D01*
X961665Y79260D01*
Y78908D01*
X961693Y78839D01*
X961719Y78811D01*
G02Y76757I-1096J-1027D01*
G01X961693Y76729D01*
X961665Y76660D01*
Y76308D01*
X961693Y76239D01*
X961719Y76211D01*
G02X962125Y75184I-1096J-1027D01*
G02X959121I-1502J0D01*
G02X959527Y76211I1502J0D01*
G01X959553Y76239D01*
X959581Y76308D01*
Y76660D01*
X959553Y76729D01*
X959527Y76757D01*
G02Y78811I1096J1027D01*
G01X959553Y78839D01*
X959581Y78908D01*
Y79260D01*
X959553Y79329D01*
X959527Y79357D01*
G02Y81411I1096J1027D01*
G01X959553Y81439D01*
X959581Y81508D01*
Y81860D01*
X959553Y81929D01*
X959527Y81957D01*
G02Y84011I1096J1027D01*
G01X959553Y84039D01*
X959581Y84108D01*
G37*
G36*
G01X969059Y101516D02*
X969095Y101900D01*
X969068Y101981D01*
X969039Y102013D01*
G02X968635Y103037I1098J1025D01*
G02X971639I1502J0D01*
G02X971172Y101948I-1503J0D01*
G01X971140Y101918D01*
X971108Y101839D01*
X971121Y101454D01*
X971159Y101377D01*
X971192Y101350D01*
G02X971846Y99961I-1148J-1389D01*
G02X968242I-1802J0D01*
G02X968982Y101417I1802J0D01*
G01X969017Y101442D01*
X969059Y101516D01*
G37*
G36*
G01X989024Y116195D02*
X989143Y116168D01*
G03X989286Y116189I44J195D01*
G02X990178Y116426I893J-1566D01*
G02X991070Y116189I-1J-1803D01*
G03X991213Y116168I99J174D01*
G01X991332Y116195D01*
G03X991451Y116274I-44J195D01*
G02X992674Y116903I1222J-873D01*
G02Y113899I0J-1502D01*
G02X992442Y113917I0J1502D01*
G01X992399Y113924D01*
X992315Y113900D01*
X992050Y113674D01*
G03X991980Y113522I130J-152D01*
G01Y112324D01*
G03X992050Y112172I200J0D01*
G01X992315Y111946D01*
X992399Y111922D01*
X992442Y111929D01*
G02X992674Y111947I232J-1484D01*
G02Y108943I0J-1502D01*
G02X991451Y109572I-1J1502D01*
G03X991332Y109651I-163J-116D01*
G01X991213Y109678D01*
G03X991070Y109657I-44J-195D01*
G02X990178Y109420I-893J1566D01*
G02X989286Y109657I1J1803D01*
G03X989143Y109678I-99J-174D01*
G01X989024Y109651D01*
G03X988905Y109572I44J-195D01*
G02X987682Y108943I-1222J873D01*
G02Y111947I0J1502D01*
G02X987914Y111929I0J-1502D01*
G01X987957Y111922D01*
X988041Y111946D01*
X988306Y112172D01*
G03X988376Y112324I-130J152D01*
G01Y113522D01*
G03X988306Y113674I-200J0D01*
G01X988041Y113900D01*
X987957Y113924D01*
X987914Y113917D01*
G02X987682Y113899I-232J1484D01*
G02Y116903I0J1502D01*
G02X988905Y116274I1J-1502D01*
G03X989024Y116195I163J116D01*
G37*
G36*
G01Y130368D02*
X989143Y130341D01*
G03X989286Y130362I44J195D01*
G02X990178Y130598I892J-1566D01*
G02X991070Y130362I0J-1802D01*
G03X991213Y130341I99J174D01*
G01X991332Y130368D01*
G03X991451Y130447I-44J195D01*
G02X992674Y131076I1222J-873D01*
G02Y128072I0J-1502D01*
G02X992442Y128090I0J1502D01*
G01X992399Y128097D01*
X992315Y128073D01*
X992050Y127847D01*
G03X991980Y127695I130J-152D01*
G01Y126497D01*
G03X992050Y126345I200J0D01*
G01X992315Y126119D01*
X992399Y126095D01*
X992442Y126102D01*
G02X992674Y126120I232J-1484D01*
G02Y123116I0J-1502D01*
G02X991451Y123745I-1J1502D01*
G03X991332Y123824I-163J-116D01*
G01X991213Y123851D01*
G03X991070Y123830I-44J-195D01*
G02X990178Y123594I-892J1566D01*
G02X989286Y123830I0J1802D01*
G03X989143Y123851I-99J-174D01*
G01X989024Y123824D01*
G03X988905Y123745I44J-195D01*
G02X987682Y123116I-1222J873D01*
G02Y126120I0J1502D01*
G02X987914Y126102I0J-1502D01*
G01X987957Y126095D01*
X988041Y126119D01*
X988306Y126345D01*
G03X988376Y126497I-130J152D01*
G01Y127695D01*
G03X988306Y127847I-200J0D01*
G01X988041Y128073D01*
X987957Y128097D01*
X987914Y128090D01*
G02X987682Y128072I-232J1484D01*
G02Y131076I0J1502D01*
G02X988905Y130447I1J-1502D01*
G03X989024Y130368I163J116D01*
G37*
G36*
G01X968393Y146186D02*
G02X965217Y140292I-3176J-2091D01*
G01X965216D01*
G02X962040Y146186I0J3803D01*
G01X962056Y146211D01*
X962073Y146266D01*
Y146296D01*
G03X961873Y146496I-200J0D01*
G01X961566D01*
G02Y153898I0J3701D01*
G01X968866D01*
G02Y146496I0J-3701D01*
G01X968560D01*
G03X968360Y146296I0J-200D01*
G01Y146236D01*
X968393Y146186D01*
G37*
G36*
G01X961687Y92655D02*
X961682Y92709D01*
G02X961675Y92849I1495J145D01*
G02X964679I1502J0D01*
G02X964676Y92747I-1502J-7D01*
G01X964672Y92696D01*
X964711Y92607D01*
X965049Y92340D01*
X965144Y92322D01*
X965192Y92337D01*
G02X965723Y92417I531J-1722D01*
G02X963921Y90615I0J-1802D01*
G02X963947Y90917I1802J-3D01*
G01X963955Y90967D01*
X963925Y91059D01*
X963616Y91359D01*
X963523Y91386D01*
X963473Y91377D01*
G02X963177Y91347I-299J1472D01*
G02X962704Y91424I2J1502D01*
G01X962652Y91441D01*
X962550Y91420D01*
X962209Y91124D01*
X962174Y91026D01*
X962184Y90972D01*
G02X962213Y90650I-1773J-322D01*
G02X960411Y92452I-1802J0D01*
G02X961125Y92305I1J-1802D01*
G01X961174Y92283D01*
X961278Y92295D01*
X961644Y92560D01*
X961687Y92655D01*
G37*
G36*
G01X986441Y100457D02*
G02X985781Y101701I842J1244D01*
G02X988785I1502J0D01*
G02X988125Y100457I-1502J0D01*
G03Y99795I224J-331D01*
G02X988785Y98551I-842J-1244D01*
G02X985781I-1502J0D01*
G02X986441Y99795I1502J0D01*
G03Y100457I-224J331D01*
G37*
G36*
G01X978853Y108025D02*
G02X978271Y107908I-581J1385D01*
G02Y110912I0J1502D01*
G02X979759Y109616I0J-1502D01*
G01X979765Y109569D01*
X979818Y109492D01*
X980177Y109290D01*
X980270Y109285D01*
X980314Y109304D01*
G02X981029Y109452I715J-1655D01*
G02X982832Y107649I0J-1803D01*
G01Y104249D01*
G02X981029Y102446I-1803J0D01*
G02X980326Y102589I1J1803D01*
G01X980281Y102608D01*
X980184Y102601D01*
X979823Y102375D01*
X979773Y102291D01*
X979771Y102242D01*
G02X978271Y100821I-1500J81D01*
G02Y103825I0J1502D01*
G02X978712Y103759I1J-1502D01*
G01X978759Y103744D01*
X978855Y103762D01*
X979190Y104023D01*
X979231Y104112D01*
X979229Y104161D01*
G02X979226Y104249I1799J105D01*
G01Y107649D01*
G02X979230Y107759I1803J-10D01*
G03X979145Y107935I-200J12D01*
G01X979045Y108005D01*
G03X978853Y108025I-114J-164D01*
G37*
G36*
G01X983929Y480324D02*
Y480369D01*
X983926Y480386D01*
G02X983897Y480705I1773J322D01*
G02X985699Y482507I1802J0D01*
G01X985700D01*
G02X987025Y481926I0J-1802D01*
G01X987026Y481925D01*
G03X987156Y481862I146J136D01*
G01X987426Y481840D01*
G03X987565Y481881I17J199D01*
G01X987567Y481883D01*
X987568Y481884D01*
G02X988499Y482207I931J-1180D01*
G02Y479203I0J-1502D01*
G02X987568Y479526I0J1503D01*
G01X987567Y479527D01*
X987565Y479529D01*
G03X987426Y479570I-122J-158D01*
G01X987156Y479548D01*
G03X987026Y479485I16J-199D01*
G01X987025Y479484D01*
G02X985856Y478910I-1325J1221D01*
G01X985817Y478907D01*
X985749Y478872D01*
X985541Y478638D01*
G03X985503Y478573I151J-132D01*
G01X985490Y478537D01*
X985491Y478498D01*
Y478497D01*
G02X985492Y478446I-1502J-55D01*
G02X985122Y477459I-1503J1D01*
G01X985121Y477458D01*
X985120Y477457D01*
G03X985072Y477327I152J-130D01*
G01Y477065D01*
G03X985120Y476935I200J0D01*
G01X985121Y476934D01*
X985122Y476933D01*
G02X985492Y475946I-1133J-988D01*
G02X982486I-1503J0D01*
G02X982856Y476933I1503J-1D01*
G01X982857Y476934D01*
X982858Y476935D01*
G03X982906Y477065I-152J130D01*
G01Y477327D01*
G03X982858Y477457I-200J0D01*
G01X982857Y477458D01*
X982856Y477459D01*
G02X982486Y478446I1133J988D01*
G02X983633Y479906I1503J0D01*
G01X983670Y479915D01*
X983732Y479960D01*
X983897Y480216D01*
G03X983929Y480324I-168J109D01*
G37*
G36*
G01X967494Y475825D02*
G02X968075Y477151I1804J0D01*
G03X968118Y477693I-271J294D01*
G02X967794Y478625I1178J932D01*
G02X970800I1503J0D01*
G02X970476Y477693I-1502J0D01*
G03X970519Y477151I314J-248D01*
G02X971100Y475825I-1223J-1326D01*
G02X969298Y474022I-1803J0D01*
G01X969296D01*
G02X969255I-20J1803D01*
G01X969197Y474023D01*
X969101Y473965D01*
X969074Y473912D01*
G03X969052Y473810I178J-92D01*
G01X969055Y473758D01*
X969083Y473713D01*
X969084Y473712D01*
G02X969319Y472905I-1268J-807D01*
G02X966313I-1503J0D01*
G02X967719Y474405I1503J0D01*
G01X967773Y474408D01*
X967860Y474466D01*
X967885Y474516D01*
G03X967866Y474728I-178J91D01*
G02X967494Y475825I1431J1097D01*
G37*
G36*
G01X973899Y473044D02*
G02Y473018I-1502J-13D01*
G03Y473009I200J-5D01*
G02X973900Y472954I-1502J-55D01*
G02X972397Y471451I-1503J0D01*
G02X970894Y472954I0J1503D01*
G02X970895Y473009I1503J0D01*
G03Y473018I-200J5D01*
G02Y473044I1502J13D01*
G01Y473046D01*
G02X972397Y474547I1502J-1D01*
G02X973899Y473046I0J-1502D01*
G01Y473044D01*
G37*
G36*
G01X966493Y486221D02*
X966831D01*
X966897Y486246D01*
X966925Y486270D01*
G02X968899I987J-1131D01*
G01X968927Y486246D01*
X968993Y486221D01*
X969331D01*
X969397Y486246D01*
X969425Y486270D01*
G02X970412Y486640I987J-1131D01*
G02X971914Y485138I0J-1502D01*
G02X971647Y484283I-1502J0D01*
G01X971623Y484249D01*
X971607Y484168D01*
X971677Y483843D01*
G03X971710Y483768I196J41D01*
G01X971734Y483735D01*
X971770Y483713D01*
X971771D01*
G02X972499Y482425I-775J-1288D01*
G02X969495I-1502J0D01*
G02X969762Y483280I1502J0D01*
G01X969786Y483314D01*
X969802Y483395D01*
X969732Y483720D01*
G03X969699Y483795I-196J-41D01*
G01X969675Y483828D01*
X969639Y483850D01*
X969638D01*
G02X969425Y484006I778J1285D01*
G01X969397Y484030D01*
X969331Y484055D01*
X968993D01*
X968927Y484030D01*
X968899Y484006D01*
G02X966925I-987J1131D01*
G01X966897Y484030D01*
X966831Y484055D01*
X966493D01*
X966427Y484030D01*
X966399Y484006D01*
G02X965412Y483636I-987J1131D01*
G02X964295Y484134I0J1502D01*
G01X964292Y484138D01*
X964283Y484147D01*
G03X964141Y484206I-142J-141D01*
G01X963843Y484205D01*
X963841D01*
X963799D01*
X963722Y484171D01*
X963691Y484137D01*
X963690Y484136D01*
X963686Y484132D01*
G02X962563Y483626I-1124J996D01*
G02X961061Y485128I0J1502D01*
G02X962563Y486630I1502J0D01*
G02X963680Y486132I0J-1502D01*
G01X963683Y486128D01*
X963692Y486119D01*
G03X963834Y486060I142J141D01*
G01X964132Y486061D01*
X964134D01*
X964176D01*
X964253Y486095D01*
X964284Y486129D01*
X964285Y486130D01*
X964289Y486134D01*
G02X965412Y486640I1124J-996D01*
G02X966399Y486270I0J-1501D01*
G01X966427Y486246D01*
X966493Y486221D01*
G37*
G36*
G01X981627Y483553D02*
Y483215D01*
X981652Y483149D01*
X981676Y483121D01*
G02X982046Y482134I-1131J-987D01*
G02X979042I-1502J0D01*
G02X979412Y483121I1501J0D01*
G01X979436Y483149D01*
X979461Y483215D01*
Y483553D01*
X979436Y483619D01*
X979412Y483647D01*
G02X979042Y484634I1131J987D01*
G02X982046I1502J0D01*
G02X981676Y483647I-1501J0D01*
G01X981652Y483619D01*
X981627Y483553D01*
G37*
G36*
G01X993289Y480005D02*
Y479667D01*
X993314Y479601D01*
X993338Y479573D01*
G02Y477599I-1131J-987D01*
G01X993314Y477571D01*
X993289Y477505D01*
Y477167D01*
X993314Y477101D01*
X993338Y477073D01*
G02X993708Y476086I-1131J-987D01*
G02X990704I-1502J0D01*
G02X991074Y477073I1501J0D01*
G01X991098Y477101D01*
X991123Y477167D01*
Y477505D01*
X991098Y477571D01*
X991074Y477599D01*
G02Y479573I1131J987D01*
G01X991098Y479601D01*
X991123Y479667D01*
Y480005D01*
X991098Y480071D01*
X991074Y480099D01*
G02X990704Y481086I1131J987D01*
G02X991027Y482017I1503J0D01*
G01X991028Y482018D01*
X991030Y482020D01*
G03X991071Y482159I-158J122D01*
G01X991049Y482429D01*
G03X990986Y482559I-199J-16D01*
G01X990985Y482560D01*
G02X990404Y483885I1221J1325D01*
G01Y483886D01*
G02X994008I1802J0D01*
G01Y483885D01*
G02X993427Y482560I-1802J0D01*
G01X993426Y482559D01*
G03X993363Y482429I136J-146D01*
G01X993341Y482159D01*
G03X993382Y482020I199J-17D01*
G01X993384Y482018D01*
X993385Y482017D01*
G02X993708Y481086I-1180J-931D01*
G02X993338Y480099I-1501J0D01*
G01X993314Y480071D01*
X993289Y480005D01*
G37*
G36*
G01X970595Y465001D02*
Y465004D01*
G02X974199I1802J0D01*
G02X972630Y463217I-1802J0D01*
G01X972628D01*
G03X972489Y463130I27J-198D01*
G01X972297Y462843D01*
X972282Y462759D01*
X972293Y462717D01*
G02X972342Y462339I-1453J-380D01*
G02X971972Y461352I-1501J0D01*
G01X971948Y461324D01*
X971923Y461258D01*
Y460920D01*
X971948Y460854D01*
X971972Y460826D01*
G02Y458852I-1131J-987D01*
G01X971948Y458824D01*
X971923Y458758D01*
Y458420D01*
X971948Y458354D01*
X971972Y458326D01*
G02X972342Y457339I-1131J-987D01*
G02X970840Y455837I-1502J0D01*
G02X969853Y456207I0J1501D01*
G01X969825Y456231D01*
X969759Y456256D01*
X969421D01*
X969355Y456231D01*
X969327Y456207D01*
G02X968340Y455837I-987J1131D01*
G02X966838Y457339I0J1502D01*
G02X967208Y458326I1501J0D01*
G01X967232Y458354D01*
X967257Y458420D01*
Y458758D01*
X967232Y458824D01*
X967208Y458852D01*
G02Y460826I1131J987D01*
G01X967232Y460854D01*
X967257Y460920D01*
Y461258D01*
X967232Y461324D01*
X967208Y461352D01*
G02X966838Y462339I1131J987D01*
G02X968340Y463841I1502J0D01*
G02X969327Y463471I0J-1501D01*
G01X969355Y463447D01*
X969421Y463422D01*
X969759D01*
X969825Y463447D01*
X969853Y463471D01*
G02X970455Y463790I986J-1133D01*
G01X970497Y463801D01*
X970533Y463831D01*
G03X970585Y463895I-126J156D01*
G01X970719Y464163D01*
G03X970727Y464325I-178J90D01*
G01X970726Y464328D01*
Y464329D01*
G02X970595Y465001I1671J675D01*
G37*
G36*
G01X1061943Y84108D02*
Y84460D01*
X1061915Y84529D01*
X1061889Y84557D01*
G02X1061483Y85584I1096J1027D01*
G02X1064487I1502J0D01*
G02X1064081Y84557I-1502J0D01*
G01X1064055Y84529D01*
X1064027Y84460D01*
Y84108D01*
X1064055Y84039D01*
X1064081Y84011D01*
G02Y81957I-1096J-1027D01*
G01X1064055Y81929D01*
X1064027Y81860D01*
Y81508D01*
X1064055Y81439D01*
X1064081Y81411D01*
G02Y79357I-1096J-1027D01*
G01X1064055Y79329D01*
X1064027Y79260D01*
Y78908D01*
X1064055Y78839D01*
X1064081Y78811D01*
G02Y76757I-1096J-1027D01*
G01X1064055Y76729D01*
X1064027Y76660D01*
Y76308D01*
X1064055Y76239D01*
X1064081Y76211D01*
G02X1064487Y75184I-1096J-1027D01*
G02X1061483I-1502J0D01*
G02X1061889Y76211I1502J0D01*
G01X1061915Y76239D01*
X1061943Y76308D01*
Y76660D01*
X1061915Y76729D01*
X1061889Y76757D01*
G02Y78811I1096J1027D01*
G01X1061915Y78839D01*
X1061943Y78908D01*
Y79260D01*
X1061915Y79329D01*
X1061889Y79357D01*
G02Y81411I1096J1027D01*
G01X1061915Y81439D01*
X1061943Y81508D01*
Y81860D01*
X1061915Y81929D01*
X1061889Y81957D01*
G02Y84011I1096J1027D01*
G01X1061915Y84039D01*
X1061943Y84108D01*
G37*
G36*
G01X1071421Y101516D02*
X1071457Y101900D01*
X1071430Y101981D01*
X1071401Y102013D01*
G02X1070997Y103037I1098J1025D01*
G02X1074001I1502J0D01*
G02X1073534Y101948I-1503J0D01*
G01X1073502Y101918D01*
X1073470Y101839D01*
X1073483Y101454D01*
X1073521Y101377D01*
X1073554Y101350D01*
G02X1074208Y99961I-1148J-1389D01*
G02X1070604I-1802J0D01*
G02X1071344Y101417I1802J0D01*
G01X1071379Y101442D01*
X1071421Y101516D01*
G37*
G36*
G01X1091386Y116195D02*
X1091505Y116168D01*
G03X1091648Y116189I44J195D01*
G02X1092540Y116426I893J-1566D01*
G02X1093432Y116189I-1J-1803D01*
G03X1093575Y116168I99J174D01*
G01X1093694Y116195D01*
G03X1093813Y116274I-44J195D01*
G02X1095036Y116903I1222J-873D01*
G02Y113899I0J-1502D01*
G02X1094804Y113917I0J1502D01*
G01X1094761Y113924D01*
X1094677Y113900D01*
X1094412Y113674D01*
G03X1094342Y113522I130J-152D01*
G01Y112324D01*
G03X1094412Y112172I200J0D01*
G01X1094677Y111946D01*
X1094761Y111922D01*
X1094804Y111929D01*
G02X1095036Y111947I232J-1484D01*
G02Y108943I0J-1502D01*
G02X1093813Y109572I-1J1502D01*
G03X1093694Y109651I-163J-116D01*
G01X1093575Y109678D01*
G03X1093432Y109657I-44J-195D01*
G02X1092540Y109420I-893J1566D01*
G02X1091648Y109657I1J1803D01*
G03X1091505Y109678I-99J-174D01*
G01X1091386Y109651D01*
G03X1091267Y109572I44J-195D01*
G02X1090044Y108943I-1222J873D01*
G02Y111947I0J1502D01*
G02X1090276Y111929I0J-1502D01*
G01X1090319Y111922D01*
X1090403Y111946D01*
X1090668Y112172D01*
G03X1090738Y112324I-130J152D01*
G01Y113522D01*
G03X1090668Y113674I-200J0D01*
G01X1090403Y113900D01*
X1090319Y113924D01*
X1090276Y113917D01*
G02X1090044Y113899I-232J1484D01*
G02Y116903I0J1502D01*
G02X1091267Y116274I1J-1502D01*
G03X1091386Y116195I163J116D01*
G37*
G36*
G01Y130368D02*
X1091505Y130341D01*
G03X1091648Y130362I44J195D01*
G02X1092540Y130598I892J-1566D01*
G02X1093432Y130362I0J-1802D01*
G03X1093575Y130341I99J174D01*
G01X1093694Y130368D01*
G03X1093813Y130447I-44J195D01*
G02X1095036Y131076I1222J-873D01*
G02Y128072I0J-1502D01*
G02X1094804Y128090I0J1502D01*
G01X1094761Y128097D01*
X1094677Y128073D01*
X1094412Y127847D01*
G03X1094342Y127695I130J-152D01*
G01Y126497D01*
G03X1094412Y126345I200J0D01*
G01X1094677Y126119D01*
X1094761Y126095D01*
X1094804Y126102D01*
G02X1095036Y126120I232J-1484D01*
G02Y123116I0J-1502D01*
G02X1093813Y123745I-1J1502D01*
G03X1093694Y123824I-163J-116D01*
G01X1093575Y123851D01*
G03X1093432Y123830I-44J-195D01*
G02X1092540Y123594I-892J1566D01*
G02X1091648Y123830I0J1802D01*
G03X1091505Y123851I-99J-174D01*
G01X1091386Y123824D01*
G03X1091267Y123745I44J-195D01*
G02X1090044Y123116I-1222J873D01*
G02Y126120I0J1502D01*
G02X1090276Y126102I0J-1502D01*
G01X1090319Y126095D01*
X1090403Y126119D01*
X1090668Y126345D01*
G03X1090738Y126497I-130J152D01*
G01Y127695D01*
G03X1090668Y127847I-200J0D01*
G01X1090403Y128073D01*
X1090319Y128097D01*
X1090276Y128090D01*
G02X1090044Y128072I-232J1484D01*
G02Y131076I0J1502D01*
G02X1091267Y130447I1J-1502D01*
G03X1091386Y130368I163J116D01*
G37*
G36*
G01X1070755Y146186D02*
G02X1067579Y140292I-3176J-2091D01*
G01X1067578D01*
G02X1064402Y146186I0J3803D01*
G01X1064418Y146211D01*
X1064435Y146266D01*
Y146296D01*
G03X1064235Y146496I-200J0D01*
G01X1063928D01*
G02Y153898I0J3701D01*
G01X1071228D01*
G02Y146496I0J-3701D01*
G01X1070922D01*
G03X1070722Y146296I0J-200D01*
G01Y146236D01*
X1070755Y146186D01*
G37*
G36*
G01X1064049Y92655D02*
X1064044Y92709D01*
G02X1064037Y92849I1495J145D01*
G02X1067041I1502J0D01*
G02X1067038Y92747I-1502J-7D01*
G01X1067034Y92696D01*
X1067073Y92607D01*
X1067411Y92340D01*
X1067506Y92322D01*
X1067554Y92337D01*
G02X1068085Y92417I531J-1722D01*
G02X1066283Y90615I0J-1802D01*
G02X1066309Y90917I1802J-3D01*
G01X1066317Y90967D01*
X1066287Y91059D01*
X1065978Y91359D01*
X1065885Y91386D01*
X1065835Y91377D01*
G02X1065539Y91347I-299J1472D01*
G02X1065066Y91424I2J1502D01*
G01X1065014Y91441D01*
X1064912Y91420D01*
X1064571Y91124D01*
X1064536Y91026D01*
X1064546Y90972D01*
G02X1064575Y90650I-1773J-322D01*
G02X1062773Y92452I-1802J0D01*
G02X1063487Y92305I1J-1802D01*
G01X1063536Y92283D01*
X1063640Y92295D01*
X1064006Y92560D01*
X1064049Y92655D01*
G37*
G36*
G01X1088803Y100457D02*
G02X1088143Y101701I842J1244D01*
G02X1091147I1502J0D01*
G02X1090487Y100457I-1502J0D01*
G03Y99795I224J-331D01*
G02X1091147Y98551I-842J-1244D01*
G02X1088143I-1502J0D01*
G02X1088803Y99795I1502J0D01*
G03Y100457I-224J331D01*
G37*
G36*
G01X1081215Y108025D02*
G02X1080633Y107908I-581J1385D01*
G02Y110912I0J1502D01*
G02X1082121Y109616I0J-1502D01*
G01X1082127Y109569D01*
X1082180Y109492D01*
X1082539Y109290D01*
X1082632Y109285D01*
X1082676Y109304D01*
G02X1083391Y109452I715J-1655D01*
G02X1085194Y107649I0J-1803D01*
G01Y104249D01*
G02X1083391Y102446I-1803J0D01*
G02X1082688Y102589I1J1803D01*
G01X1082643Y102608D01*
X1082546Y102601D01*
X1082185Y102375D01*
X1082135Y102291D01*
X1082133Y102242D01*
G02X1080633Y100821I-1500J81D01*
G02Y103825I0J1502D01*
G02X1081074Y103759I1J-1502D01*
G01X1081121Y103744D01*
X1081217Y103762D01*
X1081552Y104023D01*
X1081593Y104112D01*
X1081591Y104161D01*
G02X1081588Y104249I1799J105D01*
G01Y107649D01*
G02X1081592Y107759I1803J-10D01*
G03X1081507Y107935I-200J12D01*
G01X1081407Y108005D01*
G03X1081215Y108025I-114J-164D01*
G37*
G36*
G01X1074597Y262678D02*
G02Y265682I0J1502D01*
G02X1075584Y265312I0J-1501D01*
G01X1075585D01*
Y265311D01*
G03X1075715Y265263I130J152D01*
G01X1075979D01*
G03X1076109Y265311I0J200D01*
G01X1076110Y265312D01*
G02X1077097Y265682I987J-1131D01*
G02Y262678I0J-1502D01*
G02X1076110Y263048I0J1501D01*
G01X1076109D01*
Y263049D01*
G03X1075979Y263097I-130J-152D01*
G01X1075715D01*
G03X1075585Y263049I0J-200D01*
G01X1075584Y263048D01*
G02X1074597Y262678I-987J1131D01*
G37*
G36*
G01X1176959D02*
G02Y265682I0J1502D01*
G02X1177946Y265312I0J-1501D01*
G01X1177947D01*
Y265311D01*
G03X1178077Y265263I130J152D01*
G01X1178341D01*
G03X1178471Y265311I0J200D01*
G01X1178472Y265312D01*
G02X1179459Y265682I987J-1131D01*
G02Y262678I0J-1502D01*
G02X1178472Y263048I0J1501D01*
G01X1178471D01*
Y263049D01*
G03X1178341Y263097I-130J-152D01*
G01X1178077D01*
G03X1177947Y263049I0J-200D01*
G01X1177946Y263048D01*
G02X1176959Y262678I-987J1131D01*
G37*
G36*
G01X1279321D02*
G02Y265682I0J1502D01*
G02X1280308Y265312I0J-1501D01*
G01X1280309D01*
Y265311D01*
G03X1280439Y265263I130J152D01*
G01X1280703D01*
G03X1280833Y265311I0J200D01*
G01X1280834Y265312D01*
G02X1281821Y265682I987J-1131D01*
G02Y262678I0J-1502D01*
G02X1280834Y263048I0J1501D01*
G01X1280833D01*
Y263049D01*
G03X1280703Y263097I-130J-152D01*
G01X1280439D01*
G03X1280309Y263049I0J-200D01*
G01X1280308Y263048D01*
G02X1279321Y262678I-987J1131D01*
G37*
G36*
G01X1429322D02*
G02Y265682I0J1502D01*
G02X1430309Y265312I0J-1501D01*
G01X1430310D01*
Y265311D01*
G03X1430440Y265263I130J152D01*
G01X1430704D01*
G03X1430834Y265311I0J200D01*
G01X1430835Y265312D01*
G02X1431822Y265682I987J-1131D01*
G02Y262678I0J-1502D01*
G02X1430835Y263048I0J1501D01*
G01X1430834D01*
Y263049D01*
G03X1430704Y263097I-130J-152D01*
G01X1430440D01*
G03X1430310Y263049I0J-200D01*
G01X1430309Y263048D01*
G02X1429322Y262678I-987J1131D01*
G37*
G36*
G01X1531684D02*
G02Y265682I0J1502D01*
G02X1532671Y265312I0J-1501D01*
G01X1532672D01*
Y265311D01*
G03X1532802Y265263I130J152D01*
G01X1533066D01*
G03X1533196Y265311I0J200D01*
G01X1533197Y265312D01*
G02X1534184Y265682I987J-1131D01*
G02Y262678I0J-1502D01*
G02X1533197Y263048I0J1501D01*
G01X1533196D01*
Y263049D01*
G03X1533066Y263097I-130J-152D01*
G01X1532802D01*
G03X1532672Y263049I0J-200D01*
G01X1532671Y263048D01*
G02X1531684Y262678I-987J1131D01*
G37*
G36*
G01X1634046D02*
G02Y265682I0J1502D01*
G02X1635033Y265312I0J-1501D01*
G01X1635034D01*
Y265311D01*
G03X1635164Y265263I130J152D01*
G01X1635428D01*
G03X1635558Y265311I0J200D01*
G01X1635559Y265312D01*
G02X1636546Y265682I987J-1131D01*
G02Y262678I0J-1502D01*
G02X1635559Y263048I0J1501D01*
G01X1635558D01*
Y263049D01*
G03X1635428Y263097I-130J-152D01*
G01X1635164D01*
G03X1635034Y263049I0J-200D01*
G01X1635033Y263048D01*
G02X1634046Y262678I-987J1131D01*
G37*
G36*
G01X1736408D02*
G02Y265682I0J1502D01*
G02X1737395Y265312I0J-1501D01*
G01X1737396D01*
Y265311D01*
G03X1737526Y265263I130J152D01*
G01X1737790D01*
G03X1737920Y265311I0J200D01*
G01X1737921Y265312D01*
G02X1738908Y265682I987J-1131D01*
G02Y262678I0J-1502D01*
G02X1737921Y263048I0J1501D01*
G01X1737920D01*
Y263049D01*
G03X1737790Y263097I-130J-152D01*
G01X1737526D01*
G03X1737396Y263049I0J-200D01*
G01X1737395Y263048D01*
G02X1736408Y262678I-987J1131D01*
G37*
G36*
G01X1114282Y264395D02*
G02Y267399I0J1502D01*
G02X1115269Y267029I0J-1501D01*
G01X1115270D01*
Y267028D01*
G03X1115400Y266980I130J152D01*
G01X1115664D01*
G03X1115794Y267028I0J200D01*
G01X1115795Y267029D01*
G02X1116782Y267399I987J-1131D01*
G02Y264395I0J-1502D01*
G02X1115795Y264765I0J1501D01*
G01X1115794D01*
Y264766D01*
G03X1115664Y264814I-130J-152D01*
G01X1115400D01*
G03X1115270Y264766I0J-200D01*
G01X1115269Y264765D01*
G02X1114282Y264395I-987J1131D01*
G37*
G36*
G01X1216644D02*
G02Y267399I0J1502D01*
G02X1217631Y267029I0J-1501D01*
G01X1217632D01*
Y267028D01*
G03X1217762Y266980I130J152D01*
G01X1218026D01*
G03X1218156Y267028I0J200D01*
G01X1218157Y267029D01*
G02X1219144Y267399I987J-1131D01*
G02Y264395I0J-1502D01*
G02X1218157Y264765I0J1501D01*
G01X1218156D01*
Y264766D01*
G03X1218026Y264814I-130J-152D01*
G01X1217762D01*
G03X1217632Y264766I0J-200D01*
G01X1217631Y264765D01*
G02X1216644Y264395I-987J1131D01*
G37*
G36*
G01X1319006D02*
G02Y267399I0J1502D01*
G02X1319993Y267029I0J-1501D01*
G01X1319994D01*
Y267028D01*
G03X1320124Y266980I130J152D01*
G01X1320388D01*
G03X1320518Y267028I0J200D01*
G01X1320519Y267029D01*
G02X1321506Y267399I987J-1131D01*
G02Y264395I0J-1502D01*
G02X1320519Y264765I0J1501D01*
G01X1320518D01*
Y264766D01*
G03X1320388Y264814I-130J-152D01*
G01X1320124D01*
G03X1319994Y264766I0J-200D01*
G01X1319993Y264765D01*
G02X1319006Y264395I-987J1131D01*
G37*
G36*
G01X1469007D02*
G02Y267399I0J1502D01*
G02X1469994Y267029I0J-1501D01*
G01X1469995D01*
Y267028D01*
G03X1470125Y266980I130J152D01*
G01X1470389D01*
G03X1470519Y267028I0J200D01*
G01X1470520Y267029D01*
G02X1471507Y267399I987J-1131D01*
G02Y264395I0J-1502D01*
G02X1470520Y264765I0J1501D01*
G01X1470519D01*
Y264766D01*
G03X1470389Y264814I-130J-152D01*
G01X1470125D01*
G03X1469995Y264766I0J-200D01*
G01X1469994Y264765D01*
G02X1469007Y264395I-987J1131D01*
G37*
G36*
G01X1571369D02*
G02Y267399I0J1502D01*
G02X1572356Y267029I0J-1501D01*
G01X1572357D01*
Y267028D01*
G03X1572487Y266980I130J152D01*
G01X1572751D01*
G03X1572881Y267028I0J200D01*
G01X1572882Y267029D01*
G02X1573869Y267399I987J-1131D01*
G02Y264395I0J-1502D01*
G02X1572882Y264765I0J1501D01*
G01X1572881D01*
Y264766D01*
G03X1572751Y264814I-130J-152D01*
G01X1572487D01*
G03X1572357Y264766I0J-200D01*
G01X1572356Y264765D01*
G02X1571369Y264395I-987J1131D01*
G37*
G36*
G01X1673731D02*
G02Y267399I0J1502D01*
G02X1674718Y267029I0J-1501D01*
G01X1674719D01*
Y267028D01*
G03X1674849Y266980I130J152D01*
G01X1675113D01*
G03X1675243Y267028I0J200D01*
G01X1675244Y267029D01*
G02X1676231Y267399I987J-1131D01*
G02Y264395I0J-1502D01*
G02X1675244Y264765I0J1501D01*
G01X1675243D01*
Y264766D01*
G03X1675113Y264814I-130J-152D01*
G01X1674849D01*
G03X1674719Y264766I0J-200D01*
G01X1674718Y264765D01*
G02X1673731Y264395I-987J1131D01*
G37*
G36*
G01X1776093D02*
G02Y267399I0J1502D01*
G02X1777080Y267029I0J-1501D01*
G01X1777081D01*
Y267028D01*
G03X1777211Y266980I130J152D01*
G01X1777475D01*
G03X1777605Y267028I0J200D01*
G01X1777606Y267029D01*
G02X1778593Y267399I987J-1131D01*
G02Y264395I0J-1502D01*
G02X1777606Y264765I0J1501D01*
G01X1777605D01*
Y264766D01*
G03X1777475Y264814I-130J-152D01*
G01X1777211D01*
G03X1777081Y264766I0J-200D01*
G01X1777080Y264765D01*
G02X1776093Y264395I-987J1131D01*
G37*
G36*
G01X1107822Y272197D02*
G02X1108928Y271712I0J-1504D01*
G03X1109075Y271647I148J135D01*
G01X1109369D01*
G03X1109516Y271712I-1J200D01*
G02X1110622Y272197I1106J-1019D01*
G02X1112124Y270695I0J-1502D01*
G02X1111754Y269708I-1501J0D01*
G01Y269707D01*
X1111753D01*
G03X1111705Y269577I152J-130D01*
G01Y269313D01*
G03X1111753Y269183I200J0D01*
G01X1111754Y269182D01*
G02X1112124Y268195I-1131J-987D01*
G02X1110622Y266693I-1502J0D01*
G02X1109516Y267178I0J1504D01*
G03X1109369Y267243I-148J-135D01*
G01X1109075D01*
G03X1108928Y267178I1J-200D01*
G02X1107822Y266693I-1106J1019D01*
G02X1106835Y267063I0J1501D01*
G01X1106834D01*
Y267064D01*
G03X1106704Y267112I-130J-152D01*
G01X1106440D01*
G03X1106310Y267064I0J-200D01*
G01X1106309Y267063D01*
G02X1105322Y266693I-987J1131D01*
G02X1103820Y268195I0J1502D01*
G02X1104190Y269182I1501J0D01*
G01Y269183D01*
X1104191D01*
G03X1104239Y269313I-152J130D01*
G01Y269577D01*
G03X1104191Y269707I-200J0D01*
G01X1104190Y269708D01*
G02X1103820Y270695I1131J987D01*
G02X1105322Y272197I1502J0D01*
G02X1106309Y271827I0J-1501D01*
G01X1106310D01*
Y271826D01*
G03X1106440Y271778I130J152D01*
G01X1106704D01*
G03X1106834Y271826I0J200D01*
G01X1106835Y271827D01*
G02X1107822Y272197I987J-1131D01*
G37*
G36*
G01X1210184D02*
G02X1211290Y271712I0J-1504D01*
G03X1211437Y271647I148J135D01*
G01X1211731D01*
G03X1211878Y271712I-1J200D01*
G02X1212984Y272197I1106J-1019D01*
G02X1214486Y270695I0J-1502D01*
G02X1214116Y269708I-1501J0D01*
G01Y269707D01*
X1214115D01*
G03X1214067Y269577I152J-130D01*
G01Y269313D01*
G03X1214115Y269183I200J0D01*
G01X1214116Y269182D01*
G02X1214486Y268195I-1131J-987D01*
G02X1212984Y266693I-1502J0D01*
G02X1211878Y267178I0J1504D01*
G03X1211731Y267243I-148J-135D01*
G01X1211437D01*
G03X1211290Y267178I1J-200D01*
G02X1210184Y266693I-1106J1019D01*
G02X1209197Y267063I0J1501D01*
G01X1209196D01*
Y267064D01*
G03X1209066Y267112I-130J-152D01*
G01X1208802D01*
G03X1208672Y267064I0J-200D01*
G01X1208671Y267063D01*
G02X1207684Y266693I-987J1131D01*
G02X1206182Y268195I0J1502D01*
G02X1206552Y269182I1501J0D01*
G01Y269183D01*
X1206553D01*
G03X1206601Y269313I-152J130D01*
G01Y269577D01*
G03X1206553Y269707I-200J0D01*
G01X1206552Y269708D01*
G02X1206182Y270695I1131J987D01*
G02X1207684Y272197I1502J0D01*
G02X1208671Y271827I0J-1501D01*
G01X1208672D01*
Y271826D01*
G03X1208802Y271778I130J152D01*
G01X1209066D01*
G03X1209196Y271826I0J200D01*
G01X1209197Y271827D01*
G02X1210184Y272197I987J-1131D01*
G37*
G36*
G01X1312546D02*
G02X1313652Y271712I0J-1504D01*
G03X1313799Y271647I148J135D01*
G01X1314093D01*
G03X1314240Y271712I-1J200D01*
G02X1315346Y272197I1106J-1019D01*
G02X1316848Y270695I0J-1502D01*
G02X1316478Y269708I-1501J0D01*
G01Y269707D01*
X1316477D01*
G03X1316429Y269577I152J-130D01*
G01Y269313D01*
G03X1316477Y269183I200J0D01*
G01X1316478Y269182D01*
G02X1316848Y268195I-1131J-987D01*
G02X1315346Y266693I-1502J0D01*
G02X1314240Y267178I0J1504D01*
G03X1314093Y267243I-148J-135D01*
G01X1313799D01*
G03X1313652Y267178I1J-200D01*
G02X1312546Y266693I-1106J1019D01*
G02X1311559Y267063I0J1501D01*
G01X1311558D01*
Y267064D01*
G03X1311428Y267112I-130J-152D01*
G01X1311164D01*
G03X1311034Y267064I0J-200D01*
G01X1311033Y267063D01*
G02X1310046Y266693I-987J1131D01*
G02X1308544Y268195I0J1502D01*
G02X1308914Y269182I1501J0D01*
G01Y269183D01*
X1308915D01*
G03X1308963Y269313I-152J130D01*
G01Y269577D01*
G03X1308915Y269707I-200J0D01*
G01X1308914Y269708D01*
G02X1308544Y270695I1131J987D01*
G02X1310046Y272197I1502J0D01*
G02X1311033Y271827I0J-1501D01*
G01X1311034D01*
Y271826D01*
G03X1311164Y271778I130J152D01*
G01X1311428D01*
G03X1311558Y271826I0J200D01*
G01X1311559Y271827D01*
G02X1312546Y272197I987J-1131D01*
G37*
G36*
G01X1462547D02*
G02X1463653Y271712I0J-1504D01*
G03X1463800Y271647I148J135D01*
G01X1464094D01*
G03X1464241Y271712I-1J200D01*
G02X1465347Y272197I1106J-1019D01*
G02X1466849Y270695I0J-1502D01*
G02X1466479Y269708I-1501J0D01*
G01Y269707D01*
X1466478D01*
G03X1466430Y269577I152J-130D01*
G01Y269313D01*
G03X1466478Y269183I200J0D01*
G01X1466479Y269182D01*
G02X1466849Y268195I-1131J-987D01*
G02X1465347Y266693I-1502J0D01*
G02X1464241Y267178I0J1504D01*
G03X1464094Y267243I-148J-135D01*
G01X1463800D01*
G03X1463653Y267178I1J-200D01*
G02X1462547Y266693I-1106J1019D01*
G02X1461560Y267063I0J1501D01*
G01X1461559D01*
Y267064D01*
G03X1461429Y267112I-130J-152D01*
G01X1461165D01*
G03X1461035Y267064I0J-200D01*
G01X1461034Y267063D01*
G02X1460047Y266693I-987J1131D01*
G02X1458545Y268195I0J1502D01*
G02X1458915Y269182I1501J0D01*
G01Y269183D01*
X1458916D01*
G03X1458964Y269313I-152J130D01*
G01Y269577D01*
G03X1458916Y269707I-200J0D01*
G01X1458915Y269708D01*
G02X1458545Y270695I1131J987D01*
G02X1460047Y272197I1502J0D01*
G02X1461034Y271827I0J-1501D01*
G01X1461035D01*
Y271826D01*
G03X1461165Y271778I130J152D01*
G01X1461429D01*
G03X1461559Y271826I0J200D01*
G01X1461560Y271827D01*
G02X1462547Y272197I987J-1131D01*
G37*
G36*
G01X1564909D02*
G02X1566015Y271712I0J-1504D01*
G03X1566162Y271647I148J135D01*
G01X1566456D01*
G03X1566603Y271712I-1J200D01*
G02X1567709Y272197I1106J-1019D01*
G02X1569211Y270695I0J-1502D01*
G02X1568841Y269708I-1501J0D01*
G01Y269707D01*
X1568840D01*
G03X1568792Y269577I152J-130D01*
G01Y269313D01*
G03X1568840Y269183I200J0D01*
G01X1568841Y269182D01*
G02X1569211Y268195I-1131J-987D01*
G02X1567709Y266693I-1502J0D01*
G02X1566603Y267178I0J1504D01*
G03X1566456Y267243I-148J-135D01*
G01X1566162D01*
G03X1566015Y267178I1J-200D01*
G02X1564909Y266693I-1106J1019D01*
G02X1563922Y267063I0J1501D01*
G01X1563921D01*
Y267064D01*
G03X1563791Y267112I-130J-152D01*
G01X1563527D01*
G03X1563397Y267064I0J-200D01*
G01X1563396Y267063D01*
G02X1562409Y266693I-987J1131D01*
G02X1560907Y268195I0J1502D01*
G02X1561277Y269182I1501J0D01*
G01Y269183D01*
X1561278D01*
G03X1561326Y269313I-152J130D01*
G01Y269577D01*
G03X1561278Y269707I-200J0D01*
G01X1561277Y269708D01*
G02X1560907Y270695I1131J987D01*
G02X1562409Y272197I1502J0D01*
G02X1563396Y271827I0J-1501D01*
G01X1563397D01*
Y271826D01*
G03X1563527Y271778I130J152D01*
G01X1563791D01*
G03X1563921Y271826I0J200D01*
G01X1563922Y271827D01*
G02X1564909Y272197I987J-1131D01*
G37*
G36*
G01X1667271D02*
G02X1668377Y271712I0J-1504D01*
G03X1668524Y271647I148J135D01*
G01X1668818D01*
G03X1668965Y271712I-1J200D01*
G02X1670071Y272197I1106J-1019D01*
G02X1671573Y270695I0J-1502D01*
G02X1671203Y269708I-1501J0D01*
G01Y269707D01*
X1671202D01*
G03X1671154Y269577I152J-130D01*
G01Y269313D01*
G03X1671202Y269183I200J0D01*
G01X1671203Y269182D01*
G02X1671573Y268195I-1131J-987D01*
G02X1670071Y266693I-1502J0D01*
G02X1668965Y267178I0J1504D01*
G03X1668818Y267243I-148J-135D01*
G01X1668524D01*
G03X1668377Y267178I1J-200D01*
G02X1667271Y266693I-1106J1019D01*
G02X1666284Y267063I0J1501D01*
G01X1666283D01*
Y267064D01*
G03X1666153Y267112I-130J-152D01*
G01X1665889D01*
G03X1665759Y267064I0J-200D01*
G01X1665758Y267063D01*
G02X1664771Y266693I-987J1131D01*
G02X1663269Y268195I0J1502D01*
G02X1663639Y269182I1501J0D01*
G01Y269183D01*
X1663640D01*
G03X1663688Y269313I-152J130D01*
G01Y269577D01*
G03X1663640Y269707I-200J0D01*
G01X1663639Y269708D01*
G02X1663269Y270695I1131J987D01*
G02X1664771Y272197I1502J0D01*
G02X1665758Y271827I0J-1501D01*
G01X1665759D01*
Y271826D01*
G03X1665889Y271778I130J152D01*
G01X1666153D01*
G03X1666283Y271826I0J200D01*
G01X1666284Y271827D01*
G02X1667271Y272197I987J-1131D01*
G37*
G36*
G01X1769633D02*
G02X1770739Y271712I0J-1504D01*
G03X1770886Y271647I148J135D01*
G01X1771180D01*
G03X1771327Y271712I-1J200D01*
G02X1772433Y272197I1106J-1019D01*
G02X1773935Y270695I0J-1502D01*
G02X1773565Y269708I-1501J0D01*
G01Y269707D01*
X1773564D01*
G03X1773516Y269577I152J-130D01*
G01Y269313D01*
G03X1773564Y269183I200J0D01*
G01X1773565Y269182D01*
G02X1773935Y268195I-1131J-987D01*
G02X1772433Y266693I-1502J0D01*
G02X1771327Y267178I0J1504D01*
G03X1771180Y267243I-148J-135D01*
G01X1770886D01*
G03X1770739Y267178I1J-200D01*
G02X1769633Y266693I-1106J1019D01*
G02X1768646Y267063I0J1501D01*
G01X1768645D01*
Y267064D01*
G03X1768515Y267112I-130J-152D01*
G01X1768251D01*
G03X1768121Y267064I0J-200D01*
G01X1768120Y267063D01*
G02X1767133Y266693I-987J1131D01*
G02X1765631Y268195I0J1502D01*
G02X1766001Y269182I1501J0D01*
G01Y269183D01*
X1766002D01*
G03X1766050Y269313I-152J130D01*
G01Y269577D01*
G03X1766002Y269707I-200J0D01*
G01X1766001Y269708D01*
G02X1765631Y270695I1131J987D01*
G02X1767133Y272197I1502J0D01*
G02X1768120Y271827I0J-1501D01*
G01X1768121D01*
Y271826D01*
G03X1768251Y271778I130J152D01*
G01X1768515D01*
G03X1768645Y271826I0J200D01*
G01X1768646Y271827D01*
G02X1769633Y272197I987J-1131D01*
G37*
G36*
G01X1088791Y271528D02*
G02X1090293Y270026I0J-1502D01*
G02X1089923Y269039I-1501J0D01*
G01Y269038D01*
X1089922D01*
G03X1089874Y268908I152J-130D01*
G01Y268644D01*
G03X1089922Y268514I200J0D01*
G01X1089923Y268513D01*
G02X1090293Y267526I-1131J-987D01*
G01Y267499D01*
G03X1090400Y267319I200J-3D01*
G01X1090767Y267126D01*
X1090879Y267134D01*
X1090925Y267167D01*
G02X1091973Y267503I1048J-1466D01*
G02X1090171Y265701I0J-1802D01*
G02X1090178Y265865I1802J5D01*
G01X1090183Y265921D01*
X1090133Y266023D01*
X1089733Y266272D01*
X1089621Y266273D01*
X1089572Y266243D01*
G02X1088791Y266024I-781J1283D01*
G02X1087804Y266394I0J1501D01*
G01X1087803D01*
Y266395D01*
G03X1087673Y266443I-130J-152D01*
G01X1087409D01*
G03X1087279Y266395I0J-200D01*
G01X1087278Y266394D01*
G02X1086291Y266024I-987J1131D01*
G02X1085185Y266509I0J1504D01*
G03X1085038Y266574I-148J-135D01*
G01X1084744D01*
G03X1084597Y266509I1J-200D01*
G02X1083491Y266024I-1106J1019D01*
G02X1081989Y267526I0J1502D01*
G02X1082359Y268513I1501J0D01*
G01Y268514D01*
X1082360D01*
G03X1082408Y268644I-152J130D01*
G01Y268908D01*
G03X1082360Y269038I-200J0D01*
G01X1082359Y269039D01*
G02X1081989Y270026I1131J987D01*
G02X1083491Y271528I1502J0D01*
G02X1084597Y271043I0J-1504D01*
G03X1084744Y270978I148J135D01*
G01X1085038D01*
G03X1085185Y271043I-1J200D01*
G02X1086291Y271528I1106J-1019D01*
G02X1087278Y271158I0J-1501D01*
G01X1087279D01*
Y271157D01*
G03X1087409Y271109I130J152D01*
G01X1087673D01*
G03X1087803Y271157I0J200D01*
G01X1087804Y271158D01*
G02X1088791Y271528I987J-1131D01*
G37*
G36*
G01X1191153D02*
G02X1192655Y270026I0J-1502D01*
G02X1192285Y269039I-1501J0D01*
G01Y269038D01*
X1192284D01*
G03X1192236Y268908I152J-130D01*
G01Y268644D01*
G03X1192284Y268514I200J0D01*
G01X1192285Y268513D01*
G02X1192655Y267526I-1131J-987D01*
G01Y267499D01*
G03X1192762Y267319I200J-3D01*
G01X1193129Y267126D01*
X1193241Y267134D01*
X1193287Y267167D01*
G02X1194335Y267503I1048J-1466D01*
G02X1192533Y265701I0J-1802D01*
G02X1192540Y265865I1802J5D01*
G01X1192545Y265921D01*
X1192495Y266023D01*
X1192095Y266272D01*
X1191983Y266273D01*
X1191934Y266243D01*
G02X1191153Y266024I-781J1283D01*
G02X1190166Y266394I0J1501D01*
G01X1190165D01*
Y266395D01*
G03X1190035Y266443I-130J-152D01*
G01X1189771D01*
G03X1189641Y266395I0J-200D01*
G01X1189640Y266394D01*
G02X1188653Y266024I-987J1131D01*
G02X1187547Y266509I0J1504D01*
G03X1187400Y266574I-148J-135D01*
G01X1187106D01*
G03X1186959Y266509I1J-200D01*
G02X1185853Y266024I-1106J1019D01*
G02X1184351Y267526I0J1502D01*
G02X1184721Y268513I1501J0D01*
G01Y268514D01*
X1184722D01*
G03X1184770Y268644I-152J130D01*
G01Y268908D01*
G03X1184722Y269038I-200J0D01*
G01X1184721Y269039D01*
G02X1184351Y270026I1131J987D01*
G02X1185853Y271528I1502J0D01*
G02X1186959Y271043I0J-1504D01*
G03X1187106Y270978I148J135D01*
G01X1187400D01*
G03X1187547Y271043I-1J200D01*
G02X1188653Y271528I1106J-1019D01*
G02X1189640Y271158I0J-1501D01*
G01X1189641D01*
Y271157D01*
G03X1189771Y271109I130J152D01*
G01X1190035D01*
G03X1190165Y271157I0J200D01*
G01X1190166Y271158D01*
G02X1191153Y271528I987J-1131D01*
G37*
G36*
G01X1293515D02*
G02X1295017Y270026I0J-1502D01*
G02X1294647Y269039I-1501J0D01*
G01Y269038D01*
X1294646D01*
G03X1294598Y268908I152J-130D01*
G01Y268644D01*
G03X1294646Y268514I200J0D01*
G01X1294647Y268513D01*
G02X1295017Y267526I-1131J-987D01*
G01Y267499D01*
G03X1295124Y267319I200J-3D01*
G01X1295491Y267126D01*
X1295603Y267134D01*
X1295649Y267167D01*
G02X1296697Y267503I1048J-1466D01*
G02X1294895Y265701I0J-1802D01*
G02X1294902Y265865I1802J5D01*
G01X1294907Y265921D01*
X1294857Y266023D01*
X1294457Y266272D01*
X1294345Y266273D01*
X1294296Y266243D01*
G02X1293515Y266024I-781J1283D01*
G02X1292528Y266394I0J1501D01*
G01X1292527D01*
Y266395D01*
G03X1292397Y266443I-130J-152D01*
G01X1292133D01*
G03X1292003Y266395I0J-200D01*
G01X1292002Y266394D01*
G02X1291015Y266024I-987J1131D01*
G02X1289909Y266509I0J1504D01*
G03X1289762Y266574I-148J-135D01*
G01X1289468D01*
G03X1289321Y266509I1J-200D01*
G02X1288215Y266024I-1106J1019D01*
G02X1286713Y267526I0J1502D01*
G02X1287083Y268513I1501J0D01*
G01Y268514D01*
X1287084D01*
G03X1287132Y268644I-152J130D01*
G01Y268908D01*
G03X1287084Y269038I-200J0D01*
G01X1287083Y269039D01*
G02X1286713Y270026I1131J987D01*
G02X1288215Y271528I1502J0D01*
G02X1289321Y271043I0J-1504D01*
G03X1289468Y270978I148J135D01*
G01X1289762D01*
G03X1289909Y271043I-1J200D01*
G02X1291015Y271528I1106J-1019D01*
G02X1292002Y271158I0J-1501D01*
G01X1292003D01*
Y271157D01*
G03X1292133Y271109I130J152D01*
G01X1292397D01*
G03X1292527Y271157I0J200D01*
G01X1292528Y271158D01*
G02X1293515Y271528I987J-1131D01*
G37*
G36*
G01X1443516D02*
G02X1445018Y270026I0J-1502D01*
G02X1444648Y269039I-1501J0D01*
G01Y269038D01*
X1444647D01*
G03X1444599Y268908I152J-130D01*
G01Y268644D01*
G03X1444647Y268514I200J0D01*
G01X1444648Y268513D01*
G02X1445018Y267526I-1131J-987D01*
G01Y267499D01*
G03X1445125Y267319I200J-3D01*
G01X1445492Y267126D01*
X1445604Y267134D01*
X1445650Y267167D01*
G02X1446698Y267503I1048J-1466D01*
G02X1444896Y265701I0J-1802D01*
G02X1444903Y265865I1802J5D01*
G01X1444908Y265921D01*
X1444858Y266023D01*
X1444458Y266272D01*
X1444346Y266273D01*
X1444297Y266243D01*
G02X1443516Y266024I-781J1283D01*
G02X1442529Y266394I0J1501D01*
G01X1442528D01*
Y266395D01*
G03X1442398Y266443I-130J-152D01*
G01X1442134D01*
G03X1442004Y266395I0J-200D01*
G01X1442003Y266394D01*
G02X1441016Y266024I-987J1131D01*
G02X1439910Y266509I0J1504D01*
G03X1439763Y266574I-148J-135D01*
G01X1439469D01*
G03X1439322Y266509I1J-200D01*
G02X1438216Y266024I-1106J1019D01*
G02X1436714Y267526I0J1502D01*
G02X1437084Y268513I1501J0D01*
G01Y268514D01*
X1437085D01*
G03X1437133Y268644I-152J130D01*
G01Y268908D01*
G03X1437085Y269038I-200J0D01*
G01X1437084Y269039D01*
G02X1436714Y270026I1131J987D01*
G02X1438216Y271528I1502J0D01*
G02X1439322Y271043I0J-1504D01*
G03X1439469Y270978I148J135D01*
G01X1439763D01*
G03X1439910Y271043I-1J200D01*
G02X1441016Y271528I1106J-1019D01*
G02X1442003Y271158I0J-1501D01*
G01X1442004D01*
Y271157D01*
G03X1442134Y271109I130J152D01*
G01X1442398D01*
G03X1442528Y271157I0J200D01*
G01X1442529Y271158D01*
G02X1443516Y271528I987J-1131D01*
G37*
G36*
G01X1545878D02*
G02X1547380Y270026I0J-1502D01*
G02X1547010Y269039I-1501J0D01*
G01Y269038D01*
X1547009D01*
G03X1546961Y268908I152J-130D01*
G01Y268644D01*
G03X1547009Y268514I200J0D01*
G01X1547010Y268513D01*
G02X1547380Y267526I-1131J-987D01*
G01Y267499D01*
G03X1547487Y267319I200J-3D01*
G01X1547854Y267126D01*
X1547966Y267134D01*
X1548012Y267167D01*
G02X1549060Y267503I1048J-1466D01*
G02X1547258Y265701I0J-1802D01*
G02X1547265Y265865I1802J5D01*
G01X1547270Y265921D01*
X1547220Y266023D01*
X1546820Y266272D01*
X1546708Y266273D01*
X1546659Y266243D01*
G02X1545878Y266024I-781J1283D01*
G02X1544891Y266394I0J1501D01*
G01X1544890D01*
Y266395D01*
G03X1544760Y266443I-130J-152D01*
G01X1544496D01*
G03X1544366Y266395I0J-200D01*
G01X1544365Y266394D01*
G02X1543378Y266024I-987J1131D01*
G02X1542272Y266509I0J1504D01*
G03X1542125Y266574I-148J-135D01*
G01X1541831D01*
G03X1541684Y266509I1J-200D01*
G02X1540578Y266024I-1106J1019D01*
G02X1539076Y267526I0J1502D01*
G02X1539446Y268513I1501J0D01*
G01Y268514D01*
X1539447D01*
G03X1539495Y268644I-152J130D01*
G01Y268908D01*
G03X1539447Y269038I-200J0D01*
G01X1539446Y269039D01*
G02X1539076Y270026I1131J987D01*
G02X1540578Y271528I1502J0D01*
G02X1541684Y271043I0J-1504D01*
G03X1541831Y270978I148J135D01*
G01X1542125D01*
G03X1542272Y271043I-1J200D01*
G02X1543378Y271528I1106J-1019D01*
G02X1544365Y271158I0J-1501D01*
G01X1544366D01*
Y271157D01*
G03X1544496Y271109I130J152D01*
G01X1544760D01*
G03X1544890Y271157I0J200D01*
G01X1544891Y271158D01*
G02X1545878Y271528I987J-1131D01*
G37*
G36*
G01X1648240D02*
G02X1649742Y270026I0J-1502D01*
G02X1649372Y269039I-1501J0D01*
G01Y269038D01*
X1649371D01*
G03X1649323Y268908I152J-130D01*
G01Y268644D01*
G03X1649371Y268514I200J0D01*
G01X1649372Y268513D01*
G02X1649742Y267526I-1131J-987D01*
G01Y267499D01*
G03X1649849Y267319I200J-3D01*
G01X1650216Y267126D01*
X1650328Y267134D01*
X1650374Y267167D01*
G02X1651422Y267503I1048J-1466D01*
G02X1649620Y265701I0J-1802D01*
G02X1649627Y265865I1802J5D01*
G01X1649632Y265921D01*
X1649582Y266023D01*
X1649182Y266272D01*
X1649070Y266273D01*
X1649021Y266243D01*
G02X1648240Y266024I-781J1283D01*
G02X1647253Y266394I0J1501D01*
G01X1647252D01*
Y266395D01*
G03X1647122Y266443I-130J-152D01*
G01X1646858D01*
G03X1646728Y266395I0J-200D01*
G01X1646727Y266394D01*
G02X1645740Y266024I-987J1131D01*
G02X1644634Y266509I0J1504D01*
G03X1644487Y266574I-148J-135D01*
G01X1644193D01*
G03X1644046Y266509I1J-200D01*
G02X1642940Y266024I-1106J1019D01*
G02X1641438Y267526I0J1502D01*
G02X1641808Y268513I1501J0D01*
G01Y268514D01*
X1641809D01*
G03X1641857Y268644I-152J130D01*
G01Y268908D01*
G03X1641809Y269038I-200J0D01*
G01X1641808Y269039D01*
G02X1641438Y270026I1131J987D01*
G02X1642940Y271528I1502J0D01*
G02X1644046Y271043I0J-1504D01*
G03X1644193Y270978I148J135D01*
G01X1644487D01*
G03X1644634Y271043I-1J200D01*
G02X1645740Y271528I1106J-1019D01*
G02X1646727Y271158I0J-1501D01*
G01X1646728D01*
Y271157D01*
G03X1646858Y271109I130J152D01*
G01X1647122D01*
G03X1647252Y271157I0J200D01*
G01X1647253Y271158D01*
G02X1648240Y271528I987J-1131D01*
G37*
G36*
G01X1750602D02*
G02X1752104Y270026I0J-1502D01*
G02X1751734Y269039I-1501J0D01*
G01Y269038D01*
X1751733D01*
G03X1751685Y268908I152J-130D01*
G01Y268644D01*
G03X1751733Y268514I200J0D01*
G01X1751734Y268513D01*
G02X1752104Y267526I-1131J-987D01*
G01Y267499D01*
G03X1752211Y267319I200J-3D01*
G01X1752578Y267126D01*
X1752690Y267134D01*
X1752736Y267167D01*
G02X1753784Y267503I1048J-1466D01*
G02X1751982Y265701I0J-1802D01*
G02X1751989Y265865I1802J5D01*
G01X1751994Y265921D01*
X1751944Y266023D01*
X1751544Y266272D01*
X1751432Y266273D01*
X1751383Y266243D01*
G02X1750602Y266024I-781J1283D01*
G02X1749615Y266394I0J1501D01*
G01X1749614D01*
Y266395D01*
G03X1749484Y266443I-130J-152D01*
G01X1749220D01*
G03X1749090Y266395I0J-200D01*
G01X1749089Y266394D01*
G02X1748102Y266024I-987J1131D01*
G02X1746996Y266509I0J1504D01*
G03X1746849Y266574I-148J-135D01*
G01X1746555D01*
G03X1746408Y266509I1J-200D01*
G02X1745302Y266024I-1106J1019D01*
G02X1743800Y267526I0J1502D01*
G02X1744170Y268513I1501J0D01*
G01Y268514D01*
X1744171D01*
G03X1744219Y268644I-152J130D01*
G01Y268908D01*
G03X1744171Y269038I-200J0D01*
G01X1744170Y269039D01*
G02X1743800Y270026I1131J987D01*
G02X1745302Y271528I1502J0D01*
G02X1746408Y271043I0J-1504D01*
G03X1746555Y270978I148J135D01*
G01X1746849D01*
G03X1746996Y271043I-1J200D01*
G02X1748102Y271528I1106J-1019D01*
G02X1749089Y271158I0J-1501D01*
G01X1749090D01*
Y271157D01*
G03X1749220Y271109I130J152D01*
G01X1749484D01*
G03X1749614Y271157I0J200D01*
G01X1749615Y271158D01*
G02X1750602Y271528I987J-1131D01*
G37*
G36*
G01X1096347Y1144313D02*
G02X1096493Y1144130I-744J-743D01*
G02X1096655Y1143569I-890J-561D01*
G02X1096654Y1143527I-1052J4D01*
G01Y1141829D01*
G02X1096203Y1141378I-451J0D01*
G01X1096135D01*
G03X1095935Y1141178I0J-200D01*
G01Y1141140D01*
X1095949Y1141105D01*
G02X1096035Y1140649I-1166J-456D01*
G02X1093531I-1252J0D01*
G02X1094411Y1141844I1251J0D01*
G01X1094412D01*
G03X1094552Y1142035I-60J191D01*
G01Y1143132D01*
X1094527Y1143158D01*
X1094411Y1143194D01*
G02X1093531Y1144389I371J1195D01*
G02X1094783Y1145641I1252J0D01*
G02X1095995Y1144704I0J-1252D01*
G01Y1144702D01*
X1096002Y1144677D01*
X1096028Y1144632D01*
X1096347Y1144313D01*
G37*
G36*
G01X1107423Y1180590D02*
X1106356D01*
X1106330Y1180583D01*
G02X1106003Y1180539I-329J1208D01*
G02Y1183043I0J1252D01*
G02X1106330Y1182999I-2J-1252D01*
G01X1106356Y1182992D01*
X1107423D01*
G02X1107875Y1182541I1J-451D01*
G01Y1181041D01*
G02X1107423Y1180590I-452J1D01*
G37*
G36*
G01X1104801Y1172890D02*
Y1173957D01*
X1104795Y1173983D01*
G02X1104751Y1174310I1208J329D01*
G02X1107255I1252J0D01*
G02X1107211Y1173983I-1252J2D01*
G01X1107205Y1173957D01*
Y1172890D01*
G02X1106753Y1172438I-452J0D01*
G01X1105253D01*
G02X1104801Y1172890I0J452D01*
G37*
G36*
G01X1164645Y1170923D02*
Y1171990D01*
G02X1165096Y1172442I451J1D01*
G01X1166596D01*
G02X1167047Y1171990I-1J-452D01*
G01Y1170923D01*
X1167054Y1170897D01*
G02X1167098Y1170570I-1208J-329D01*
G02X1164594I-1252J0D01*
G02X1164638Y1170897I1252J-2D01*
G01X1164645Y1170923D01*
G37*
G36*
G01X1157163D02*
Y1171990D01*
G02X1157615Y1172442I452J0D01*
G01X1159115D01*
G02X1159567Y1171990I0J-452D01*
G01Y1170923D01*
X1159573Y1170897D01*
G02X1159617Y1170570I-1208J-329D01*
G02X1157113I-1252J0D01*
G02X1157157Y1170897I1252J-2D01*
G01X1157163Y1170923D01*
G37*
G36*
G01X1149683D02*
Y1171990D01*
G02X1150135Y1172442I452J0D01*
G01X1151635D01*
G02X1152087Y1171990I0J-452D01*
G01Y1170923D01*
X1152093Y1170897D01*
G02X1152137Y1170570I-1208J-329D01*
G02X1149633I-1252J0D01*
G02X1149677Y1170897I1252J-2D01*
G01X1149683Y1170923D01*
G37*
G36*
G01X1138463D02*
Y1171990D01*
G02X1138915Y1172442I452J0D01*
G01X1140415D01*
G02X1140867Y1171990I0J-452D01*
G01Y1170923D01*
X1140873Y1170897D01*
G02X1140917Y1170570I-1208J-329D01*
G02X1138413I-1252J0D01*
G02X1138457Y1170897I1252J-2D01*
G01X1138463Y1170923D01*
G37*
G36*
G01X1130983D02*
Y1171990D01*
G02X1131434Y1172442I451J1D01*
G01X1132934D01*
G02X1133385Y1171990I-1J-452D01*
G01Y1170923D01*
X1133392Y1170897D01*
G02X1133436Y1170570I-1208J-329D01*
G02X1130932I-1252J0D01*
G02X1130976Y1170897I1252J-2D01*
G01X1130983Y1170923D01*
G37*
G36*
G01X1123503D02*
Y1171990D01*
G02X1123954Y1172442I451J1D01*
G01X1125454D01*
G02X1125905Y1171990I-1J-452D01*
G01Y1170923D01*
X1125912Y1170897D01*
G02X1125956Y1170570I-1208J-329D01*
G02X1123452I-1252J0D01*
G02X1123496Y1170897I1252J-2D01*
G01X1123503Y1170923D01*
G37*
G36*
G01X1116023D02*
Y1171990D01*
G02X1116474Y1172442I451J1D01*
G01X1117974D01*
G02X1118425Y1171990I-1J-452D01*
G01Y1170923D01*
X1118432Y1170897D01*
G02X1118476Y1170570I-1208J-329D01*
G02X1115972I-1252J0D01*
G02X1116016Y1170897I1252J-2D01*
G01X1116023Y1170923D01*
G37*
G36*
G01X1108541D02*
Y1171990D01*
G02X1108993Y1172442I452J0D01*
G01X1110493D01*
G02X1110945Y1171990I0J-452D01*
G01Y1170923D01*
X1110951Y1170897D01*
G02X1110995Y1170570I-1208J-329D01*
G02X1108491I-1252J0D01*
G02X1108535Y1170897I1252J-2D01*
G01X1108541Y1170923D01*
G37*
G36*
G01X1155182Y1167952D02*
X1155187D01*
G02X1155523Y1168102I336J-301D01*
G01X1156723D01*
G02X1157175Y1167650I0J-452D01*
G01Y1166150D01*
G02X1156723Y1165698I-452J0D01*
G01X1155523D01*
G02X1155363Y1165728I2J452D01*
G03X1155201Y1165718I-70J-187D01*
G02X1154625Y1165578I-575J1112D01*
G02X1154082Y1165702I0J1251D01*
G03X1153942Y1165715I-87J-180D01*
G02X1153823Y1165698I-123J434D01*
G01X1152623D01*
G02X1152171Y1166150I0J452D01*
G01Y1167650D01*
G02X1152623Y1168102I452J0D01*
G01X1153823D01*
G02X1154058Y1168035I-2J-452D01*
G03X1154226Y1168017I103J171D01*
G02X1154625Y1168082I398J-1187D01*
G02X1155182Y1167952I1J-1252D01*
G37*
G36*
G01X1171086Y1165628D02*
X1169939D01*
X1169913Y1165622D01*
G02X1169586Y1165578I-329J1208D01*
G02Y1168082I0J1252D01*
G02X1169913Y1168038I-2J-1252D01*
G01X1169939Y1168032D01*
X1171086D01*
G02X1171537Y1167580I-1J-452D01*
G01Y1166080D01*
G02X1171086Y1165628I-451J-1D01*
G37*
G36*
G01X1163606D02*
X1162459D01*
X1162433Y1165622D01*
G02X1162106Y1165578I-329J1208D01*
G02Y1168082I0J1252D01*
G02X1162433Y1168038I-2J-1252D01*
G01X1162459Y1168032D01*
X1163606D01*
G02X1164057Y1167580I-1J-452D01*
G01Y1166080D01*
G02X1163606Y1165628I-451J-1D01*
G37*
G36*
G01X1144905D02*
X1143758D01*
X1143732Y1165622D01*
G02X1143405Y1165578I-329J1208D01*
G02Y1168082I0J1252D01*
G02X1143732Y1168038I-2J-1252D01*
G01X1143758Y1168032D01*
X1144905D01*
G02X1145357Y1167580I0J-452D01*
G01Y1166080D01*
G02X1144905Y1165628I-452J0D01*
G37*
G36*
G01X1136325D02*
G02X1136312Y1165629I28J450D01*
G03X1136253Y1165622I-6J-200D01*
G02X1135925Y1165578I-329J1208D01*
G02Y1168082I0J1252D01*
G02X1136253Y1168038I-1J-1252D01*
G03X1136312Y1168031I53J193D01*
G02X1136325Y1168032I41J-449D01*
G01X1137525D01*
G02X1137977Y1167580I0J-452D01*
G01Y1166080D01*
G02X1137525Y1165628I-452J0D01*
G01X1136325D01*
G37*
G36*
G01X1128844D02*
G02X1128831Y1165629I28J450D01*
G03X1128772Y1165622I-6J-200D01*
G02X1128444Y1165578I-329J1208D01*
G02Y1168082I0J1252D01*
G02X1128772Y1168038I-1J-1252D01*
G03X1128831Y1168031I53J193D01*
G02X1128844Y1168032I41J-449D01*
G01X1130044D01*
G02X1130495Y1167580I-1J-452D01*
G01Y1166080D01*
G02X1130044Y1165628I-451J-1D01*
G01X1128844D01*
G37*
G36*
G01X1121364D02*
G02X1121351Y1165629I28J450D01*
G03X1121292Y1165622I-6J-200D01*
G02X1120964Y1165578I-329J1208D01*
G02Y1168082I0J1252D01*
G02X1121292Y1168038I-1J-1252D01*
G03X1121351Y1168031I53J193D01*
G02X1121364Y1168032I41J-449D01*
G01X1122564D01*
G02X1123015Y1167580I-1J-452D01*
G01Y1166080D01*
G02X1122564Y1165628I-451J-1D01*
G01X1121364D01*
G37*
G36*
G01X1113884D02*
G02X1113871Y1165629I28J450D01*
G03X1113812Y1165622I-6J-200D01*
G02X1113484Y1165578I-329J1208D01*
G02Y1168082I0J1252D01*
G02X1113812Y1168038I-1J-1252D01*
G03X1113871Y1168031I53J193D01*
G02X1113884Y1168032I41J-449D01*
G01X1115084D01*
G02X1115535Y1167580I-1J-452D01*
G01Y1166080D01*
G02X1115084Y1165628I-451J-1D01*
G01X1113884D01*
G37*
G36*
G01X1106403D02*
G02X1106390Y1165629I28J450D01*
G03X1106331Y1165622I-6J-200D01*
G02X1106003Y1165578I-329J1208D01*
G02Y1168082I0J1252D01*
G02X1106331Y1168038I-1J-1252D01*
G03X1106390Y1168031I53J193D01*
G02X1106403Y1168032I41J-449D01*
G01X1107603D01*
G02X1108055Y1167580I0J-452D01*
G01Y1166080D01*
G02X1107603Y1165628I-452J0D01*
G01X1106403D01*
G37*
G36*
G01X1154025Y1160891D02*
Y1163691D01*
G02X1154477Y1164142I452J-1D01*
G01X1157677D01*
G02X1158129Y1163691I1J-451D01*
G01Y1161809D01*
G03X1158187Y1161668I200J0D01*
G01X1159109Y1160747D01*
G02X1159414Y1160077I-744J-743D01*
G03X1159441Y1159989I200J13D01*
G02X1159617Y1159350I-1076J-640D01*
G02X1159573Y1159023I-1252J2D01*
G01X1159567Y1158997D01*
Y1157930D01*
G02X1159115Y1157478I-452J0D01*
G01X1157615D01*
G02X1157163Y1157930I0J452D01*
G01Y1158997D01*
X1157157Y1159023D01*
G02X1157113Y1159350I1208J329D01*
G02X1157141Y1159611I1252J-2D01*
G01X1157151Y1159662D01*
X1157123Y1159758D01*
X1156500Y1160381D01*
G03X1156359Y1160440I-142J-141D01*
G01X1154477D01*
G02X1154025Y1160891I-1J451D01*
G37*
G36*
G01X1135325D02*
Y1163691D01*
G02X1135776Y1164142I451J0D01*
G01X1138976D01*
G02X1139427Y1163691I0J-451D01*
G01Y1161809D01*
G03X1139486Y1161668I200J1D01*
G01X1140409Y1160746D01*
G02X1140714Y1160077I-744J-743D01*
G03X1140741Y1159990I199J14D01*
G02X1140917Y1159350I-1076J-640D01*
G02X1140873Y1159023I-1252J2D01*
G01X1140867Y1158997D01*
Y1157930D01*
G02X1140415Y1157478I-452J0D01*
G01X1138915D01*
G02X1138463Y1157930I0J452D01*
G01Y1158997D01*
X1138457Y1159023D01*
G02X1138413Y1159350I1208J329D01*
G02X1138440Y1159611I1252J2D01*
G01X1138451Y1159661D01*
X1138423Y1159757D01*
X1137799Y1160381D01*
G03X1137658Y1160440I-142J-141D01*
G01X1135776D01*
G02X1135325Y1160891I0J451D01*
G37*
G36*
G01X1120363D02*
Y1163691D01*
G02X1120815Y1164142I452J-1D01*
G01X1124015D01*
G02X1124467Y1163691I1J-451D01*
G01Y1161809D01*
G03X1124525Y1161668I200J0D01*
G01X1124987Y1161207D01*
G02X1125214Y1160865I-746J-741D01*
G01X1125404Y1160407D01*
X1125436Y1160366D01*
X1125458Y1160349D01*
G02X1125956Y1159350I-753J-999D01*
G02X1125912Y1159023I-1252J2D01*
G01X1125905Y1158997D01*
Y1157930D01*
G02X1125454Y1157478I-451J-1D01*
G01X1123954D01*
G02X1123503Y1157930I1J452D01*
G01Y1158997D01*
X1123496Y1159023D01*
G02X1123452Y1159350I1208J329D01*
G02X1123464Y1159524I1252J1D01*
G01X1123468Y1159551D01*
X1123461Y1159602D01*
X1123367Y1159831D01*
G03X1123323Y1159896I-185J-78D01*
G01X1122838Y1160381D01*
G03X1122697Y1160440I-142J-141D01*
G01X1120815D01*
G02X1120363Y1160891I-1J451D01*
G37*
G36*
G01X1164645Y1157930D02*
Y1158997D01*
X1164638Y1159023D01*
G02X1164594Y1159350I1208J329D01*
G02X1167098I1252J0D01*
G02X1167054Y1159023I-1252J2D01*
G01X1167047Y1158997D01*
Y1157930D01*
G02X1166596Y1157478I-451J-1D01*
G01X1165096D01*
G02X1164645Y1157930I1J452D01*
G37*
G36*
G01X1149683D02*
Y1158997D01*
X1149677Y1159023D01*
G02X1149633Y1159350I1208J329D01*
G02X1152137I1252J0D01*
G02X1152093Y1159023I-1252J2D01*
G01X1152087Y1158997D01*
Y1157930D01*
G02X1151635Y1157478I-452J0D01*
G01X1150135D01*
G02X1149683Y1157930I0J452D01*
G37*
G36*
G01X1130983D02*
Y1158997D01*
X1130976Y1159023D01*
G02X1130932Y1159350I1208J329D01*
G02X1133436I1252J0D01*
G02X1133392Y1159023I-1252J2D01*
G01X1133385Y1158997D01*
Y1157930D01*
G02X1132934Y1157478I-451J-1D01*
G01X1131434D01*
G02X1130983Y1157930I1J452D01*
G37*
G36*
G01X1116023D02*
Y1158997D01*
X1116016Y1159023D01*
G02X1115972Y1159350I1208J329D01*
G02X1118476I1252J0D01*
G02X1118432Y1159023I-1252J2D01*
G01X1118425Y1158997D01*
Y1157930D01*
G02X1117974Y1157478I-451J-1D01*
G01X1116474D01*
G02X1116023Y1157930I1J452D01*
G37*
G36*
G01X1108541D02*
Y1158997D01*
X1108535Y1159023D01*
G02X1108491Y1159350I1208J329D01*
G02X1110995I1252J0D01*
G02X1110951Y1159023I-1252J2D01*
G01X1110945Y1158997D01*
Y1157930D01*
G02X1110493Y1157478I-452J0D01*
G01X1108993D01*
G02X1108541Y1157930I0J452D01*
G37*
G36*
G01X1104801Y1155963D02*
Y1157030D01*
G02X1105253Y1157482I452J0D01*
G01X1106753D01*
G02X1107205Y1157030I0J-452D01*
G01Y1155963D01*
X1107211Y1155937D01*
G02X1107255Y1155610I-1208J-329D01*
G02X1104751I-1252J0D01*
G02X1104795Y1155937I1252J-2D01*
G01X1104801Y1155963D01*
G37*
G36*
G01X1107423Y1146928D02*
X1106356D01*
X1106330Y1146921D01*
G02X1106003Y1146877I-329J1208D01*
G02Y1149381I0J1252D01*
G02X1106330Y1149337I-2J-1252D01*
G01X1106356Y1149330D01*
X1107423D01*
G02X1107875Y1148879I1J-451D01*
G01Y1147379D01*
G02X1107423Y1146928I-452J1D01*
G37*
G36*
G01X1181132Y1156819D02*
X1181157Y1156812D01*
X1184195D01*
X1184220Y1156819D01*
G02X1184546Y1156862I325J-1209D01*
G02Y1154358I0J-1252D01*
G02X1184220Y1154401I-1J1252D01*
G01X1184195Y1154408D01*
X1181157D01*
X1181132Y1154401D01*
G02X1180806Y1154358I-325J1209D01*
G02Y1156862I0J1252D01*
G02X1181132Y1156819I1J-1252D01*
G37*
G36*
G01X1113830Y1149888D02*
X1113859Y1149902D01*
X1114397Y1150440D01*
G02X1114538Y1150498I141J-142D01*
G01X1181041D01*
G02X1181891Y1150146I0J-1201D01*
G01X1182272Y1149765D01*
G02X1182625Y1148915I-849J-851D01*
G01Y1147879D01*
G02X1182272Y1147029I-1202J1D01*
G01X1181691Y1146448D01*
G02X1180841Y1146096I-850J849D01*
G01X1114844D01*
G02X1114703Y1146154I0J200D01*
G01X1113954Y1146903D01*
X1113851Y1146931D01*
X1113800Y1146917D01*
G02X1113484Y1146877I-314J1212D01*
G02X1112232Y1148129I0J1252D01*
G02X1113170Y1149341I1252J0D01*
G01X1113196Y1149348D01*
X1113242Y1149374D01*
X1113560Y1149693D01*
G02X1113830Y1149888I743J-744D01*
G37*
G36*
G01X1182566Y1180986D02*
X1181026Y1179446D01*
G02X1180885Y1179388I-141J142D01*
G01X1113265D01*
G02X1113124Y1179446I0J200D01*
G01X1111826Y1180744D01*
G02X1111767Y1180885I141J142D01*
G01Y1182662D01*
G02X1111826Y1182803I200J-1D01*
G01X1112631Y1183608D01*
G02X1112772Y1183666I141J-142D01*
G01X1181653D01*
G02X1181794Y1183608I0J-200D01*
G01X1182566Y1182836D01*
G02X1182625Y1182695I-141J-142D01*
G01Y1181127D01*
G02X1182566Y1180986I-200J1D01*
G37*
G36*
G01X1164305Y84108D02*
Y84460D01*
X1164277Y84529D01*
X1164251Y84557D01*
G02X1163845Y85584I1096J1027D01*
G02X1166849I1502J0D01*
G02X1166443Y84557I-1502J0D01*
G01X1166417Y84529D01*
X1166389Y84460D01*
Y84108D01*
X1166417Y84039D01*
X1166443Y84011D01*
G02Y81957I-1096J-1027D01*
G01X1166417Y81929D01*
X1166389Y81860D01*
Y81508D01*
X1166417Y81439D01*
X1166443Y81411D01*
G02Y79357I-1096J-1027D01*
G01X1166417Y79329D01*
X1166389Y79260D01*
Y78908D01*
X1166417Y78839D01*
X1166443Y78811D01*
G02Y76757I-1096J-1027D01*
G01X1166417Y76729D01*
X1166389Y76660D01*
Y76308D01*
X1166417Y76239D01*
X1166443Y76211D01*
G02X1166849Y75184I-1096J-1027D01*
G02X1163845I-1502J0D01*
G02X1164251Y76211I1502J0D01*
G01X1164277Y76239D01*
X1164305Y76308D01*
Y76660D01*
X1164277Y76729D01*
X1164251Y76757D01*
G02Y78811I1096J1027D01*
G01X1164277Y78839D01*
X1164305Y78908D01*
Y79260D01*
X1164277Y79329D01*
X1164251Y79357D01*
G02Y81411I1096J1027D01*
G01X1164277Y81439D01*
X1164305Y81508D01*
Y81860D01*
X1164277Y81929D01*
X1164251Y81957D01*
G02Y84011I1096J1027D01*
G01X1164277Y84039D01*
X1164305Y84108D01*
G37*
G36*
G01X1173783Y101516D02*
X1173819Y101900D01*
X1173792Y101981D01*
X1173763Y102013D01*
G02X1173359Y103037I1098J1025D01*
G02X1176363I1502J0D01*
G02X1175896Y101948I-1503J0D01*
G01X1175864Y101918D01*
X1175832Y101839D01*
X1175845Y101454D01*
X1175883Y101377D01*
X1175916Y101350D01*
G02X1176570Y99961I-1148J-1389D01*
G02X1172966I-1802J0D01*
G02X1173706Y101417I1802J0D01*
G01X1173741Y101442D01*
X1173783Y101516D01*
G37*
G36*
G01X1193748Y116195D02*
X1193867Y116168D01*
G03X1194010Y116189I44J195D01*
G02X1194902Y116426I893J-1566D01*
G02X1195794Y116189I-1J-1803D01*
G03X1195937Y116168I99J174D01*
G01X1196056Y116195D01*
G03X1196175Y116274I-44J195D01*
G02X1197398Y116903I1222J-873D01*
G02Y113899I0J-1502D01*
G02X1197166Y113917I0J1502D01*
G01X1197123Y113924D01*
X1197039Y113900D01*
X1196774Y113674D01*
G03X1196704Y113522I130J-152D01*
G01Y112324D01*
G03X1196774Y112172I200J0D01*
G01X1197039Y111946D01*
X1197123Y111922D01*
X1197166Y111929D01*
G02X1197398Y111947I232J-1484D01*
G02Y108943I0J-1502D01*
G02X1196175Y109572I-1J1502D01*
G03X1196056Y109651I-163J-116D01*
G01X1195937Y109678D01*
G03X1195794Y109657I-44J-195D01*
G02X1194902Y109420I-893J1566D01*
G02X1194010Y109657I1J1803D01*
G03X1193867Y109678I-99J-174D01*
G01X1193748Y109651D01*
G03X1193629Y109572I44J-195D01*
G02X1192406Y108943I-1222J873D01*
G02Y111947I0J1502D01*
G02X1192638Y111929I0J-1502D01*
G01X1192681Y111922D01*
X1192765Y111946D01*
X1193030Y112172D01*
G03X1193100Y112324I-130J152D01*
G01Y113522D01*
G03X1193030Y113674I-200J0D01*
G01X1192765Y113900D01*
X1192681Y113924D01*
X1192638Y113917D01*
G02X1192406Y113899I-232J1484D01*
G02Y116903I0J1502D01*
G02X1193629Y116274I1J-1502D01*
G03X1193748Y116195I163J116D01*
G37*
G36*
G01Y130368D02*
X1193867Y130341D01*
G03X1194010Y130362I44J195D01*
G02X1194902Y130598I892J-1566D01*
G02X1195794Y130362I0J-1802D01*
G03X1195937Y130341I99J174D01*
G01X1196056Y130368D01*
G03X1196175Y130447I-44J195D01*
G02X1197398Y131076I1222J-873D01*
G02Y128072I0J-1502D01*
G02X1197166Y128090I0J1502D01*
G01X1197123Y128097D01*
X1197039Y128073D01*
X1196774Y127847D01*
G03X1196704Y127695I130J-152D01*
G01Y126497D01*
G03X1196774Y126345I200J0D01*
G01X1197039Y126119D01*
X1197123Y126095D01*
X1197166Y126102D01*
G02X1197398Y126120I232J-1484D01*
G02Y123116I0J-1502D01*
G02X1196175Y123745I-1J1502D01*
G03X1196056Y123824I-163J-116D01*
G01X1195937Y123851D01*
G03X1195794Y123830I-44J-195D01*
G02X1194902Y123594I-892J1566D01*
G02X1194010Y123830I0J1802D01*
G03X1193867Y123851I-99J-174D01*
G01X1193748Y123824D01*
G03X1193629Y123745I44J-195D01*
G02X1192406Y123116I-1222J873D01*
G02Y126120I0J1502D01*
G02X1192638Y126102I0J-1502D01*
G01X1192681Y126095D01*
X1192765Y126119D01*
X1193030Y126345D01*
G03X1193100Y126497I-130J152D01*
G01Y127695D01*
G03X1193030Y127847I-200J0D01*
G01X1192765Y128073D01*
X1192681Y128097D01*
X1192638Y128090D01*
G02X1192406Y128072I-232J1484D01*
G02Y131076I0J1502D01*
G02X1193629Y130447I1J-1502D01*
G03X1193748Y130368I163J116D01*
G37*
G36*
G01X1173117Y146186D02*
G02X1169941Y140292I-3176J-2091D01*
G01X1169940D01*
G02X1166764Y146186I0J3803D01*
G01X1166780Y146211D01*
X1166797Y146266D01*
Y146296D01*
G03X1166597Y146496I-200J0D01*
G01X1166290D01*
G02Y153898I0J3701D01*
G01X1173590D01*
G02Y146496I0J-3701D01*
G01X1173284D01*
G03X1173084Y146296I0J-200D01*
G01Y146236D01*
X1173117Y146186D01*
G37*
G36*
G01X1166254Y92683D02*
Y92732D01*
G02X1169258Y92734I1502J2D01*
G02X1169257Y92684I-1502J5D01*
G01X1169255Y92633D01*
X1169300Y92543D01*
X1169654Y92292D01*
X1169753Y92279D01*
X1169800Y92297D01*
G02X1170447Y92417I647J-1682D01*
G02X1168645Y90615I0J-1802D01*
G02X1168660Y90849I1802J2D01*
G01X1168667Y90899D01*
X1168631Y90993D01*
X1168303Y91278D01*
X1168205Y91300D01*
X1168157Y91286D01*
G02X1167756Y91232I-399J1448D01*
G02X1167415Y91271I-1J1502D01*
G01X1167368Y91282D01*
X1167275Y91259D01*
X1166957Y90978D01*
X1166922Y90888D01*
X1166927Y90840D01*
G02X1166937Y90650I-1792J-190D01*
G02X1165135Y92452I-1802J0D01*
G02X1165723Y92353I-1J-1802D01*
G01X1165770Y92337D01*
X1165865Y92351D01*
X1166210Y92597D01*
X1166254Y92683D01*
G37*
G36*
G01X1191165Y100457D02*
G02X1190505Y101701I842J1244D01*
G02X1193509I1502J0D01*
G02X1192849Y100457I-1502J0D01*
G03Y99795I224J-331D01*
G02X1193509Y98551I-842J-1244D01*
G02X1190505I-1502J0D01*
G02X1191165Y99795I1502J0D01*
G03Y100457I-224J331D01*
G37*
G36*
G01X1183577Y108025D02*
G02X1182995Y107908I-581J1385D01*
G02Y110912I0J1502D01*
G02X1184483Y109616I0J-1502D01*
G01X1184489Y109569D01*
X1184542Y109492D01*
X1184901Y109290D01*
X1184994Y109285D01*
X1185038Y109304D01*
G02X1185753Y109452I715J-1655D01*
G02X1187556Y107649I0J-1803D01*
G01Y104249D01*
G02X1185753Y102446I-1803J0D01*
G02X1185050Y102589I1J1803D01*
G01X1185005Y102608D01*
X1184908Y102601D01*
X1184547Y102375D01*
X1184497Y102291D01*
X1184495Y102242D01*
G02X1182995Y100821I-1500J81D01*
G02Y103825I0J1502D01*
G02X1183436Y103759I1J-1502D01*
G01X1183483Y103744D01*
X1183579Y103762D01*
X1183914Y104023D01*
X1183955Y104112D01*
X1183953Y104161D01*
G02X1183950Y104249I1799J105D01*
G01Y107649D01*
G02X1183954Y107759I1803J-10D01*
G03X1183869Y107935I-200J12D01*
G01X1183769Y108005D01*
G03X1183577Y108025I-114J-164D01*
G37*
G36*
G01X1306648Y989136D02*
G02X1306078Y990314I932J1178D01*
G02X1309082I1502J0D01*
G02X1308498Y989125I-1502J0D01*
G03X1308528Y988471I245J-316D01*
G02X1309363Y986951I-966J-1520D01*
G02X1305759I-1802J0D01*
G02X1306611Y988482I1802J0D01*
G03X1306648Y989136I-211J340D01*
G37*
G36*
G01X1280849Y454009D02*
X1280826Y454426D01*
X1280780Y454506D01*
X1280740Y454533D01*
G02X1279935Y456034I997J1501D01*
G02X1283539I1802J0D01*
G02X1282734Y454533I-1802J0D01*
G01X1282694Y454506D01*
X1282648Y454426D01*
X1282625Y454009D01*
X1282662Y453924D01*
X1282700Y453893D01*
G02X1283239Y452740I-964J-1153D01*
G02X1280235I-1502J0D01*
G02X1280774Y453893I1503J0D01*
G01X1280812Y453924D01*
X1280849Y454009D01*
G37*
G36*
G01X1282503Y466541D02*
Y466835D01*
G03X1282438Y466982I-200J-1D01*
G02X1281953Y468088I1017J1105D01*
G02X1284957I1502J0D01*
G02X1284472Y466982I-1502J-1D01*
G03X1284407Y466835I135J-148D01*
G01Y466541D01*
G03X1284472Y466394I200J1D01*
G02X1284957Y465288I-1017J-1105D01*
G02X1281953I-1502J0D01*
G02X1282438Y466394I1502J1D01*
G03X1282503Y466541I-135J148D01*
G37*
G36*
G01X1289137Y468918D02*
X1288801D01*
X1288734Y468893D01*
X1288706Y468869D01*
G02X1287719Y468499I-987J1131D01*
G02Y471503I0J1502D01*
G02X1288706Y471133I0J-1501D01*
G01X1288734Y471109D01*
X1288801Y471084D01*
X1289137D01*
X1289204Y471109D01*
X1289232Y471133D01*
G02X1290219Y471503I987J-1131D01*
G02Y468499I0J-1502D01*
G02X1289232Y468869I0J1501D01*
G01X1289204Y468893D01*
X1289137Y468918D01*
G37*
G36*
G01X1266898Y1158278D02*
X1266681Y1158621D01*
X1266603Y1158669D01*
X1266557Y1158674D01*
G02X1265207Y1160168I152J1494D01*
G02X1268211I1502J0D01*
G02X1268174Y1159835I-1502J-2D01*
G01X1268163Y1159790D01*
X1268184Y1159700D01*
X1268440Y1159384D01*
X1268523Y1159345D01*
X1268569Y1159346D01*
X1268593D01*
G02X1266791Y1157544I0J-1802D01*
G02X1266893Y1158143I1802J1D01*
G01X1266909Y1158186D01*
X1266898Y1158278D01*
G37*
G36*
G01X1272709Y1157955D02*
G02X1272120Y1157844I-588J1500D01*
G02X1273732Y1159455I1J1611D01*
G02X1273731Y1159415I-1611J20D01*
G03X1274298Y1159041I400J-10D01*
G02X1275050Y1159206I753J-1637D01*
G02X1273248Y1157404I0J-1802D01*
G02X1273254Y1157550I1802J-1D01*
G03X1272709Y1157955I-399J33D01*
G37*
G36*
G01X1266667Y84108D02*
Y84460D01*
X1266639Y84529D01*
X1266613Y84557D01*
G02X1266207Y85584I1096J1027D01*
G02X1269211I1502J0D01*
G02X1268805Y84557I-1502J0D01*
G01X1268779Y84529D01*
X1268751Y84460D01*
Y84108D01*
X1268779Y84039D01*
X1268805Y84011D01*
G02Y81957I-1096J-1027D01*
G01X1268779Y81929D01*
X1268751Y81860D01*
Y81508D01*
X1268779Y81439D01*
X1268805Y81411D01*
G02Y79357I-1096J-1027D01*
G01X1268779Y79329D01*
X1268751Y79260D01*
Y78908D01*
X1268779Y78839D01*
X1268805Y78811D01*
G02Y76757I-1096J-1027D01*
G01X1268779Y76729D01*
X1268751Y76660D01*
Y76308D01*
X1268779Y76239D01*
X1268805Y76211D01*
G02X1269211Y75184I-1096J-1027D01*
G02X1266207I-1502J0D01*
G02X1266613Y76211I1502J0D01*
G01X1266639Y76239D01*
X1266667Y76308D01*
Y76660D01*
X1266639Y76729D01*
X1266613Y76757D01*
G02Y78811I1096J1027D01*
G01X1266639Y78839D01*
X1266667Y78908D01*
Y79260D01*
X1266639Y79329D01*
X1266613Y79357D01*
G02Y81411I1096J1027D01*
G01X1266639Y81439D01*
X1266667Y81508D01*
Y81860D01*
X1266639Y81929D01*
X1266613Y81957D01*
G02Y84011I1096J1027D01*
G01X1266639Y84039D01*
X1266667Y84108D01*
G37*
G36*
G01X1276145Y101516D02*
X1276181Y101900D01*
X1276154Y101981D01*
X1276125Y102013D01*
G02X1275721Y103037I1098J1025D01*
G02X1278725I1502J0D01*
G02X1278258Y101948I-1503J0D01*
G01X1278226Y101918D01*
X1278194Y101839D01*
X1278207Y101454D01*
X1278245Y101377D01*
X1278278Y101350D01*
G02X1278932Y99961I-1148J-1389D01*
G02X1275328I-1802J0D01*
G02X1276068Y101417I1802J0D01*
G01X1276103Y101442D01*
X1276145Y101516D01*
G37*
G36*
G01X1296110Y116195D02*
X1296229Y116168D01*
G03X1296372Y116189I44J195D01*
G02X1297264Y116426I893J-1566D01*
G02X1298156Y116189I-1J-1803D01*
G03X1298299Y116168I99J174D01*
G01X1298418Y116195D01*
G03X1298537Y116274I-44J195D01*
G02X1299760Y116903I1222J-873D01*
G02Y113899I0J-1502D01*
G02X1299528Y113917I0J1502D01*
G01X1299485Y113924D01*
X1299401Y113900D01*
X1299136Y113674D01*
G03X1299066Y113522I130J-152D01*
G01Y112324D01*
G03X1299136Y112172I200J0D01*
G01X1299401Y111946D01*
X1299485Y111922D01*
X1299528Y111929D01*
G02X1299760Y111947I232J-1484D01*
G02Y108943I0J-1502D01*
G02X1298537Y109572I-1J1502D01*
G03X1298418Y109651I-163J-116D01*
G01X1298299Y109678D01*
G03X1298156Y109657I-44J-195D01*
G02X1297264Y109420I-893J1566D01*
G02X1296372Y109657I1J1803D01*
G03X1296229Y109678I-99J-174D01*
G01X1296110Y109651D01*
G03X1295991Y109572I44J-195D01*
G02X1294768Y108943I-1222J873D01*
G02Y111947I0J1502D01*
G02X1295000Y111929I0J-1502D01*
G01X1295043Y111922D01*
X1295127Y111946D01*
X1295392Y112172D01*
G03X1295462Y112324I-130J152D01*
G01Y113522D01*
G03X1295392Y113674I-200J0D01*
G01X1295127Y113900D01*
X1295043Y113924D01*
X1295000Y113917D01*
G02X1294768Y113899I-232J1484D01*
G02Y116903I0J1502D01*
G02X1295991Y116274I1J-1502D01*
G03X1296110Y116195I163J116D01*
G37*
G36*
G01Y130368D02*
X1296229Y130341D01*
G03X1296372Y130362I44J195D01*
G02X1297264Y130598I892J-1566D01*
G02X1298156Y130362I0J-1802D01*
G03X1298299Y130341I99J174D01*
G01X1298418Y130368D01*
G03X1298537Y130447I-44J195D01*
G02X1299760Y131076I1222J-873D01*
G02Y128072I0J-1502D01*
G02X1299528Y128090I0J1502D01*
G01X1299485Y128097D01*
X1299401Y128073D01*
X1299136Y127847D01*
G03X1299066Y127695I130J-152D01*
G01Y126497D01*
G03X1299136Y126345I200J0D01*
G01X1299401Y126119D01*
X1299485Y126095D01*
X1299528Y126102D01*
G02X1299760Y126120I232J-1484D01*
G02Y123116I0J-1502D01*
G02X1298537Y123745I-1J1502D01*
G03X1298418Y123824I-163J-116D01*
G01X1298299Y123851D01*
G03X1298156Y123830I-44J-195D01*
G02X1297264Y123594I-892J1566D01*
G02X1296372Y123830I0J1802D01*
G03X1296229Y123851I-99J-174D01*
G01X1296110Y123824D01*
G03X1295991Y123745I44J-195D01*
G02X1294768Y123116I-1222J873D01*
G02Y126120I0J1502D01*
G02X1295000Y126102I0J-1502D01*
G01X1295043Y126095D01*
X1295127Y126119D01*
X1295392Y126345D01*
G03X1295462Y126497I-130J152D01*
G01Y127695D01*
G03X1295392Y127847I-200J0D01*
G01X1295127Y128073D01*
X1295043Y128097D01*
X1295000Y128090D01*
G02X1294768Y128072I-232J1484D01*
G02Y131076I0J1502D01*
G02X1295991Y130447I1J-1502D01*
G03X1296110Y130368I163J116D01*
G37*
G36*
G01X1268959Y146496D02*
X1268652D01*
G02Y153898I0J3701D01*
G01X1275952D01*
G02Y146496I0J-3701D01*
G01X1275645D01*
G03X1275445Y146296I0J-200D01*
G01Y146236D01*
X1275478Y146186D01*
G02X1269126I-3176J-2091D01*
G01X1269142Y146211D01*
X1269159Y146266D01*
Y146296D01*
G03X1268959Y146496I-200J0D01*
G37*
G36*
G01X1268773Y92655D02*
X1268768Y92709D01*
G02X1268761Y92849I1495J145D01*
G02X1271765I1502J0D01*
G02X1271719Y92481I-1502J1D01*
G01X1271705Y92426D01*
X1271739Y92319D01*
X1272091Y92009D01*
X1272202Y91990D01*
X1272255Y92011D01*
G02X1272809Y92117I554J-1395D01*
G02X1271307Y90615I0J-1502D01*
G02X1271353Y90983I1502J-1D01*
G01X1271367Y91038D01*
X1271333Y91145D01*
X1270981Y91455D01*
X1270870Y91474D01*
X1270817Y91453D01*
G02X1270263Y91347I-554J1395D01*
G02X1269790Y91424I2J1502D01*
G01X1269738Y91441D01*
X1269636Y91420D01*
X1269295Y91124D01*
X1269260Y91026D01*
X1269270Y90972D01*
G02X1269299Y90650I-1773J-322D01*
G02X1267497Y92452I-1802J0D01*
G02X1268211Y92305I1J-1802D01*
G01X1268260Y92283D01*
X1268364Y92295D01*
X1268730Y92560D01*
X1268773Y92655D01*
G37*
G36*
G01X1293527Y100457D02*
G02X1292867Y101701I842J1244D01*
G02X1295871I1502J0D01*
G02X1295211Y100457I-1502J0D01*
G03Y99795I224J-331D01*
G02X1295871Y98551I-842J-1244D01*
G02X1292867I-1502J0D01*
G02X1293527Y99795I1502J0D01*
G03Y100457I-224J331D01*
G37*
G36*
G01X1285939Y108025D02*
G02X1285357Y107908I-581J1385D01*
G02Y110912I0J1502D01*
G02X1286845Y109616I0J-1502D01*
G01X1286851Y109569D01*
X1286904Y109492D01*
X1287263Y109290D01*
X1287356Y109285D01*
X1287400Y109304D01*
G02X1288115Y109452I715J-1655D01*
G02X1289918Y107649I0J-1803D01*
G01Y104249D01*
G02X1288115Y102446I-1803J0D01*
G02X1287412Y102589I1J1803D01*
G01X1287367Y102608D01*
X1287270Y102601D01*
X1286909Y102375D01*
X1286859Y102291D01*
X1286857Y102242D01*
G02X1285357Y100821I-1500J81D01*
G02Y103825I0J1502D01*
G02X1285798Y103759I1J-1502D01*
G01X1285845Y103744D01*
X1285941Y103762D01*
X1286276Y104023D01*
X1286317Y104112D01*
X1286315Y104161D01*
G02X1286312Y104249I1799J105D01*
G01Y107649D01*
G02X1286316Y107759I1803J-10D01*
G03X1286231Y107935I-200J12D01*
G01X1286131Y108005D01*
G03X1285939Y108025I-114J-164D01*
G37*
G36*
G01X1279460Y862685D02*
G02Y866289I0J1802D01*
G01X1279462D01*
G02X1280358Y866050I-1J-1802D01*
G01X1280394Y866029D01*
X1280478Y866020D01*
X1280799Y866122D01*
G03X1280920Y866229I-61J191D01*
G02X1282285Y867104I1365J-627D01*
G02Y864100I0J-1502D01*
G02X1281718Y864212I2J1502D01*
G01X1281716D01*
G03X1281556Y864207I-74J-185D01*
G01X1281288Y864081D01*
G03X1281183Y863959I86J-181D01*
G02X1279460Y862685I-1723J528D01*
G37*
G36*
G01X1279299Y897011D02*
G02Y900615I0J1802D01*
G02X1280637Y900020I0J-1802D01*
G03X1280774Y899954I149J134D01*
G01X1281053Y899937D01*
G03X1281197Y899986I12J200D01*
G02X1282184Y900356I987J-1131D01*
G02Y897352I0J-1502D01*
G02X1281230Y897694I0J1502D01*
G01X1281229Y897695D01*
G03X1281085Y897739I-126J-155D01*
G01X1280766Y897711D01*
X1280697Y897675D01*
X1280671Y897645D01*
G02X1279299Y897011I-1372J1168D01*
G37*
G36*
G01X1346412Y434358D02*
X1346221Y434652D01*
X1346159Y434697D01*
X1346122Y434706D01*
G02X1344981Y436164I361J1458D01*
G02X1347985I1502J0D01*
G02X1347960Y435893I-1502J2D01*
G01X1347954Y435856D01*
X1347968Y435781D01*
X1348159Y435487D01*
X1348221Y435442D01*
X1348258Y435433D01*
G02X1349399Y433975I-361J-1458D01*
G02X1348287Y432525I-1501J0D01*
G01X1348243Y432513D01*
X1348174Y432454D01*
X1348012Y432083D01*
X1348016Y431993D01*
X1348037Y431952D01*
G02X1348245Y431112I-1594J-840D01*
G02X1344641I-1802J0D01*
G02X1346181Y432895I1802J0D01*
G01X1346226Y432902D01*
X1346301Y432952D01*
X1346505Y433302D01*
X1346512Y433391D01*
X1346496Y433434D01*
G02X1346395Y433975I1401J541D01*
G02X1346420Y434246I1502J-2D01*
G01X1346426Y434283D01*
X1346412Y434358D01*
G37*
G36*
G01X1316906Y869017D02*
G02Y866313I0J-1352D01*
G02X1316512Y866372I1J1352D01*
G01X1316483Y866380D01*
X1315490D01*
G03X1315348Y866321I0J-200D01*
G01X1315197Y866170D01*
G03X1315138Y866028I141J-142D01*
G01Y865424D01*
G02X1315107Y865317I-200J0D01*
G01X1314966Y865096D01*
G02X1314797Y865004I-168J108D01*
G01X1314324D01*
G02X1314155Y865097I0J200D01*
G01X1314015Y865317D01*
G02X1313984Y865424I169J107D01*
G01Y866027D01*
G03X1313925Y866169I-200J0D01*
G01X1313347Y866746D01*
G02X1313288Y866888I141J142D01*
G01Y867776D01*
G02X1313347Y867918I200J0D01*
G01X1313974Y868545D01*
G02X1314116Y868604I142J-141D01*
G01X1315005D01*
G02X1315147Y868545I0J-200D01*
G01X1315349Y868343D01*
G03X1315491Y868284I142J141D01*
G01X1315588D01*
G03X1315758Y868378I0J200D01*
G02X1316906Y869017I1148J-712D01*
G37*
G36*
G01X1378548Y845509D02*
G02X1378544Y845619I1348J104D01*
G02X1381248I1352J0D01*
G02X1379923Y844267I-1352J0D01*
G01X1379884Y844266D01*
X1379814Y844237D01*
X1379786Y844209D01*
G03Y843926I141J-142D01*
G01X1379860Y843852D01*
X1379926Y843822D01*
X1379964Y843820D01*
G02X1381248Y842470I-68J-1350D01*
G02X1379896Y841118I-1352J0D01*
G02X1378546Y842402I0J1352D01*
G01X1378544Y842440D01*
X1378514Y842506D01*
X1378329Y842691D01*
G03X1378188Y842750I-142J-141D01*
G01X1377822D01*
G02X1377680Y842808I-1J200D01*
G01X1377104Y843385D01*
G03X1376987Y843442I-141J-142D01*
G01X1376300D01*
X1375938Y843673D01*
Y844368D01*
Y844439D01*
G03X1375868Y844591I-200J0D01*
G02X1375395Y845618I879J1027D01*
G01Y845619D01*
G02X1378099I1352J0D01*
G02X1378095Y845509I-1352J-6D01*
G01X1378094Y845501D01*
Y845492D01*
G03X1378294Y845292I200J0D01*
G01X1378349D01*
G03X1378549Y845492I0J200D01*
G01Y845501D01*
X1378548Y845509D01*
G37*
G36*
G01X1362923Y855820D02*
G03X1363080Y855897I-1J200D01*
G02X1364148Y856420I1068J-829D01*
G02Y853716I0J-1352D01*
G01X1364136D01*
G03X1363998Y853662I-1J-200D01*
G01X1363846Y853519D01*
Y853467D01*
X1363998Y853324D01*
G03X1364136Y853270I137J146D01*
G01X1364148D01*
G02Y850566I0J-1352D01*
G02X1362804Y851775I0J1352D01*
G01X1362800Y851809D01*
X1362771Y851871D01*
X1362746Y851895D01*
G03X1362463I-141J-141D01*
G01X1362369Y851801D01*
X1362340Y851745D01*
X1362335Y851712D01*
G02X1360999Y850566I-1336J206D01*
G02X1359657Y851752I0J1352D01*
G03X1359633Y851825I-198J-25D01*
G01X1359634Y852022D01*
G03X1359659Y852095I-173J100D01*
G02X1360793Y853254I1340J-177D01*
G01X1360826Y853259D01*
X1360882Y853288D01*
X1361244Y853650D01*
G03X1361302Y853791I-142J141D01*
G01Y853936D01*
G02X1361361Y854078I200J0D01*
G01X1361938Y854654D01*
G03X1361996Y854781I-142J141D01*
G01Y855458D01*
X1362226Y855820D01*
X1362921D01*
X1362923D01*
G37*
G36*
G01X1371996Y870512D02*
X1372048D01*
G03X1372248Y870712I0J200D01*
G01Y870726D01*
G02X1372245Y870814I1349J90D01*
G02X1373597Y869462I1352J0D01*
G01X1373585D01*
G03X1373447Y869408I-1J-200D01*
G01X1373294Y869265D01*
Y869214D01*
X1373447Y869071D01*
G03X1373585Y869017I137J146D01*
G01X1373597D01*
G02Y866313I0J-1352D01*
G02X1372529Y866836I0J1352D01*
G03X1372371Y866914I-159J-122D01*
G01X1371673D01*
G03X1371515Y866836I1J-200D01*
G02X1370447Y866313I-1068J829D01*
G02X1369095Y867665I0J1352D01*
G02X1370100Y868972I1352J0D01*
G01X1370126Y868979D01*
X1370171Y869005D01*
X1370312Y869145D01*
G03Y869428I-142J141D01*
G01X1370290Y869450D01*
X1370236Y869478D01*
X1370206Y869484D01*
G02X1369095Y870814I241J1330D01*
G02X1371799I1352J0D01*
G02X1371796Y870726I-1352J2D01*
G01Y870712D01*
G03X1371996Y870512I200J0D01*
G37*
G36*
G01X1416668Y84108D02*
Y84460D01*
X1416640Y84529D01*
X1416614Y84557D01*
G02X1416208Y85584I1096J1027D01*
G02X1419212I1502J0D01*
G02X1418806Y84557I-1502J0D01*
G01X1418780Y84529D01*
X1418752Y84460D01*
Y84108D01*
X1418780Y84039D01*
X1418806Y84011D01*
G02Y81957I-1096J-1027D01*
G01X1418780Y81929D01*
X1418752Y81860D01*
Y81508D01*
X1418780Y81439D01*
X1418806Y81411D01*
G02Y79357I-1096J-1027D01*
G01X1418780Y79329D01*
X1418752Y79260D01*
Y78908D01*
X1418780Y78839D01*
X1418806Y78811D01*
G02Y76757I-1096J-1027D01*
G01X1418780Y76729D01*
X1418752Y76660D01*
Y76308D01*
X1418780Y76239D01*
X1418806Y76211D01*
G02X1419212Y75184I-1096J-1027D01*
G02X1416208I-1502J0D01*
G02X1416614Y76211I1502J0D01*
G01X1416640Y76239D01*
X1416668Y76308D01*
Y76660D01*
X1416640Y76729D01*
X1416614Y76757D01*
G02Y78811I1096J1027D01*
G01X1416640Y78839D01*
X1416668Y78908D01*
Y79260D01*
X1416640Y79329D01*
X1416614Y79357D01*
G02Y81411I1096J1027D01*
G01X1416640Y81439D01*
X1416668Y81508D01*
Y81860D01*
X1416640Y81929D01*
X1416614Y81957D01*
G02Y84011I1096J1027D01*
G01X1416640Y84039D01*
X1416668Y84108D01*
G37*
G36*
G01X1426146Y101516D02*
X1426182Y101900D01*
X1426155Y101981D01*
X1426126Y102013D01*
G02X1425722Y103037I1098J1025D01*
G02X1428726I1502J0D01*
G02X1428259Y101948I-1503J0D01*
G01X1428227Y101918D01*
X1428195Y101839D01*
X1428208Y101454D01*
X1428246Y101377D01*
X1428279Y101350D01*
G02X1428933Y99961I-1148J-1389D01*
G02X1425329I-1802J0D01*
G02X1426069Y101417I1802J0D01*
G01X1426104Y101442D01*
X1426146Y101516D01*
G37*
G36*
G01X1446111Y116195D02*
X1446230Y116168D01*
G03X1446373Y116189I44J195D01*
G02X1447265Y116426I893J-1566D01*
G02X1448157Y116189I-1J-1803D01*
G03X1448300Y116168I99J174D01*
G01X1448419Y116195D01*
G03X1448538Y116274I-44J195D01*
G02X1449761Y116903I1222J-873D01*
G02Y113899I0J-1502D01*
G02X1449529Y113917I0J1502D01*
G01X1449486Y113924D01*
X1449402Y113900D01*
X1449137Y113674D01*
G03X1449068Y113522I131J-151D01*
G01Y112324D01*
G03X1449137Y112172I200J-1D01*
G01X1449402Y111946D01*
X1449486Y111922D01*
X1449529Y111929D01*
G02X1449761Y111947I232J-1484D01*
G02Y108943I0J-1502D01*
G02X1448538Y109572I-1J1502D01*
G03X1448419Y109651I-163J-116D01*
G01X1448300Y109678D01*
G03X1448157Y109657I-44J-195D01*
G02X1447265Y109420I-893J1566D01*
G02X1446373Y109657I1J1803D01*
G03X1446230Y109678I-99J-174D01*
G01X1446111Y109651D01*
G03X1445992Y109572I44J-195D01*
G02X1444769Y108943I-1222J873D01*
G02Y111947I0J1502D01*
G02X1445001Y111929I0J-1502D01*
G01X1445044Y111922D01*
X1445128Y111946D01*
X1445393Y112172D01*
G03X1445462Y112324I-131J151D01*
G01Y113522D01*
G03X1445393Y113674I-200J1D01*
G01X1445128Y113900D01*
X1445044Y113924D01*
X1445001Y113917D01*
G02X1444769Y113899I-232J1484D01*
G02Y116903I0J1502D01*
G02X1445992Y116274I1J-1502D01*
G03X1446111Y116195I163J116D01*
G37*
G36*
G01Y130368D02*
X1446230Y130341D01*
G03X1446373Y130362I44J195D01*
G02X1447265Y130598I892J-1566D01*
G02X1448157Y130362I0J-1802D01*
G03X1448300Y130341I99J174D01*
G01X1448419Y130368D01*
G03X1448538Y130447I-44J195D01*
G02X1449761Y131076I1222J-873D01*
G02Y128072I0J-1502D01*
G02X1449529Y128090I0J1502D01*
G01X1449486Y128097D01*
X1449402Y128073D01*
X1449137Y127847D01*
G03X1449068Y127695I131J-151D01*
G01Y126497D01*
G03X1449137Y126345I200J-1D01*
G01X1449402Y126119D01*
X1449486Y126095D01*
X1449529Y126102D01*
G02X1449761Y126120I232J-1484D01*
G02Y123116I0J-1502D01*
G02X1448538Y123745I-1J1502D01*
G03X1448419Y123824I-163J-116D01*
G01X1448300Y123851D01*
G03X1448157Y123830I-44J-195D01*
G02X1447265Y123594I-892J1566D01*
G02X1446373Y123830I0J1802D01*
G03X1446230Y123851I-99J-174D01*
G01X1446111Y123824D01*
G03X1445992Y123745I44J-195D01*
G02X1444769Y123116I-1222J873D01*
G02Y126120I0J1502D01*
G02X1445001Y126102I0J-1502D01*
G01X1445044Y126095D01*
X1445128Y126119D01*
X1445393Y126345D01*
G03X1445462Y126497I-131J151D01*
G01Y127695D01*
G03X1445393Y127847I-200J1D01*
G01X1445128Y128073D01*
X1445044Y128097D01*
X1445001Y128090D01*
G02X1444769Y128072I-232J1484D01*
G02Y131076I0J1502D01*
G02X1445992Y130447I1J-1502D01*
G03X1446111Y130368I163J116D01*
G37*
G36*
G01X1418960Y146496D02*
X1418653D01*
G02Y153898I0J3701D01*
G01X1425953D01*
G02Y146496I0J-3701D01*
G01X1425646D01*
G03X1425446Y146296I0J-200D01*
G01Y146236D01*
X1425479Y146186D01*
G02X1419127I-3176J-2091D01*
G01X1419143Y146211D01*
X1419160Y146266D01*
Y146296D01*
G03X1418960Y146496I-200J0D01*
G37*
G36*
G01X1418774Y92655D02*
X1418769Y92709D01*
G02X1418762Y92849I1495J145D01*
G02X1421766I1502J0D01*
G02X1421763Y92747I-1502J-7D01*
G01X1421759Y92696D01*
X1421798Y92607D01*
X1422136Y92340D01*
X1422231Y92322D01*
X1422279Y92337D01*
G02X1422810Y92417I531J-1722D01*
G02X1421008Y90615I0J-1802D01*
G02X1421034Y90917I1802J-3D01*
G01X1421042Y90967D01*
X1421012Y91059D01*
X1420703Y91359D01*
X1420610Y91386D01*
X1420560Y91377D01*
G02X1420264Y91347I-299J1472D01*
G02X1419791Y91424I2J1502D01*
G01X1419739Y91441D01*
X1419637Y91420D01*
X1419296Y91124D01*
X1419261Y91026D01*
X1419271Y90972D01*
G02X1419300Y90650I-1773J-322D01*
G02X1417498Y92452I-1802J0D01*
G02X1418212Y92305I1J-1802D01*
G01X1418261Y92283D01*
X1418365Y92295D01*
X1418731Y92560D01*
X1418774Y92655D01*
G37*
G36*
G01X1443528Y100457D02*
G02X1442868Y101701I842J1244D01*
G02X1445872I1502J0D01*
G02X1445212Y100457I-1502J0D01*
G03Y99795I224J-331D01*
G02X1445872Y98551I-842J-1244D01*
G02X1442868I-1502J0D01*
G02X1443528Y99795I1502J0D01*
G03Y100457I-224J331D01*
G37*
G36*
G01X1435940Y108025D02*
G02X1435358Y107908I-581J1385D01*
G02Y110912I0J1502D01*
G02X1436846Y109616I0J-1502D01*
G01X1436852Y109569D01*
X1436905Y109492D01*
X1437264Y109290D01*
X1437357Y109285D01*
X1437401Y109304D01*
G02X1438116Y109452I715J-1655D01*
G02X1439918Y107649I-1J-1803D01*
G01Y104249D01*
G02X1438116Y102446I-1802J-1D01*
G02X1437413Y102589I1J1803D01*
G01X1437368Y102608D01*
X1437271Y102601D01*
X1436910Y102375D01*
X1436860Y102291D01*
X1436858Y102242D01*
G02X1435358Y100821I-1500J81D01*
G02Y103825I0J1502D01*
G02X1435799Y103759I1J-1502D01*
G01X1435846Y103744D01*
X1435942Y103762D01*
X1436277Y104023D01*
X1436318Y104112D01*
X1436316Y104161D01*
G02X1436314Y104249I1800J85D01*
G01Y107649D01*
G02X1436317Y107759I1802J6D01*
G03X1436232Y107935I-200J12D01*
G01X1436132Y108005D01*
G03X1435940Y108025I-114J-164D01*
G37*
G36*
G01X1424012Y486270D02*
G02X1425985Y486271I987J-1131D01*
G03X1425987Y486269I142J140D01*
G03X1426117Y486221I130J152D01*
G01X1426381D01*
G03X1426511Y486269I0J200D01*
G01X1426512Y486270D01*
G02X1427499Y486640I987J-1131D01*
G02X1429001Y485138I0J-1502D01*
G02X1428734Y484283I-1502J0D01*
G01X1428710Y484249D01*
X1428694Y484168D01*
X1428773Y483802D01*
X1428821Y483735D01*
X1428857Y483713D01*
G02X1429586Y482425I-773J-1288D01*
G02X1426582I-1502J0D01*
G02X1426849Y483280I1502J0D01*
G01X1426873Y483314D01*
X1426889Y483395D01*
X1426810Y483761D01*
X1426762Y483828D01*
X1426726Y483850D01*
G02X1426513Y484005I774J1287D01*
G03X1426511Y484007I-142J-140D01*
G03X1426381Y484055I-130J-152D01*
G01X1426117D01*
G03X1425987Y484007I0J-200D01*
G01X1425986Y484006D01*
G02X1424013Y484005I-987J1131D01*
G03X1424011Y484007I-142J-140D01*
G03X1423881Y484055I-130J-152D01*
G01X1423617D01*
G03X1423487Y484007I0J-200D01*
G01X1423486Y484006D01*
G02X1422499Y483636I-987J1131D01*
G02X1421379Y484138I0J1500D01*
G01X1421378Y484139D01*
X1421377Y484140D01*
G03X1421311Y484188I-148J-134D01*
G01X1421271Y484206D01*
X1420929Y484205D01*
G03X1420845Y484187I-1J-200D01*
G01X1420807Y484169D01*
X1420778Y484137D01*
X1420777Y484136D01*
G02X1419650Y483626I-1128J992D01*
G02Y486630I0J1502D01*
G02X1420770Y486128I0J-1500D01*
G01X1420771Y486127D01*
X1420772Y486126D01*
G03X1420838Y486078I148J134D01*
G01X1420878Y486060D01*
X1421220Y486061D01*
G03X1421304Y486079I1J200D01*
G01X1421342Y486097D01*
X1421371Y486129D01*
X1421372Y486130D01*
G02X1422499Y486640I1128J-992D01*
G02X1423485Y486271I0J-1502D01*
G03X1423487Y486269I142J140D01*
G03X1423617Y486221I130J152D01*
G01X1423881D01*
G03X1424011Y486269I0J200D01*
G01X1424012Y486270D01*
G37*
G36*
G01X1436498Y483648D02*
G02X1436129Y484634I1133J986D01*
G02X1439133I1502J0D01*
G02X1438764Y483648I-1502J0D01*
G01X1438763Y483647D01*
X1438762Y483646D01*
G03X1438714Y483516I152J-130D01*
G01Y483252D01*
G03X1438762Y483122I200J0D01*
G01X1438763Y483121D01*
X1438764Y483120D01*
G02X1439133Y482134I-1133J-986D01*
G02X1436129I-1502J0D01*
G02X1436498Y483120I1502J0D01*
G01X1436499Y483121D01*
X1436500Y483122D01*
G03X1436548Y483252I-152J130D01*
G01Y483516D01*
G03X1436500Y483646I-200J0D01*
G01X1436499Y483647D01*
X1436498Y483648D01*
G37*
G36*
G01X1447791Y481087D02*
G02X1448276Y482192I1502J0D01*
G03X1448341Y482340I-135J148D01*
G01Y482632D01*
G03X1448276Y482780I-200J0D01*
G02X1447791Y483885I1017J1105D01*
G01Y483886D01*
G02X1450795I1502J0D01*
G01Y483885D01*
G02X1450310Y482780I-1502J0D01*
G03X1450245Y482632I135J-148D01*
G01Y482340D01*
G03X1450310Y482192I200J0D01*
G02X1450795Y481087I-1017J-1105D01*
G01Y481086D01*
G02X1450426Y480100I-1502J0D01*
G01X1450425Y480099D01*
X1450424Y480098D01*
G03X1450376Y479968I152J-130D01*
G01Y479704D01*
G03X1450424Y479574I200J0D01*
G01X1450425Y479573D01*
X1450426Y479572D01*
G02Y477600I-1132J-986D01*
G01X1450425Y477599D01*
X1450424Y477598D01*
G03X1450376Y477468I152J-130D01*
G01Y477204D01*
G03X1450424Y477074I200J0D01*
G01X1450425Y477073D01*
X1450426Y477072D01*
G02X1450795Y476086I-1133J-986D01*
G02X1447791I-1502J0D01*
G02X1448160Y477072I1502J0D01*
G01X1448161Y477073D01*
X1448162Y477074D01*
G03X1448210Y477204I-152J130D01*
G01Y477468D01*
G03X1448162Y477598I-200J0D01*
G01X1448161Y477599D01*
X1448160Y477600D01*
G02Y479572I1132J986D01*
G01X1448161Y479573D01*
X1448162Y479574D01*
G03X1448210Y479704I-152J130D01*
G01Y479968D01*
G03X1448162Y480098I-200J0D01*
G01X1448161Y480099D01*
X1448160Y480100D01*
G02X1447791Y481086I1133J986D01*
G01Y481087D01*
G37*
G36*
G01X1441312Y480419D02*
G02X1441284Y480705I1474J289D01*
G02X1442786Y482207I1502J0D01*
G01X1442787D01*
G02X1443892Y481722I0J-1502D01*
G03X1444040Y481657I148J135D01*
G01X1444332D01*
G03X1444480Y481722I0J200D01*
G02X1445585Y482207I1105J-1017D01*
G01X1445586D01*
G02Y479203I0J-1502D01*
G01X1445585D01*
G02X1444480Y479688I0J1502D01*
G03X1444332Y479753I-148J-135D01*
G01X1444040D01*
G03X1443892Y479688I0J-200D01*
G02X1442910Y479208I-1105J1017D01*
G01X1442867Y479204D01*
X1442793Y479164D01*
X1442587Y478891D01*
G03X1442550Y478734I159J-120D01*
G01Y478733D01*
Y478732D01*
G02X1442578Y478446I-1474J-289D01*
G02X1442209Y477460I-1502J0D01*
G01X1442208Y477459D01*
X1442207Y477458D01*
G03X1442159Y477328I152J-130D01*
G01Y477064D01*
G03X1442207Y476934I200J0D01*
G01X1442208Y476933D01*
X1442209Y476932D01*
G02X1442578Y475946I-1133J-986D01*
G02X1439574I-1502J0D01*
G02X1439943Y476932I1502J0D01*
G01X1439944Y476933D01*
X1439945Y476934D01*
G03X1439993Y477064I-152J130D01*
G01Y477328D01*
G03X1439945Y477458I-200J0D01*
G01X1439944Y477459D01*
X1439943Y477460D01*
G02X1439574Y478446I1133J986D01*
G02X1440952Y479943I1502J0D01*
G01X1440995Y479947D01*
X1441069Y479987D01*
X1441275Y480260D01*
G03X1441312Y480417I-159J120D01*
G01Y480418D01*
Y480419D01*
G37*
G36*
G01X1425251Y477639D02*
G02X1424882Y478625I1133J986D01*
G02X1427886I1502J0D01*
G02X1427517Y477639I-1502J0D01*
G01X1427516Y477638D01*
X1427515Y477637D01*
G03X1427467Y477507I152J-130D01*
G01Y477243D01*
G03X1427515Y477113I200J0D01*
G01X1427516Y477112D01*
X1427517Y477111D01*
G02X1427886Y476125I-1133J-986D01*
G02X1424882I-1502J0D01*
G02X1425251Y477111I1502J0D01*
G01X1425252Y477112D01*
X1425253Y477113D01*
G03X1425301Y477243I-152J130D01*
G01Y477507D01*
G03X1425253Y477637I-200J0D01*
G01X1425252Y477638D01*
X1425251Y477639D01*
G37*
G36*
G01X1414865Y493904D02*
G03X1415009Y494518I-168J363D01*
G02X1414610Y495649I1403J1131D01*
G02X1418216I1803J0D01*
G02X1417171Y494013I-1803J0D01*
G03X1417027Y493399I168J-363D01*
G02X1417426Y492268I-1403J-1131D01*
G02X1413820I-1803J0D01*
G02X1414865Y493904I1803J0D01*
G37*
G36*
G01X1473610Y1406992D02*
G02Y1409998I0J1503D01*
G01X1477010D01*
G02Y1406992I0J-1503D01*
G01X1473610D01*
G37*
G36*
G01Y1395080D02*
G02Y1398086I0J1503D01*
G01X1477010D01*
G02Y1395080I0J-1503D01*
G01X1473610D01*
G37*
G36*
G01X1485850Y1406992D02*
G02Y1409998I0J1503D01*
G01X1489250D01*
G02Y1406992I0J-1503D01*
G01X1485850D01*
G37*
G36*
G01Y1395080D02*
G02Y1398086I0J1503D01*
G01X1489250D01*
G02Y1395080I0J-1503D01*
G01X1485850D01*
G37*
G36*
G01X1498090D02*
G02Y1398086I0J1503D01*
G01X1501490D01*
G02Y1395080I0J-1503D01*
G01X1498090D01*
G37*
G36*
G01Y1406992D02*
G02Y1409998I0J1503D01*
G01X1501490D01*
G02Y1406992I0J-1503D01*
G01X1498090D01*
G37*
G36*
G01X1510330D02*
G02Y1409998I0J1503D01*
G01X1513730D01*
G02Y1406992I0J-1503D01*
G01X1510330D01*
G37*
G36*
G01Y1395080D02*
G02Y1398086I0J1503D01*
G01X1513730D01*
G02Y1395080I0J-1503D01*
G01X1510330D01*
G37*
G36*
G01X1522570Y1406992D02*
G02Y1409998I0J1503D01*
G01X1525970D01*
G02Y1406992I0J-1503D01*
G01X1522570D01*
G37*
G36*
G01Y1395080D02*
G02Y1398086I0J1503D01*
G01X1525970D01*
G02Y1395080I0J-1503D01*
G01X1522570D01*
G37*
G36*
G01X1534810Y1406992D02*
G02Y1409998I0J1503D01*
G01X1538210D01*
G02Y1406992I0J-1503D01*
G01X1534810D01*
G37*
G36*
G01Y1395080D02*
G02Y1398086I0J1503D01*
G01X1538210D01*
G02Y1395080I0J-1503D01*
G01X1534810D01*
G37*
G36*
G01X1547050Y1406992D02*
G02Y1409998I0J1503D01*
G01X1550450D01*
G02Y1406992I0J-1503D01*
G01X1547050D01*
G37*
G36*
G01Y1395080D02*
G02Y1398086I0J1503D01*
G01X1550450D01*
G02Y1395080I0J-1503D01*
G01X1547050D01*
G37*
G36*
G01X1559290Y1406992D02*
G02Y1409998I0J1503D01*
G01X1562690D01*
G02Y1406992I0J-1503D01*
G01X1559290D01*
G37*
G36*
G01Y1395080D02*
G02Y1398086I0J1503D01*
G01X1562690D01*
G02Y1395080I0J-1503D01*
G01X1559290D01*
G37*
G36*
G01X1571530Y1406992D02*
G02Y1409998I0J1503D01*
G01X1574930D01*
G02Y1406992I0J-1503D01*
G01X1571530D01*
G37*
G36*
G01Y1395080D02*
G02Y1398086I0J1503D01*
G01X1574930D01*
G02Y1395080I0J-1503D01*
G01X1571530D01*
G37*
G36*
G01X1583770Y1406992D02*
G02Y1409998I0J1503D01*
G01X1587170D01*
G02Y1406992I0J-1503D01*
G01X1583770D01*
G37*
G36*
G01Y1395080D02*
G02Y1398086I0J1503D01*
G01X1587170D01*
G02Y1395080I0J-1503D01*
G01X1583770D01*
G37*
G36*
G01Y1382794D02*
G02Y1385800I0J1503D01*
G01X1587170D01*
G02Y1382794I0J-1503D01*
G01X1583770D01*
G37*
G36*
G01Y1370882D02*
G02Y1373888I0J1503D01*
G01X1587170D01*
G02Y1370882I0J-1503D01*
G01X1583770D01*
G37*
G36*
G01X1571530D02*
G02Y1373888I0J1503D01*
G01X1574930D01*
G02Y1370882I0J-1503D01*
G01X1571530D01*
G37*
G36*
G01Y1382794D02*
G02Y1385800I0J1503D01*
G01X1574930D01*
G02Y1382794I0J-1503D01*
G01X1571530D01*
G37*
G36*
G01X1559290D02*
G02Y1385800I0J1503D01*
G01X1562690D01*
G02Y1382794I0J-1503D01*
G01X1559290D01*
G37*
G36*
G01Y1370882D02*
G02Y1373888I0J1503D01*
G01X1562690D01*
G02Y1370882I0J-1503D01*
G01X1559290D01*
G37*
G36*
G01X1547050D02*
G02Y1373888I0J1503D01*
G01X1550450D01*
G02Y1370882I0J-1503D01*
G01X1547050D01*
G37*
G36*
G01Y1382794D02*
G02Y1385800I0J1503D01*
G01X1550450D01*
G02Y1382794I0J-1503D01*
G01X1547050D01*
G37*
G36*
G01X1534810D02*
G02Y1385800I0J1503D01*
G01X1538210D01*
G02Y1382794I0J-1503D01*
G01X1534810D01*
G37*
G36*
G01Y1370882D02*
G02Y1373888I0J1503D01*
G01X1538210D01*
G02Y1370882I0J-1503D01*
G01X1534810D01*
G37*
G36*
G01X1522570D02*
G02Y1373888I0J1503D01*
G01X1525970D01*
G02Y1370882I0J-1503D01*
G01X1522570D01*
G37*
G36*
G01Y1382794D02*
G02Y1385800I0J1503D01*
G01X1525970D01*
G02Y1382794I0J-1503D01*
G01X1522570D01*
G37*
G36*
G01X1510330D02*
G02Y1385800I0J1503D01*
G01X1513730D01*
G02Y1382794I0J-1503D01*
G01X1510330D01*
G37*
G36*
G01Y1370882D02*
G02Y1373888I0J1503D01*
G01X1513730D01*
G02Y1370882I0J-1503D01*
G01X1510330D01*
G37*
G36*
G01X1498090Y1382794D02*
G02Y1385800I0J1503D01*
G01X1501490D01*
G02Y1382794I0J-1503D01*
G01X1498090D01*
G37*
G36*
G01Y1370882D02*
G02Y1373888I0J1503D01*
G01X1501490D01*
G02Y1370882I0J-1503D01*
G01X1498090D01*
G37*
G36*
G01X1485850D02*
G02Y1373888I0J1503D01*
G01X1489250D01*
G02Y1370882I0J-1503D01*
G01X1485850D01*
G37*
G36*
G01Y1382794D02*
G02Y1385800I0J1503D01*
G01X1489250D01*
G02Y1382794I0J-1503D01*
G01X1485850D01*
G37*
G36*
G01X1473610D02*
G02Y1385800I0J1503D01*
G01X1477010D01*
G02Y1382794I0J-1503D01*
G01X1473610D01*
G37*
G36*
G01Y1370882D02*
G02Y1373888I0J1503D01*
G01X1477010D01*
G02Y1370882I0J-1503D01*
G01X1473610D01*
G37*
G36*
G01X1461370Y1382794D02*
G02Y1385800I0J1503D01*
G01X1464770D01*
G02Y1382794I0J-1503D01*
G01X1461370D01*
G37*
G36*
G01Y1370882D02*
G02Y1373888I0J1503D01*
G01X1464770D01*
G02Y1370882I0J-1503D01*
G01X1461370D01*
G37*
G36*
G01Y1358596D02*
G02Y1361602I0J1503D01*
G01X1464770D01*
G02Y1358596I0J-1503D01*
G01X1461370D01*
G37*
G36*
G01Y1346684D02*
G02Y1349690I0J1503D01*
G01X1464770D01*
G02Y1346684I0J-1503D01*
G01X1461370D01*
G37*
G36*
G01X1473610D02*
G02Y1349690I0J1503D01*
G01X1477010D01*
G02Y1346684I0J-1503D01*
G01X1473610D01*
G37*
G36*
G01Y1358596D02*
G02Y1361602I0J1503D01*
G01X1477010D01*
G02Y1358596I0J-1503D01*
G01X1473610D01*
G37*
G36*
G01X1485850D02*
G02Y1361602I0J1503D01*
G01X1489250D01*
G02Y1358596I0J-1503D01*
G01X1485850D01*
G37*
G36*
G01Y1346684D02*
G02Y1349690I0J1503D01*
G01X1489250D01*
G02Y1346684I0J-1503D01*
G01X1485850D01*
G37*
G36*
G01X1498090D02*
G02Y1349690I0J1503D01*
G01X1501490D01*
G02Y1346684I0J-1503D01*
G01X1498090D01*
G37*
G36*
G01Y1358596D02*
G02Y1361602I0J1503D01*
G01X1501490D01*
G02Y1358596I0J-1503D01*
G01X1498090D01*
G37*
G36*
G01X1510330D02*
G02Y1361602I0J1503D01*
G01X1513730D01*
G02Y1358596I0J-1503D01*
G01X1510330D01*
G37*
G36*
G01Y1346684D02*
G02Y1349690I0J1503D01*
G01X1513730D01*
G02Y1346684I0J-1503D01*
G01X1510330D01*
G37*
G36*
G01X1534810Y1358596D02*
G02Y1361602I0J1503D01*
G01X1538210D01*
G02Y1358596I0J-1503D01*
G01X1534810D01*
G37*
G36*
G01Y1346684D02*
G02Y1349690I0J1503D01*
G01X1538210D01*
G02Y1346684I0J-1503D01*
G01X1534810D01*
G37*
G36*
G01X1547050D02*
G02Y1349690I0J1503D01*
G01X1550450D01*
G02Y1346684I0J-1503D01*
G01X1547050D01*
G37*
G36*
G01Y1358596D02*
G02Y1361602I0J1503D01*
G01X1550450D01*
G02Y1358596I0J-1503D01*
G01X1547050D01*
G37*
G36*
G01X1559290D02*
G02Y1361602I0J1503D01*
G01X1562690D01*
G02Y1358596I0J-1503D01*
G01X1559290D01*
G37*
G36*
G01Y1346684D02*
G02Y1349690I0J1503D01*
G01X1562690D01*
G02Y1346684I0J-1503D01*
G01X1559290D01*
G37*
G36*
G01X1571530Y1358596D02*
G02Y1361602I0J1503D01*
G01X1574930D01*
G02Y1358596I0J-1503D01*
G01X1571530D01*
G37*
G36*
G01Y1346684D02*
G02Y1349690I0J1503D01*
G01X1574930D01*
G02Y1346684I0J-1503D01*
G01X1571530D01*
G37*
G36*
G01X1583770Y1358596D02*
G02Y1361602I0J1503D01*
G01X1587170D01*
G02Y1358596I0J-1503D01*
G01X1583770D01*
G37*
G36*
G01Y1346684D02*
G02Y1349690I0J1503D01*
G01X1587170D01*
G02Y1346684I0J-1503D01*
G01X1583770D01*
G37*
G36*
G01X1623638Y1406992D02*
G02Y1409998I0J1503D01*
G01X1627038D01*
G02Y1406992I0J-1503D01*
G01X1623638D01*
G37*
G36*
G01Y1395080D02*
G02Y1398086I0J1503D01*
G01X1627038D01*
G02Y1395080I0J-1503D01*
G01X1623638D01*
G37*
G36*
G01X1635878Y1406992D02*
G02Y1409998I0J1503D01*
G01X1639278D01*
G02Y1406992I0J-1503D01*
G01X1635878D01*
G37*
G36*
G01X1648118Y1395080D02*
G02Y1398086I0J1503D01*
G01X1651518D01*
G02Y1395080I0J-1503D01*
G01X1648118D01*
G37*
G36*
G01Y1406992D02*
G02Y1409998I0J1503D01*
G01X1651518D01*
G02Y1406992I0J-1503D01*
G01X1648118D01*
G37*
G36*
G01X1660358D02*
G02Y1409998I0J1503D01*
G01X1663758D01*
G02Y1406992I0J-1503D01*
G01X1660358D01*
G37*
G36*
G01X1672598D02*
G02Y1409998I0J1503D01*
G01X1675998D01*
G02Y1406992I0J-1503D01*
G01X1672598D01*
G37*
G36*
G01Y1395080D02*
G02Y1398086I0J1503D01*
G01X1675998D01*
G02Y1395080I0J-1503D01*
G01X1672598D01*
G37*
G36*
G01X1684838Y1406992D02*
G02Y1409998I0J1503D01*
G01X1688238D01*
G02Y1406992I0J-1503D01*
G01X1684838D01*
G37*
G36*
G01Y1395080D02*
G02Y1398086I0J1503D01*
G01X1688238D01*
G02Y1395080I0J-1503D01*
G01X1684838D01*
G37*
G36*
G01X1697078D02*
G02Y1398086I0J1503D01*
G01X1700478D01*
G02Y1395080I0J-1503D01*
G01X1697078D01*
G37*
G36*
G01Y1406992D02*
G02Y1409998I0J1503D01*
G01X1700478D01*
G02Y1406992I0J-1503D01*
G01X1697078D01*
G37*
G36*
G01X1709318D02*
G02Y1409998I0J1503D01*
G01X1712718D01*
G02Y1406992I0J-1503D01*
G01X1709318D01*
G37*
G36*
G01Y1395080D02*
G02Y1398086I0J1503D01*
G01X1712718D01*
G02Y1395080I0J-1503D01*
G01X1709318D01*
G37*
G36*
G01X1721558Y1406992D02*
G02Y1409998I0J1503D01*
G01X1724958D01*
G02Y1406992I0J-1503D01*
G01X1721558D01*
G37*
G36*
G01Y1395080D02*
G02Y1398086I0J1503D01*
G01X1724958D01*
G02Y1395080I0J-1503D01*
G01X1721558D01*
G37*
G36*
G01X1733798Y1406992D02*
G02Y1409998I0J1503D01*
G01X1737198D01*
G02Y1406992I0J-1503D01*
G01X1733798D01*
G37*
G36*
G01Y1395080D02*
G02Y1398086I0J1503D01*
G01X1737198D01*
G02Y1395080I0J-1503D01*
G01X1733798D01*
G37*
G36*
G01Y1382794D02*
G02Y1385800I0J1503D01*
G01X1737198D01*
G02Y1382794I0J-1503D01*
G01X1733798D01*
G37*
G36*
G01Y1370882D02*
G02Y1373888I0J1503D01*
G01X1737198D01*
G02Y1370882I0J-1503D01*
G01X1733798D01*
G37*
G36*
G01X1721558D02*
G02Y1373888I0J1503D01*
G01X1724958D01*
G02Y1370882I0J-1503D01*
G01X1721558D01*
G37*
G36*
G01Y1382794D02*
G02Y1385800I0J1503D01*
G01X1724958D01*
G02Y1382794I0J-1503D01*
G01X1721558D01*
G37*
G36*
G01X1709318D02*
G02Y1385800I0J1503D01*
G01X1712718D01*
G02Y1382794I0J-1503D01*
G01X1709318D01*
G37*
G36*
G01Y1370882D02*
G02Y1373888I0J1503D01*
G01X1712718D01*
G02Y1370882I0J-1503D01*
G01X1709318D01*
G37*
G36*
G01X1697078Y1382794D02*
G02Y1385800I0J1503D01*
G01X1700478D01*
G02Y1382794I0J-1503D01*
G01X1697078D01*
G37*
G36*
G01X1684838D02*
G02Y1385800I0J1503D01*
G01X1688238D01*
G02Y1382794I0J-1503D01*
G01X1684838D01*
G37*
G36*
G01X1672598D02*
G02Y1385800I0J1503D01*
G01X1675998D01*
G02Y1382794I0J-1503D01*
G01X1672598D01*
G37*
G36*
G01Y1370882D02*
G02Y1373888I0J1503D01*
G01X1675998D01*
G02Y1370882I0J-1503D01*
G01X1672598D01*
G37*
G36*
G01X1660358Y1382794D02*
G02Y1385800I0J1503D01*
G01X1663758D01*
G02Y1382794I0J-1503D01*
G01X1660358D01*
G37*
G36*
G01Y1370882D02*
G02Y1373888I0J1503D01*
G01X1663758D01*
G02Y1370882I0J-1503D01*
G01X1660358D01*
G37*
G36*
G01X1648118D02*
G02Y1373888I0J1503D01*
G01X1651518D01*
G02Y1370882I0J-1503D01*
G01X1648118D01*
G37*
G36*
G01Y1382794D02*
G02Y1385800I0J1503D01*
G01X1651518D01*
G02Y1382794I0J-1503D01*
G01X1648118D01*
G37*
G36*
G01X1635878Y1370882D02*
G02Y1373888I0J1503D01*
G01X1639278D01*
G02Y1370882I0J-1503D01*
G01X1635878D01*
G37*
G36*
G01X1623638D02*
G02Y1373888I0J1503D01*
G01X1627038D01*
G02Y1370882I0J-1503D01*
G01X1623638D01*
G37*
G36*
G01Y1382794D02*
G02Y1385800I0J1503D01*
G01X1627038D01*
G02Y1382794I0J-1503D01*
G01X1623638D01*
G37*
G36*
G01X1611398D02*
G02Y1385800I0J1503D01*
G01X1614798D01*
G02Y1382794I0J-1503D01*
G01X1611398D01*
G37*
G36*
G01Y1370882D02*
G02Y1373888I0J1503D01*
G01X1614798D01*
G02Y1370882I0J-1503D01*
G01X1611398D01*
G37*
G36*
G01Y1358596D02*
G02Y1361602I0J1503D01*
G01X1614798D01*
G02Y1358596I0J-1503D01*
G01X1611398D01*
G37*
G36*
G01Y1346684D02*
G02Y1349690I0J1503D01*
G01X1614798D01*
G02Y1346684I0J-1503D01*
G01X1611398D01*
G37*
G36*
G01X1623638D02*
G02Y1349690I0J1503D01*
G01X1627038D01*
G02Y1346684I0J-1503D01*
G01X1623638D01*
G37*
G36*
G01Y1358596D02*
G02Y1361602I0J1503D01*
G01X1627038D01*
G02Y1358596I0J-1503D01*
G01X1623638D01*
G37*
G36*
G01X1635878D02*
G02Y1361602I0J1503D01*
G01X1639278D01*
G02Y1358596I0J-1503D01*
G01X1635878D01*
G37*
G36*
G01Y1346684D02*
G02Y1349690I0J1503D01*
G01X1639278D01*
G02Y1346684I0J-1503D01*
G01X1635878D01*
G37*
G36*
G01X1648118D02*
G02Y1349690I0J1503D01*
G01X1651518D01*
G02Y1346684I0J-1503D01*
G01X1648118D01*
G37*
G36*
G01Y1358596D02*
G02Y1361602I0J1503D01*
G01X1651518D01*
G02Y1358596I0J-1503D01*
G01X1648118D01*
G37*
G36*
G01X1660358D02*
G02Y1361602I0J1503D01*
G01X1663758D01*
G02Y1358596I0J-1503D01*
G01X1660358D01*
G37*
G36*
G01Y1346684D02*
G02Y1349690I0J1503D01*
G01X1663758D01*
G02Y1346684I0J-1503D01*
G01X1660358D01*
G37*
G36*
G01X1672598D02*
G02Y1349690I0J1503D01*
G01X1675998D01*
G02Y1346684I0J-1503D01*
G01X1672598D01*
G37*
G36*
G01Y1358596D02*
G02Y1361602I0J1503D01*
G01X1675998D01*
G02Y1358596I0J-1503D01*
G01X1672598D01*
G37*
G36*
G01X1684838D02*
G02Y1361602I0J1503D01*
G01X1688238D01*
G02Y1358596I0J-1503D01*
G01X1684838D01*
G37*
G36*
G01Y1346684D02*
G02Y1349690I0J1503D01*
G01X1688238D01*
G02Y1346684I0J-1503D01*
G01X1684838D01*
G37*
G36*
G01X1697078D02*
G02Y1349690I0J1503D01*
G01X1700478D01*
G02Y1346684I0J-1503D01*
G01X1697078D01*
G37*
G36*
G01Y1358596D02*
G02Y1361602I0J1503D01*
G01X1700478D01*
G02Y1358596I0J-1503D01*
G01X1697078D01*
G37*
G36*
G01X1709318D02*
G02Y1361602I0J1503D01*
G01X1712718D01*
G02Y1358596I0J-1503D01*
G01X1709318D01*
G37*
G36*
G01Y1346684D02*
G02Y1349690I0J1503D01*
G01X1712718D01*
G02Y1346684I0J-1503D01*
G01X1709318D01*
G37*
G36*
G01X1721558D02*
G02Y1349690I0J1503D01*
G01X1724958D01*
G02Y1346684I0J-1503D01*
G01X1721558D01*
G37*
G36*
G01Y1358596D02*
G02Y1361602I0J1503D01*
G01X1724958D01*
G02Y1358596I0J-1503D01*
G01X1721558D01*
G37*
G36*
G01X1733798D02*
G02Y1361602I0J1503D01*
G01X1737198D01*
G02Y1358596I0J-1503D01*
G01X1733798D01*
G37*
G36*
G01Y1346684D02*
G02Y1349690I0J1503D01*
G01X1737198D01*
G02Y1346684I0J-1503D01*
G01X1733798D01*
G37*
G36*
G01X1522570D02*
G02Y1349690I0J1503D01*
G01X1525970D01*
G02Y1346684I0J-1503D01*
G01X1522570D01*
G37*
G36*
G01Y1358596D02*
G02Y1361602I0J1503D01*
G01X1525970D01*
G02Y1358596I0J-1503D01*
G01X1522570D01*
G37*
G36*
G01X1635878Y1395080D02*
G02Y1398086I0J1503D01*
G01X1639278D01*
G02Y1395080I0J-1503D01*
G01X1635878D01*
G37*
G36*
G01X1697078Y1370882D02*
G02Y1373888I0J1503D01*
G01X1700478D01*
G02Y1370882I0J-1503D01*
G01X1697078D01*
G37*
G36*
G01X1684838D02*
G02Y1373888I0J1503D01*
G01X1688238D01*
G02Y1370882I0J-1503D01*
G01X1684838D01*
G37*
G36*
G01X1635878Y1382794D02*
G02Y1385800I0J1503D01*
G01X1639278D01*
G02Y1382794I0J-1503D01*
G01X1635878D01*
G37*
G36*
G01X1660358Y1395080D02*
G02Y1398086I0J1503D01*
G01X1663758D01*
G02Y1395080I0J-1503D01*
G01X1660358D01*
G37*
G36*
G01X1477698Y689616D02*
G03X1477192Y689999I-400J-3D01*
G02X1476794Y689945I-399J1448D01*
G02Y692949I0J1502D01*
G02X1478285Y691627I0J-1502D01*
G03X1478831Y691303I397J47D01*
G02X1479500Y691432I670J-1673D01*
G02Y687828I0J-1802D01*
G02X1477698Y689616I0J1802D01*
G37*
G36*
G01X1472898Y708083D02*
X1472822Y708478D01*
X1472769Y708549D01*
X1472729Y708571D01*
G02X1471844Y710052I797J1481D01*
G02X1475206I1681J0D01*
G02X1474734Y708883I-1681J-1D01*
G01X1474702Y708850D01*
X1474673Y708766D01*
X1474720Y708367D01*
X1474767Y708292D01*
X1474806Y708267D01*
G02X1475502Y707000I-805J-1267D01*
G02X1472498I-1502J0D01*
G02X1472847Y707962I1502J-1D01*
G01X1472876Y707998D01*
X1472898Y708083D01*
G37*
G36*
G01X1478509Y708124D02*
X1478482Y708153D01*
G02X1477992Y709388I1311J1235D01*
G02X1481596I1802J0D01*
G02X1480831Y707914I-1803J0D01*
G01X1480798Y707891D01*
X1480756Y707825D01*
X1480693Y707467D01*
X1480709Y707392D01*
X1480733Y707358D01*
G02X1481002Y706500I-1234J-858D01*
G02X1479500Y704998I-1502J0D01*
G02X1479024Y705075I-1J1502D01*
G01X1478975Y705092D01*
X1478874Y705073D01*
X1478532Y704790D01*
X1478494Y704693D01*
X1478501Y704642D01*
G02X1478518Y704398I-1785J-247D01*
G02X1476716Y706200I-1802J0D01*
G02X1477439Y706048I-1J-1802D01*
G01X1477487Y706028D01*
X1477590Y706037D01*
X1477956Y706288D01*
X1478002Y706381D01*
X1478000Y706433D01*
G02X1477998Y706500I1500J78D01*
G02X1478466Y707589I1501J0D01*
G01X1478495Y707617D01*
X1478527Y707688D01*
X1478537Y708051D01*
X1478509Y708124D01*
G37*
G36*
G01X1519030Y84108D02*
Y84460D01*
X1519002Y84529D01*
X1518976Y84557D01*
G02X1518570Y85584I1096J1027D01*
G02X1521574I1502J0D01*
G02X1521168Y84557I-1502J0D01*
G01X1521142Y84529D01*
X1521114Y84460D01*
Y84108D01*
X1521142Y84039D01*
X1521168Y84011D01*
G02Y81957I-1096J-1027D01*
G01X1521142Y81929D01*
X1521114Y81860D01*
Y81508D01*
X1521142Y81439D01*
X1521168Y81411D01*
G02Y79357I-1096J-1027D01*
G01X1521142Y79329D01*
X1521114Y79260D01*
Y78908D01*
X1521142Y78839D01*
X1521168Y78811D01*
G02Y76757I-1096J-1027D01*
G01X1521142Y76729D01*
X1521114Y76660D01*
Y76308D01*
X1521142Y76239D01*
X1521168Y76211D01*
G02X1521574Y75184I-1096J-1027D01*
G02X1518570I-1502J0D01*
G02X1518976Y76211I1502J0D01*
G01X1519002Y76239D01*
X1519030Y76308D01*
Y76660D01*
X1519002Y76729D01*
X1518976Y76757D01*
G02Y78811I1096J1027D01*
G01X1519002Y78839D01*
X1519030Y78908D01*
Y79260D01*
X1519002Y79329D01*
X1518976Y79357D01*
G02Y81411I1096J1027D01*
G01X1519002Y81439D01*
X1519030Y81508D01*
Y81860D01*
X1519002Y81929D01*
X1518976Y81957D01*
G02Y84011I1096J1027D01*
G01X1519002Y84039D01*
X1519030Y84108D01*
G37*
G36*
G01X1528508Y101516D02*
X1528544Y101900D01*
X1528517Y101981D01*
X1528488Y102013D01*
G02X1528084Y103037I1098J1025D01*
G02X1531088I1502J0D01*
G02X1530621Y101948I-1503J0D01*
G01X1530589Y101918D01*
X1530557Y101839D01*
X1530570Y101454D01*
X1530608Y101377D01*
X1530641Y101350D01*
G02X1531295Y99961I-1148J-1389D01*
G02X1527691I-1802J0D01*
G02X1528431Y101417I1802J0D01*
G01X1528466Y101442D01*
X1528508Y101516D01*
G37*
G36*
G01X1548473Y116195D02*
X1548592Y116168D01*
G03X1548735Y116189I44J195D01*
G02X1549627Y116426I893J-1566D01*
G02X1550519Y116189I-1J-1803D01*
G03X1550662Y116168I99J174D01*
G01X1550781Y116195D01*
G03X1550900Y116274I-44J195D01*
G02X1552123Y116903I1222J-873D01*
G02Y113899I0J-1502D01*
G02X1551891Y113917I0J1502D01*
G01X1551848Y113924D01*
X1551764Y113900D01*
X1551499Y113674D01*
G03X1551430Y113522I131J-151D01*
G01Y112324D01*
G03X1551499Y112172I200J-1D01*
G01X1551764Y111946D01*
X1551848Y111922D01*
X1551891Y111929D01*
G02X1552123Y111947I232J-1484D01*
G02Y108943I0J-1502D01*
G02X1550900Y109572I-1J1502D01*
G03X1550781Y109651I-163J-116D01*
G01X1550662Y109678D01*
G03X1550519Y109657I-44J-195D01*
G02X1549627Y109420I-893J1566D01*
G02X1548735Y109657I1J1803D01*
G03X1548592Y109678I-99J-174D01*
G01X1548473Y109651D01*
G03X1548354Y109572I44J-195D01*
G02X1547131Y108943I-1222J873D01*
G02Y111947I0J1502D01*
G02X1547363Y111929I0J-1502D01*
G01X1547406Y111922D01*
X1547490Y111946D01*
X1547755Y112172D01*
G03X1547824Y112324I-131J151D01*
G01Y113522D01*
G03X1547755Y113674I-200J1D01*
G01X1547490Y113900D01*
X1547406Y113924D01*
X1547363Y113917D01*
G02X1547131Y113899I-232J1484D01*
G02Y116903I0J1502D01*
G02X1548354Y116274I1J-1502D01*
G03X1548473Y116195I163J116D01*
G37*
G36*
G01Y130368D02*
X1548592Y130341D01*
G03X1548735Y130362I44J195D01*
G02X1549627Y130598I892J-1566D01*
G02X1550519Y130362I0J-1802D01*
G03X1550662Y130341I99J174D01*
G01X1550781Y130368D01*
G03X1550900Y130447I-44J195D01*
G02X1552123Y131076I1222J-873D01*
G02Y128072I0J-1502D01*
G02X1551891Y128090I0J1502D01*
G01X1551848Y128097D01*
X1551764Y128073D01*
X1551499Y127847D01*
G03X1551430Y127695I131J-151D01*
G01Y126497D01*
G03X1551499Y126345I200J-1D01*
G01X1551764Y126119D01*
X1551848Y126095D01*
X1551891Y126102D01*
G02X1552123Y126120I232J-1484D01*
G02Y123116I0J-1502D01*
G02X1550900Y123745I-1J1502D01*
G03X1550781Y123824I-163J-116D01*
G01X1550662Y123851D01*
G03X1550519Y123830I-44J-195D01*
G02X1549627Y123594I-892J1566D01*
G02X1548735Y123830I0J1802D01*
G03X1548592Y123851I-99J-174D01*
G01X1548473Y123824D01*
G03X1548354Y123745I44J-195D01*
G02X1547131Y123116I-1222J873D01*
G02Y126120I0J1502D01*
G02X1547363Y126102I0J-1502D01*
G01X1547406Y126095D01*
X1547490Y126119D01*
X1547755Y126345D01*
G03X1547824Y126497I-131J151D01*
G01Y127695D01*
G03X1547755Y127847I-200J1D01*
G01X1547490Y128073D01*
X1547406Y128097D01*
X1547363Y128090D01*
G02X1547131Y128072I-232J1484D01*
G02Y131076I0J1502D01*
G02X1548354Y130447I1J-1502D01*
G03X1548473Y130368I163J116D01*
G37*
G36*
G01X1521322Y146496D02*
X1521015D01*
G02Y153898I0J3701D01*
G01X1528315D01*
G02Y146496I0J-3701D01*
G01X1528008D01*
G03X1527808Y146296I0J-200D01*
G01Y146236D01*
X1527841Y146186D01*
G02X1521489I-3176J-2091D01*
G01X1521505Y146211D01*
X1521522Y146266D01*
Y146296D01*
G03X1521322Y146496I-200J0D01*
G37*
G36*
G01X1521136Y92655D02*
X1521131Y92709D01*
G02X1521124Y92849I1495J145D01*
G02X1524128I1502J0D01*
G02X1524125Y92747I-1502J-7D01*
G01X1524121Y92696D01*
X1524160Y92607D01*
X1524498Y92340D01*
X1524593Y92322D01*
X1524641Y92337D01*
G02X1525172Y92417I531J-1722D01*
G02X1523370Y90615I0J-1802D01*
G02X1523396Y90917I1802J-3D01*
G01X1523404Y90967D01*
X1523374Y91059D01*
X1523065Y91359D01*
X1522972Y91386D01*
X1522922Y91377D01*
G02X1522626Y91347I-299J1472D01*
G02X1522153Y91424I2J1502D01*
G01X1522101Y91441D01*
X1521999Y91420D01*
X1521658Y91124D01*
X1521623Y91026D01*
X1521633Y90972D01*
G02X1521662Y90650I-1773J-322D01*
G02X1519860Y92452I-1802J0D01*
G02X1520574Y92305I1J-1802D01*
G01X1520623Y92283D01*
X1520727Y92295D01*
X1521093Y92560D01*
X1521136Y92655D01*
G37*
G36*
G01X1545890Y100457D02*
G02X1545230Y101701I842J1244D01*
G02X1548234I1502J0D01*
G02X1547574Y100457I-1502J0D01*
G03Y99795I224J-331D01*
G02X1548234Y98551I-842J-1244D01*
G02X1545230I-1502J0D01*
G02X1545890Y99795I1502J0D01*
G03Y100457I-224J331D01*
G37*
G36*
G01X1538302Y108025D02*
G02X1537720Y107908I-581J1385D01*
G02Y110912I0J1502D01*
G02X1539208Y109616I0J-1502D01*
G01X1539214Y109569D01*
X1539267Y109492D01*
X1539626Y109290D01*
X1539719Y109285D01*
X1539763Y109304D01*
G02X1540478Y109452I715J-1655D01*
G02X1542280Y107649I-1J-1803D01*
G01Y104249D01*
G02X1540478Y102446I-1802J-1D01*
G02X1539775Y102589I1J1803D01*
G01X1539730Y102608D01*
X1539633Y102601D01*
X1539272Y102375D01*
X1539222Y102291D01*
X1539220Y102242D01*
G02X1537720Y100821I-1500J81D01*
G02Y103825I0J1502D01*
G02X1538161Y103759I1J-1502D01*
G01X1538208Y103744D01*
X1538304Y103762D01*
X1538639Y104023D01*
X1538680Y104112D01*
X1538678Y104161D01*
G02X1538676Y104249I1800J85D01*
G01Y107649D01*
G02X1538679Y107759I1802J6D01*
G03X1538594Y107935I-200J12D01*
G01X1538494Y108005D01*
G03X1538302Y108025I-114J-164D01*
G37*
G36*
G01X1785764Y817380D02*
X1777989Y825155D01*
G02X1777402Y826570I1415J1416D01*
G02X1779404Y828572I2002J0D01*
G02X1780819Y827985I-1J-2002D01*
G01X1787949Y820855D01*
G03X1788091Y820796I142J141D01*
G01X1791041D01*
G02Y816794I0J-2001D01*
G01X1787179D01*
G02X1785764Y817380I0J2001D01*
G37*
G36*
G01X1757745Y542083D02*
X1757355Y542071D01*
X1757278Y542034D01*
X1757250Y541999D01*
G02X1756089Y541450I-1161J953D01*
G02Y544454I0J1502D01*
G02X1757193Y543971I0J-1503D01*
G01X1757222Y543939D01*
X1757301Y543905D01*
X1757691Y543917D01*
X1757768Y543954D01*
X1757796Y543989D01*
G02X1758957Y544538I1161J-953D01*
G02Y541534I0J-1502D01*
G02X1757853Y542017I0J1503D01*
G01X1757824Y542049D01*
X1757745Y542083D01*
G37*
G36*
G01X1690779Y549181D02*
X1690485D01*
G03X1690338Y549117I0J-200D01*
G02X1689236Y548635I-1102J1019D01*
G02Y551639I0J1502D01*
G02X1690338Y551157I0J-1501D01*
G03X1690485Y551093I147J136D01*
G01X1690779D01*
G03X1690926Y551157I0J200D01*
G02X1692028Y551639I1102J-1019D01*
G02Y548635I0J-1502D01*
G02X1690926Y549117I0J1501D01*
G03X1690779Y549181I-147J-136D01*
G37*
G36*
G01X1746558Y899314D02*
X1746242D01*
G03X1746085Y899237I1J-200D01*
G02X1744900Y898658I-1185J923D01*
G02Y901662I0J1502D01*
G02X1746085Y901083I0J-1502D01*
G03X1746242Y901006I158J123D01*
G01X1746558D01*
G03X1746715Y901083I-1J200D01*
G02X1747900Y901662I1185J-923D01*
G02Y898658I0J-1502D01*
G02X1746715Y899237I0J1502D01*
G03X1746558Y899314I-158J-123D01*
G37*
G36*
G01X1772943Y929005D02*
Y929321D01*
G03X1772866Y929478I-200J-1D01*
G02X1772287Y930663I923J1185D01*
G02X1775291I1502J0D01*
G02X1774712Y929478I-1502J0D01*
G03X1774635Y929321I123J-158D01*
G01Y929005D01*
G03X1774712Y928848I200J1D01*
G02X1775291Y927663I-923J-1185D01*
G02X1772287I-1502J0D01*
G02X1772866Y928848I1502J0D01*
G03X1772943Y929005I-123J158D01*
G37*
G36*
G01X1781411Y957047D02*
X1781705D01*
G03X1781852Y957112I-1J200D01*
G02X1782958Y957597I1105J-1017D01*
G02X1784064Y957112I1J-1502D01*
G03X1784211Y957047I148J135D01*
G01X1784505D01*
G03X1784652Y957112I-1J200D01*
G02X1785758Y957597I1105J-1017D01*
G02X1787260Y956095I0J-1502D01*
G02X1786775Y954989I-1502J-1D01*
G03X1786710Y954842I135J-148D01*
G01Y954548D01*
G03X1786775Y954401I200J1D01*
G02X1787260Y953295I-1017J-1105D01*
G02X1785758Y951793I-1502J0D01*
G02X1784652Y952278I-1J1502D01*
G03X1784505Y952343I-148J-135D01*
G01X1784211D01*
G03X1784064Y952278I1J-200D01*
G02X1782958Y951793I-1105J1017D01*
G02X1781852Y952278I-1J1502D01*
G03X1781705Y952343I-148J-135D01*
G01X1781411D01*
G03X1781264Y952278I1J-200D01*
G02X1780158Y951793I-1105J1017D01*
G02X1778656Y953295I0J1502D01*
G02X1779141Y954401I1502J1D01*
G03X1779206Y954548I-135J148D01*
G01Y954842D01*
G03X1779141Y954989I-200J-1D01*
G02X1778656Y956095I1017J1105D01*
G02X1780158Y957597I1502J0D01*
G02X1781264Y957112I1J-1502D01*
G03X1781411Y957047I148J135D01*
G37*
G36*
G01X1553290Y1143188D02*
X1552223D01*
X1552197Y1143181D01*
G02X1551870Y1143137I-329J1208D01*
G02Y1145641I0J1252D01*
G02X1552197Y1145597I-2J-1252D01*
G01X1552223Y1145590D01*
X1553292D01*
G02X1553742Y1145139I-1J-451D01*
G01Y1143639D01*
G02X1553290Y1143188I-452J1D01*
G37*
G36*
G01X1564510Y1180590D02*
X1563443D01*
X1563417Y1180583D01*
G02X1563090Y1180539I-329J1208D01*
G02Y1183043I0J1252D01*
G02X1563417Y1182999I-2J-1252D01*
G01X1563443Y1182992D01*
X1564510D01*
G02X1564962Y1182541I1J-451D01*
G01Y1181041D01*
G02X1564510Y1180590I-452J1D01*
G37*
G36*
G01X1561888Y1172890D02*
Y1173957D01*
X1561882Y1173983D01*
G02X1561838Y1174310I1208J329D01*
G02X1564342I1252J0D01*
G02X1564298Y1173983I-1252J2D01*
G01X1564292Y1173957D01*
Y1172890D01*
G02X1563840Y1172438I-452J0D01*
G01X1562340D01*
G02X1561888Y1172890I0J452D01*
G37*
G36*
G01X1621732Y1170923D02*
Y1171990D01*
G02X1622183Y1172442I451J1D01*
G01X1623683D01*
G02X1624134Y1171990I-1J-452D01*
G01Y1170923D01*
X1624141Y1170897D01*
G02X1624185Y1170570I-1208J-329D01*
G02X1621681I-1252J0D01*
G02X1621725Y1170897I1252J-2D01*
G01X1621732Y1170923D01*
G37*
G36*
G01X1614250D02*
Y1171990D01*
G02X1614702Y1172442I452J0D01*
G01X1616202D01*
G02X1616654Y1171990I0J-452D01*
G01Y1170923D01*
X1616660Y1170897D01*
G02X1616704Y1170570I-1208J-329D01*
G02X1614200I-1252J0D01*
G02X1614244Y1170897I1252J-2D01*
G01X1614250Y1170923D01*
G37*
G36*
G01X1606770D02*
Y1171990D01*
G02X1607222Y1172442I452J0D01*
G01X1608722D01*
G02X1609174Y1171990I0J-452D01*
G01Y1170923D01*
X1609180Y1170897D01*
G02X1609224Y1170570I-1208J-329D01*
G02X1606720I-1252J0D01*
G02X1606764Y1170897I1252J-2D01*
G01X1606770Y1170923D01*
G37*
G36*
G01X1595550D02*
Y1171990D01*
G02X1596002Y1172442I452J0D01*
G01X1597502D01*
G02X1597954Y1171990I0J-452D01*
G01Y1170923D01*
X1597960Y1170897D01*
G02X1598004Y1170570I-1208J-329D01*
G02X1595500I-1252J0D01*
G02X1595544Y1170897I1252J-2D01*
G01X1595550Y1170923D01*
G37*
G36*
G01X1588070D02*
Y1171990D01*
G02X1588521Y1172442I451J1D01*
G01X1590021D01*
G02X1590472Y1171990I-1J-452D01*
G01Y1170923D01*
X1590479Y1170897D01*
G02X1590523Y1170570I-1208J-329D01*
G02X1588019I-1252J0D01*
G02X1588063Y1170897I1252J-2D01*
G01X1588070Y1170923D01*
G37*
G36*
G01X1580590D02*
Y1171990D01*
G02X1581041Y1172442I451J1D01*
G01X1582541D01*
G02X1582992Y1171990I-1J-452D01*
G01Y1170923D01*
X1582999Y1170897D01*
G02X1583043Y1170570I-1208J-329D01*
G02X1580539I-1252J0D01*
G02X1580583Y1170897I1252J-2D01*
G01X1580590Y1170923D01*
G37*
G36*
G01X1573110D02*
Y1171990D01*
G02X1573561Y1172442I451J1D01*
G01X1575061D01*
G02X1575512Y1171990I-1J-452D01*
G01Y1170923D01*
X1575519Y1170897D01*
G02X1575563Y1170570I-1208J-329D01*
G02X1573059I-1252J0D01*
G02X1573103Y1170897I1252J-2D01*
G01X1573110Y1170923D01*
G37*
G36*
G01X1565628D02*
Y1171990D01*
G02X1566080Y1172442I452J0D01*
G01X1567580D01*
G02X1568032Y1171990I0J-452D01*
G01Y1170923D01*
X1568038Y1170897D01*
G02X1568082Y1170570I-1208J-329D01*
G02X1565578I-1252J0D01*
G02X1565622Y1170897I1252J-2D01*
G01X1565628Y1170923D01*
G37*
G36*
G01X1612269Y1167952D02*
X1612274D01*
G02X1612610Y1168102I336J-301D01*
G01X1613810D01*
G02X1614262Y1167650I0J-452D01*
G01Y1166150D01*
G02X1613810Y1165698I-452J0D01*
G01X1612610D01*
G02X1612450Y1165728I2J452D01*
G03X1612288Y1165718I-70J-187D01*
G02X1611712Y1165578I-575J1112D01*
G02X1611169Y1165702I0J1251D01*
G03X1611029Y1165715I-87J-180D01*
G02X1610910Y1165698I-123J434D01*
G01X1609710D01*
G02X1609258Y1166150I0J452D01*
G01Y1167650D01*
G02X1609710Y1168102I452J0D01*
G01X1610910D01*
G02X1611145Y1168035I-2J-452D01*
G03X1611313Y1168017I103J171D01*
G02X1611712Y1168082I398J-1187D01*
G02X1612269Y1167952I1J-1252D01*
G37*
G36*
G01X1628173Y1165628D02*
X1627026D01*
X1627000Y1165622D01*
G02X1626673Y1165578I-329J1208D01*
G02Y1168082I0J1252D01*
G02X1627000Y1168038I-2J-1252D01*
G01X1627026Y1168032D01*
X1628173D01*
G02X1628624Y1167580I-1J-452D01*
G01Y1166080D01*
G02X1628173Y1165628I-451J-1D01*
G37*
G36*
G01X1620693D02*
X1619546D01*
X1619520Y1165622D01*
G02X1619193Y1165578I-329J1208D01*
G02Y1168082I0J1252D01*
G02X1619520Y1168038I-2J-1252D01*
G01X1619546Y1168032D01*
X1620693D01*
G02X1621144Y1167580I-1J-452D01*
G01Y1166080D01*
G02X1620693Y1165628I-451J-1D01*
G37*
G36*
G01X1601992D02*
X1600845D01*
X1600819Y1165622D01*
G02X1600492Y1165578I-329J1208D01*
G02Y1168082I0J1252D01*
G02X1600819Y1168038I-2J-1252D01*
G01X1600845Y1168032D01*
X1601992D01*
G02X1602444Y1167580I0J-452D01*
G01Y1166080D01*
G02X1601992Y1165628I-452J0D01*
G37*
G36*
G01X1593412D02*
G02X1593399Y1165629I28J450D01*
G03X1593340Y1165622I-6J-200D01*
G02X1593012Y1165578I-329J1208D01*
G02Y1168082I0J1252D01*
G02X1593340Y1168038I-1J-1252D01*
G03X1593399Y1168031I53J193D01*
G02X1593412Y1168032I41J-449D01*
G01X1594612D01*
G02X1595064Y1167580I0J-452D01*
G01Y1166080D01*
G02X1594612Y1165628I-452J0D01*
G01X1593412D01*
G37*
G36*
G01X1585931D02*
G02X1585918Y1165629I28J450D01*
G03X1585859Y1165622I-6J-200D01*
G02X1585531Y1165578I-329J1208D01*
G02Y1168082I0J1252D01*
G02X1585859Y1168038I-1J-1252D01*
G03X1585918Y1168031I53J193D01*
G02X1585931Y1168032I41J-449D01*
G01X1587131D01*
G02X1587582Y1167580I-1J-452D01*
G01Y1166080D01*
G02X1587131Y1165628I-451J-1D01*
G01X1585931D01*
G37*
G36*
G01X1578451D02*
G02X1578438Y1165629I28J450D01*
G03X1578379Y1165622I-6J-200D01*
G02X1578051Y1165578I-329J1208D01*
G02Y1168082I0J1252D01*
G02X1578379Y1168038I-1J-1252D01*
G03X1578438Y1168031I53J193D01*
G02X1578451Y1168032I41J-449D01*
G01X1579651D01*
G02X1580102Y1167580I-1J-452D01*
G01Y1166080D01*
G02X1579651Y1165628I-451J-1D01*
G01X1578451D01*
G37*
G36*
G01X1570971D02*
G02X1570958Y1165629I28J450D01*
G03X1570899Y1165622I-6J-200D01*
G02X1570571Y1165578I-329J1208D01*
G02Y1168082I0J1252D01*
G02X1570899Y1168038I-1J-1252D01*
G03X1570958Y1168031I53J193D01*
G02X1570971Y1168032I41J-449D01*
G01X1572171D01*
G02X1572622Y1167580I-1J-452D01*
G01Y1166080D01*
G02X1572171Y1165628I-451J-1D01*
G01X1570971D01*
G37*
G36*
G01X1563490D02*
G02X1563477Y1165629I28J450D01*
G03X1563418Y1165622I-6J-200D01*
G02X1563090Y1165578I-329J1208D01*
G02Y1168082I0J1252D01*
G02X1563418Y1168038I-1J-1252D01*
G03X1563477Y1168031I53J193D01*
G02X1563490Y1168032I41J-449D01*
G01X1564690D01*
G02X1565142Y1167580I0J-452D01*
G01Y1166080D01*
G02X1564690Y1165628I-452J0D01*
G01X1563490D01*
G37*
G36*
G01X1611112Y1160891D02*
Y1163691D01*
G02X1611564Y1164142I452J-1D01*
G01X1614764D01*
G02X1615216Y1163691I1J-451D01*
G01Y1161809D01*
G03X1615274Y1161668I200J0D01*
G01X1616196Y1160747D01*
G02X1616501Y1160077I-744J-743D01*
G03X1616528Y1159989I200J13D01*
G02X1616704Y1159350I-1076J-640D01*
G02X1616660Y1159023I-1252J2D01*
G01X1616654Y1158997D01*
Y1157930D01*
G02X1616202Y1157478I-452J0D01*
G01X1614702D01*
G02X1614250Y1157930I0J452D01*
G01Y1158997D01*
X1614244Y1159023D01*
G02X1614200Y1159350I1208J329D01*
G02X1614228Y1159611I1252J-2D01*
G01X1614238Y1159662D01*
X1614210Y1159758D01*
X1613587Y1160381D01*
G03X1613446Y1160440I-142J-141D01*
G01X1611564D01*
G02X1611112Y1160891I-1J451D01*
G37*
G36*
G01X1592412D02*
Y1163691D01*
G02X1592863Y1164142I451J0D01*
G01X1596063D01*
G02X1596514Y1163691I0J-451D01*
G01Y1161809D01*
G03X1596573Y1161668I200J1D01*
G01X1597496Y1160746D01*
G02X1597801Y1160077I-744J-743D01*
G03X1597828Y1159990I199J14D01*
G02X1598004Y1159350I-1076J-640D01*
G02X1597960Y1159023I-1252J2D01*
G01X1597954Y1158997D01*
Y1157930D01*
G02X1597502Y1157478I-452J0D01*
G01X1596002D01*
G02X1595550Y1157930I0J452D01*
G01Y1158997D01*
X1595544Y1159023D01*
G02X1595500Y1159350I1208J329D01*
G02X1595527Y1159611I1252J2D01*
G01X1595538Y1159661D01*
X1595510Y1159757D01*
X1594886Y1160381D01*
G03X1594745Y1160440I-142J-141D01*
G01X1592863D01*
G02X1592412Y1160891I0J451D01*
G37*
G36*
G01X1577450D02*
Y1163691D01*
G02X1577902Y1164142I452J-1D01*
G01X1581102D01*
G02X1581554Y1163691I1J-451D01*
G01Y1161809D01*
G03X1581612Y1161668I200J0D01*
G01X1582074Y1161207D01*
G02X1582301Y1160865I-746J-741D01*
G01X1582491Y1160407D01*
X1582523Y1160366D01*
X1582545Y1160349D01*
G02X1583043Y1159350I-753J-999D01*
G02X1582999Y1159023I-1252J2D01*
G01X1582992Y1158997D01*
Y1157930D01*
G02X1582541Y1157478I-451J-1D01*
G01X1581041D01*
G02X1580590Y1157930I1J452D01*
G01Y1158997D01*
X1580583Y1159023D01*
G02X1580539Y1159350I1208J329D01*
G02X1580551Y1159524I1252J1D01*
G01X1580555Y1159551D01*
X1580548Y1159602D01*
X1580454Y1159831D01*
G03X1580410Y1159896I-185J-78D01*
G01X1579925Y1160381D01*
G03X1579784Y1160440I-142J-141D01*
G01X1577902D01*
G02X1577450Y1160891I-1J451D01*
G37*
G36*
G01X1621732Y1157930D02*
Y1158997D01*
X1621725Y1159023D01*
G02X1621681Y1159350I1208J329D01*
G02X1624185I1252J0D01*
G02X1624141Y1159023I-1252J2D01*
G01X1624134Y1158997D01*
Y1157930D01*
G02X1623683Y1157478I-451J-1D01*
G01X1622183D01*
G02X1621732Y1157930I1J452D01*
G37*
G36*
G01X1606770D02*
Y1158997D01*
X1606764Y1159023D01*
G02X1606720Y1159350I1208J329D01*
G02X1609224I1252J0D01*
G02X1609180Y1159023I-1252J2D01*
G01X1609174Y1158997D01*
Y1157930D01*
G02X1608722Y1157478I-452J0D01*
G01X1607222D01*
G02X1606770Y1157930I0J452D01*
G37*
G36*
G01X1588070D02*
Y1158997D01*
X1588063Y1159023D01*
G02X1588019Y1159350I1208J329D01*
G02X1590523I1252J0D01*
G02X1590479Y1159023I-1252J2D01*
G01X1590472Y1158997D01*
Y1157930D01*
G02X1590021Y1157478I-451J-1D01*
G01X1588521D01*
G02X1588070Y1157930I1J452D01*
G37*
G36*
G01X1573110D02*
Y1158997D01*
X1573103Y1159023D01*
G02X1573059Y1159350I1208J329D01*
G02X1575563I1252J0D01*
G02X1575519Y1159023I-1252J2D01*
G01X1575512Y1158997D01*
Y1157930D01*
G02X1575061Y1157478I-451J-1D01*
G01X1573561D01*
G02X1573110Y1157930I1J452D01*
G37*
G36*
G01X1565628D02*
Y1158997D01*
X1565622Y1159023D01*
G02X1565578Y1159350I1208J329D01*
G02X1568082I1252J0D01*
G02X1568038Y1159023I-1252J2D01*
G01X1568032Y1158997D01*
Y1157930D01*
G02X1567580Y1157478I-452J0D01*
G01X1566080D01*
G02X1565628Y1157930I0J452D01*
G37*
G36*
G01X1561888Y1155963D02*
Y1157030D01*
G02X1562340Y1157482I452J0D01*
G01X1563840D01*
G02X1564292Y1157030I0J-452D01*
G01Y1155963D01*
X1564298Y1155937D01*
G02X1564342Y1155610I-1208J-329D01*
G02X1561838I-1252J0D01*
G02X1561882Y1155937I1252J-2D01*
G01X1561888Y1155963D01*
G37*
G36*
G01X1564510Y1146928D02*
X1563443D01*
X1563417Y1146921D01*
G02X1563090Y1146877I-329J1208D01*
G02Y1149381I0J1252D01*
G02X1563417Y1149337I-2J-1252D01*
G01X1563443Y1149330D01*
X1564510D01*
G02X1564962Y1148879I1J-451D01*
G01Y1147379D01*
G02X1564510Y1146928I-452J1D01*
G37*
G36*
G01X1638219Y1156819D02*
X1638244Y1156812D01*
X1641282D01*
X1641307Y1156819D01*
G02X1641633Y1156862I325J-1209D01*
G02Y1154358I0J-1252D01*
G02X1641307Y1154401I-1J1252D01*
G01X1641282Y1154408D01*
X1638244D01*
X1638219Y1154401D01*
G02X1637893Y1154358I-325J1209D01*
G02Y1156862I0J1252D01*
G02X1638219Y1156819I1J-1252D01*
G37*
G36*
G01X1570917Y1149888D02*
X1570946Y1149902D01*
X1571484Y1150440D01*
G02X1571625Y1150498I141J-142D01*
G01X1638128D01*
G02X1638978Y1150146I0J-1201D01*
G01X1639359Y1149765D01*
G02X1639712Y1148915I-849J-851D01*
G01Y1147879D01*
G02X1639359Y1147029I-1202J1D01*
G01X1638778Y1146448D01*
G02X1637928Y1146096I-850J849D01*
G01X1571931D01*
G02X1571790Y1146154I0J200D01*
G01X1571041Y1146903D01*
X1570938Y1146931D01*
X1570887Y1146917D01*
G02X1570571Y1146877I-314J1212D01*
G02X1569319Y1148129I0J1252D01*
G02X1570257Y1149341I1252J0D01*
G01X1570283Y1149348D01*
X1570329Y1149374D01*
X1570647Y1149693D01*
G02X1570917Y1149888I743J-744D01*
G37*
G36*
G01X1639653Y1180986D02*
X1638113Y1179446D01*
G02X1637972Y1179388I-141J142D01*
G01X1570352D01*
G02X1570211Y1179446I0J200D01*
G01X1568913Y1180744D01*
G02X1568854Y1180885I141J142D01*
G01Y1182662D01*
G02X1568913Y1182803I200J-1D01*
G01X1569718Y1183608D01*
G02X1569859Y1183666I141J-142D01*
G01X1638740D01*
G02X1638881Y1183608I0J-200D01*
G01X1639653Y1182836D01*
G02X1639712Y1182695I-141J-142D01*
G01Y1181127D01*
G02X1639653Y1180986I-200J1D01*
G37*
G36*
G01X1646970Y505454D02*
X1654270D01*
G02Y498050I0J-3702D01*
G01X1646970D01*
G02Y505454I0J3702D01*
G37*
G36*
G01X1628419Y332804D02*
X1628390Y333166D01*
X1628355Y333235D01*
X1628324Y333262D01*
G02X1627800Y334402I978J1140D01*
G02X1630804I1502J0D01*
G02X1630447Y333430I-1502J0D01*
G01X1630421Y333399D01*
X1630397Y333325D01*
X1630426Y332963D01*
X1630461Y332894D01*
X1630492Y332867D01*
G02X1630987Y332022I-978J-1140D01*
G01X1630996Y331976D01*
X1631053Y331902D01*
X1631423Y331722D01*
X1631516D01*
X1631558Y331743D01*
G02X1632230Y331902I673J-1343D01*
G02Y328898I0J-1502D01*
G02X1631587Y329043I1J1502D01*
G01X1631545Y329062D01*
X1631453D01*
X1631089Y328880D01*
X1631033Y328808D01*
X1631024Y328762D01*
G02X1629553Y327565I-1471J305D01*
G02X1628051Y329067I0J1502D01*
G02X1628464Y330102I1503J0D01*
G01X1628491Y330130D01*
X1628520Y330203D01*
X1628514Y330561D01*
X1628484Y330633D01*
X1628456Y330661D01*
G02X1628012Y331727I1058J1066D01*
G02X1628369Y332699I1502J0D01*
G01X1628395Y332730D01*
X1628419Y332804D01*
G37*
G36*
G01X1605453Y342349D02*
X1605142Y342188D01*
X1605093Y342131D01*
X1605080Y342095D01*
G02X1603664Y341094I-1416J501D01*
G02Y344098I0J1502D01*
G02X1604066Y344043I-1J-1502D01*
G01X1604103Y344033D01*
X1604177Y344041D01*
X1604488Y344202D01*
X1604537Y344259D01*
X1604550Y344295D01*
G02X1605966Y345296I1416J-501D01*
G02Y342292I0J-1502D01*
G02X1605564Y342347I1J1502D01*
G01X1605527Y342357D01*
X1605453Y342349D01*
G37*
G36*
G01X1635448Y344124D02*
X1635436Y344464D01*
X1635408Y344531D01*
X1635382Y344557D01*
G02X1634966Y345595I1087J1038D01*
G02X1637970I1502J0D01*
G02X1637627Y344640I-1501J0D01*
G01X1637604Y344612D01*
X1637581Y344543D01*
X1637593Y344203D01*
X1637621Y344136D01*
X1637647Y344110D01*
G02X1638063Y343072I-1087J-1038D01*
G02X1635059I-1502J0D01*
G02X1635402Y344027I1501J0D01*
G01X1635425Y344055D01*
X1635448Y344124D01*
G37*
G36*
G01X1597871Y374692D02*
X1597480Y374698D01*
X1597402Y374664D01*
X1597372Y374631D01*
G02X1596253Y374131I-1119J1002D01*
G02Y377135I0J1502D01*
G02X1597404Y376599I1J-1502D01*
G01X1597432Y376565D01*
X1597509Y376528D01*
X1597900Y376522D01*
X1597978Y376556D01*
X1598008Y376589D01*
G02X1599127Y377089I1119J-1002D01*
G02Y374085I0J-1502D01*
G02X1597976Y374621I-1J1502D01*
G01X1597948Y374655D01*
X1597871Y374692D01*
G37*
G36*
G01X1676741Y411236D02*
G02X1678118Y411826I1377J-1312D01*
G01X1680518D01*
G02X1682420Y409924I0J-1902D01*
G02X1681459Y408272I-1902J1D01*
G03X1681358Y408098I99J-174D01*
G01Y407750D01*
G03X1681459Y407576I200J0D01*
G02X1682420Y405924I-941J-1653D01*
G02X1681459Y404272I-1902J1D01*
G03X1681358Y404098I99J-174D01*
G01Y403750D01*
G03X1681459Y403576I200J0D01*
G02X1682420Y401924I-941J-1653D01*
G02X1680518Y400022I-1902J0D01*
G01X1678118D01*
G02X1677623Y400088I2J1902D01*
G01X1677578Y400100D01*
X1677486Y400082D01*
X1677197Y399861D01*
G03X1677119Y399702I122J-159D01*
G01Y396146D01*
G03X1677197Y395987I200J0D01*
G01X1677486Y395766D01*
X1677578Y395748D01*
X1677623Y395760D01*
G02X1678118Y395826I497J-1836D01*
G01X1680518D01*
G02X1682420Y393924I0J-1902D01*
G02X1681450Y392267I-1902J1D01*
G03X1681348Y392092I98J-174D01*
G01Y391744D01*
G03X1681450Y391569I200J-1D01*
G02X1682420Y389912I-932J-1658D01*
G02X1681459Y388260I-1902J1D01*
G03X1681358Y388086I99J-174D01*
G01Y387738D01*
G03X1681459Y387564I200J0D01*
G02X1682420Y385912I-941J-1653D01*
G02X1680518Y384010I-1902J0D01*
G01X1678225D01*
G03X1678084Y383952I0J-200D01*
G01X1677124Y382992D01*
G03X1677065Y382850I141J-142D01*
G01Y377265D01*
G02X1677006Y377123I-200J0D01*
G01X1676552Y376669D01*
Y376662D01*
X1676546D01*
X1675821Y375938D01*
G02X1675679Y375879I-142J141D01*
G01X1662071D01*
G03X1661920Y375811I-1J-200D01*
G01X1661693Y375551D01*
X1661669Y375469D01*
X1661675Y375425D01*
G02X1658025Y370692I-4165J-562D01*
G01X1657977Y370686D01*
X1657901Y370636D01*
X1657692Y370280D01*
X1657685Y370189D01*
X1657703Y370145D01*
G02X1657972Y368760I-3433J-1385D01*
G02X1654270Y365058I-3702J0D01*
G01X1646970D01*
G02Y372462I0J3702D01*
G01X1653366D01*
G03X1653535Y372555I0J200D01*
G01X1653743Y372887D01*
X1653749Y372988D01*
X1653726Y373035D01*
G02X1654232Y377491I3784J1827D01*
G01X1654280Y377552D01*
X1654272Y377703D01*
X1653765Y378210D01*
X1653701Y378239D01*
X1653665Y378242D01*
G02X1652868Y378608I95J1258D01*
G01X1651293Y380183D01*
G02X1651041Y380542I891J893D01*
G01X1651017Y380595D01*
X1650919Y380658D01*
X1647664D01*
G02X1647522Y380717I0J200D01*
G01X1647503Y380736D01*
X1647419Y380766D01*
X1647024Y380730D01*
X1646948Y380685D01*
X1646922Y380648D01*
G02X1645685Y379998I-1237J852D01*
G02X1644183Y381500I0J1502D01*
G02X1644395Y382270I1502J1D01*
G03X1644424Y382372I-171J104D01*
G01Y383397D01*
X1644411Y383445D01*
X1644398Y383468D01*
G02X1644283Y383911I775J438D01*
G01X1644284D01*
Y385089D01*
X1644283D01*
G02X1644622Y385794I890J6D01*
G01X1644660Y385824D01*
X1644700Y385910D01*
X1644687Y386327D01*
X1644641Y386410D01*
X1644602Y386437D01*
G02X1643784Y388000I1084J1563D01*
G01Y390500D01*
G02X1645685Y392402I1901J1D01*
G02X1647207Y391640I0J-1901D01*
G01X1647233Y391606D01*
X1647306Y391565D01*
X1647691Y391532D01*
X1647770Y391560D01*
X1647802Y391590D01*
G02X1648835Y392002I1033J-1089D01*
G02X1650337Y390500I0J-1502D01*
G02X1650125Y389730I-1502J-1D01*
G01X1650111Y389707D01*
X1650096Y389655D01*
Y389462D01*
G03X1650296Y389262I200J0D01*
G01X1651012D01*
G03X1651133Y389303I0J200D01*
G02X1651673Y389486I541J-707D01*
G01X1652526D01*
G02X1652726Y389286I0J-200D01*
G01Y389250D01*
X1654594D01*
G03X1654794Y389450I0J200D01*
G01Y389486D01*
X1655847D01*
G02X1656387Y389303I-1J-890D01*
G03X1656508Y389262I121J159D01*
G01X1658392D01*
G03X1658528Y389315I0J200D01*
G02X1659760Y389802I1232J-1315D01*
G02X1661561Y388059I0J-1802D01*
G01X1661562Y388020D01*
X1661592Y387952D01*
X1661759Y387785D01*
X1661819Y387755D01*
X1661852Y387751D01*
G02X1662582Y387392I-162J-1251D01*
G01X1664074Y385900D01*
X1664121Y385873D01*
X1664148Y385866D01*
G02X1664239Y385840I-367J-1456D01*
G01X1664269Y385831D01*
X1664300D01*
G03X1664500Y386031I0J200D01*
G01Y391709D01*
G03X1664425Y391866I-200J1D01*
G01X1664145Y392089D01*
X1664057Y392110D01*
X1664012Y392100D01*
G02X1663618Y392056I-396J1758D01*
G02Y395660I0J1802D01*
G02X1664012Y395616I-2J-1802D01*
G01X1664057Y395606D01*
X1664145Y395627D01*
X1664425Y395850D01*
G03X1664500Y396007I-125J156D01*
G01Y396826D01*
G03X1664396Y397002I-200J0D01*
G02Y400164I863J1581D01*
G03X1664500Y400340I-96J176D01*
G01Y401436D01*
G03X1664428Y401589I-200J-1D01*
G01X1664158Y401815D01*
X1664072Y401837D01*
X1664029Y401829D01*
G02X1663760Y401805I-267J1478D01*
G02Y404809I0J1502D01*
G02X1664953Y404219I0J-1501D01*
G01X1664980Y404185D01*
X1665055Y404144D01*
X1665399Y404121D01*
G03X1665554Y404180I13J200D01*
G01X1665619Y404245D01*
X1665634Y404276D01*
G02X1666484Y405126I1626J-776D01*
G01X1666515Y405141D01*
X1668284Y406910D01*
G03X1668342Y407069I-141J142D01*
G01X1668311Y407419D01*
X1668267Y407496D01*
X1668230Y407521D01*
G02X1667458Y409000I1031J1479D01*
G02X1669260Y410802I1802J0D01*
G02X1670492Y410315I0J-1802D01*
G01X1670520Y410289D01*
X1670589Y410262D01*
X1670655D01*
G03X1670796Y410320I0J200D01*
G01X1671292Y410816D01*
G02X1672184Y411186I893J-892D01*
G01X1673795D01*
G03X1673916Y411227I0J200D01*
G02X1674456Y411410I541J-707D01*
G01X1675310D01*
G02X1675510Y411210I0J-201D01*
G01Y411174D01*
X1676596D01*
G03X1676741Y411236I0J200D01*
G37*
G36*
G01X1737936Y454009D02*
X1737913Y454426D01*
X1737867Y454506D01*
X1737827Y454533D01*
G02X1737022Y456034I997J1501D01*
G02X1740626I1802J0D01*
G02X1739821Y454533I-1802J0D01*
G01X1739781Y454506D01*
X1739735Y454426D01*
X1739712Y454009D01*
X1739749Y453924D01*
X1739787Y453893D01*
G02X1740326Y452740I-964J-1153D01*
G02X1737322I-1502J0D01*
G02X1737861Y453893I1503J0D01*
G01X1737899Y453924D01*
X1737936Y454009D01*
G37*
G36*
G01X1664429Y463780D02*
X1664102Y464035D01*
X1664011Y464054D01*
X1663965Y464041D01*
G02X1663576Y463990I-388J1451D01*
G02Y466994I0J1502D01*
G02X1665071Y465633I0J-1502D01*
G01X1665076Y465586D01*
X1665125Y465506D01*
X1665478Y465289D01*
X1665571Y465281D01*
X1665615Y465298D01*
G02X1666271Y465422I657J-1679D01*
G02X1668074Y463619I0J-1803D01*
G01Y460219D01*
G02X1666271Y458416I-1803J0D01*
G02X1665610Y458542I1J1803D01*
G01X1665566Y458559D01*
X1665475Y458552D01*
X1665122Y458343D01*
X1665072Y458266D01*
X1665066Y458220D01*
G02X1663576Y456904I-1490J186D01*
G02Y459908I0J1502D01*
G02X1664105Y459812I1J-1502D01*
G03X1664294Y459838I71J187D01*
G01X1664393Y459911D01*
G03X1664473Y460087I-119J160D01*
G02X1664468Y460219I1798J134D01*
G01Y463619D01*
G02X1664469Y463648I1801J-48D01*
G01X1664470Y463696D01*
X1664429Y463780D01*
G37*
G36*
G01X1739590Y466541D02*
Y466835D01*
G03X1739525Y466982I-200J-1D01*
G02X1739040Y468088I1017J1105D01*
G02X1742044I1502J0D01*
G02X1741559Y466982I-1502J-1D01*
G03X1741494Y466835I135J-148D01*
G01Y466541D01*
G03X1741559Y466394I200J1D01*
G02X1742044Y465288I-1017J-1105D01*
G02X1739040I-1502J0D01*
G02X1739525Y466394I1502J1D01*
G03X1739590Y466541I-135J148D01*
G37*
G36*
G01X1746224Y468918D02*
X1745888D01*
X1745821Y468893D01*
X1745793Y468869D01*
G02X1744806Y468499I-987J1131D01*
G02Y471503I0J1502D01*
G02X1745793Y471133I0J-1501D01*
G01X1745821Y471109D01*
X1745888Y471084D01*
X1746224D01*
X1746291Y471109D01*
X1746319Y471133D01*
G02X1747306Y471503I987J-1131D01*
G02Y468499I0J-1502D01*
G02X1746319Y468869I0J1501D01*
G01X1746291Y468893D01*
X1746224Y468918D01*
G37*
G36*
G01X1691099Y472278D02*
X1691218Y472251D01*
G03X1691361Y472272I44J195D01*
G02X1692253Y472508I892J-1566D01*
G02X1693145Y472272I0J-1802D01*
G03X1693288Y472251I99J174D01*
G01X1693407Y472278D01*
G03X1693526Y472357I-44J195D01*
G02X1694749Y472986I1222J-873D01*
G02Y469982I0J-1502D01*
G02X1694517Y470000I0J1502D01*
G01X1694474Y470007D01*
X1694390Y469983D01*
X1694125Y469757D01*
G03X1694056Y469605I131J-151D01*
G01Y468407D01*
G03X1694125Y468255I200J-1D01*
G01X1694390Y468029D01*
X1694474Y468005D01*
X1694517Y468012D01*
G02X1694749Y468030I232J-1484D01*
G02Y465026I0J-1502D01*
G02X1693526Y465655I-1J1502D01*
G03X1693407Y465734I-163J-116D01*
G01X1693288Y465761D01*
G03X1693145Y465740I-44J-195D01*
G02X1692253Y465504I-892J1566D01*
G02X1691361Y465740I0J1802D01*
G03X1691218Y465761I-99J-174D01*
G01X1691099Y465734D01*
G03X1690980Y465655I44J-195D01*
G02X1689757Y465026I-1222J873D01*
G02Y468030I0J1502D01*
G02X1689989Y468012I0J-1502D01*
G01X1690032Y468005D01*
X1690116Y468029D01*
X1690381Y468255D01*
G03X1690450Y468407I-131J151D01*
G01Y469605D01*
G03X1690381Y469757I-200J1D01*
G01X1690116Y469983D01*
X1690032Y470007D01*
X1689989Y470000D01*
G02X1689757Y469982I-232J1484D01*
G02Y472986I0J1502D01*
G02X1690980Y472357I1J-1502D01*
G03X1691099Y472278I163J116D01*
G37*
G36*
G01X1701501Y479390D02*
X1701620Y479363D01*
G03X1701763Y479384I44J195D01*
G02X1702655Y479620I892J-1566D01*
G02X1703547Y479384I0J-1802D01*
G03X1703690Y479363I99J174D01*
G01X1703809Y479390D01*
G03X1703928Y479469I-44J195D01*
G02X1705151Y480098I1222J-873D01*
G02Y477094I0J-1502D01*
G02X1704919Y477112I0J1502D01*
G01X1704876Y477119D01*
X1704792Y477095D01*
X1704527Y476869D01*
G03X1704458Y476717I131J-151D01*
G01Y475519D01*
G03X1704527Y475367I200J-1D01*
G01X1704792Y475141D01*
X1704876Y475117D01*
X1704919Y475124D01*
G02X1705151Y475142I232J-1484D01*
G02Y472138I0J-1502D01*
G02X1703928Y472767I-1J1502D01*
G03X1703809Y472846I-163J-116D01*
G01X1703690Y472873D01*
G03X1703547Y472852I-44J-195D01*
G02X1702655Y472616I-892J1566D01*
G02X1701763Y472852I0J1802D01*
G03X1701620Y472873I-99J-174D01*
G01X1701501Y472846D01*
G03X1701382Y472767I44J-195D01*
G02X1700159Y472138I-1222J873D01*
G02Y475142I0J1502D01*
G02X1700391Y475124I0J-1502D01*
G01X1700434Y475117D01*
X1700518Y475141D01*
X1700783Y475367D01*
G03X1700852Y475519I-131J151D01*
G01Y476717D01*
G03X1700783Y476869I-200J1D01*
G01X1700518Y477095D01*
X1700434Y477119D01*
X1700391Y477112D01*
G02X1700159Y477094I-232J1484D01*
G02Y480098I0J1502D01*
G02X1701382Y479469I1J-1502D01*
G03X1701501Y479390I163J116D01*
G37*
G36*
G01X1744174Y486663D02*
X1744510D01*
X1744577Y486688D01*
X1744605Y486712D01*
G02X1746579I987J-1131D01*
G01X1746607Y486688D01*
X1746674Y486663D01*
X1747010D01*
X1747077Y486688D01*
X1747105Y486712D01*
G02X1748092Y487082I987J-1131D01*
G02Y484078I0J-1502D01*
G02X1747105Y484448I0J1501D01*
G01X1747077Y484472D01*
X1747010Y484497D01*
X1746674D01*
X1746607Y484472D01*
X1746579Y484448D01*
G02X1744605I-987J1131D01*
G01X1744577Y484472D01*
X1744510Y484497D01*
X1744174D01*
X1744107Y484472D01*
X1744079Y484448D01*
G02X1743092Y484078I-987J1131D01*
G02Y487082I0J1502D01*
G02X1744079Y486712I0J-1501D01*
G01X1744107Y486688D01*
X1744174Y486663D01*
G37*
G36*
G01X1691099Y486451D02*
X1691218Y486424D01*
G03X1691361Y486445I44J195D01*
G02X1692253Y486682I893J-1566D01*
G02X1693145Y486445I-1J-1803D01*
G03X1693288Y486424I99J174D01*
G01X1693407Y486451D01*
G03X1693526Y486530I-44J195D01*
G02X1694749Y487159I1222J-873D01*
G02Y484155I0J-1502D01*
G02X1694517Y484173I0J1502D01*
G01X1694474Y484180D01*
X1694390Y484156D01*
X1694125Y483930D01*
G03X1694056Y483778I131J-151D01*
G01Y482580D01*
G03X1694125Y482428I200J-1D01*
G01X1694390Y482202D01*
X1694474Y482178D01*
X1694517Y482185D01*
G02X1694749Y482203I232J-1484D01*
G02Y479199I0J-1502D01*
G02X1693526Y479828I-1J1502D01*
G03X1693407Y479907I-163J-116D01*
G01X1693288Y479934D01*
G03X1693145Y479913I-44J-195D01*
G02X1692253Y479676I-893J1566D01*
G02X1691361Y479913I1J1803D01*
G03X1691218Y479934I-99J-174D01*
G01X1691099Y479907D01*
G03X1690980Y479828I44J-195D01*
G02X1689757Y479199I-1222J873D01*
G02Y482203I0J1502D01*
G02X1689989Y482185I0J-1502D01*
G01X1690032Y482178D01*
X1690116Y482202D01*
X1690381Y482428D01*
G03X1690450Y482580I-131J151D01*
G01Y483778D01*
G03X1690381Y483930I-200J1D01*
G01X1690116Y484156D01*
X1690032Y484180D01*
X1689989Y484173D01*
G02X1689757Y484155I-232J1484D01*
G02Y487159I0J1502D01*
G02X1690980Y486530I1J-1502D01*
G03X1691099Y486451I163J116D01*
G37*
G36*
G01X1756900Y485252D02*
X1756629Y485552D01*
X1756545Y485586D01*
X1756499Y485583D01*
G02X1756391Y485580I-104J1799D01*
G02X1758193Y487382I0J1802D01*
G02X1758125Y486890I-1802J-2D01*
G01X1758112Y486846D01*
X1758127Y486757D01*
X1758362Y486428D01*
X1758441Y486384D01*
X1758487Y486382D01*
G02X1759903Y484882I-86J-1500D01*
G02X1756899I-1502J0D01*
G02X1756918Y485120I1502J0D01*
G01X1756925Y485166D01*
X1756900Y485252D01*
G37*
G36*
G01X1735509Y488652D02*
Y488988D01*
X1735484Y489055D01*
X1735460Y489083D01*
G02X1735090Y490070I1131J987D01*
G02X1738094I1502J0D01*
G02X1737724Y489083I-1501J0D01*
G01X1737700Y489055D01*
X1737675Y488988D01*
Y488652D01*
X1737700Y488585D01*
X1737724Y488557D01*
G02X1738094Y487570I-1131J-987D01*
G02X1735090I-1502J0D01*
G02X1735460Y488557I1501J0D01*
G01X1735484Y488585D01*
X1735509Y488652D01*
G37*
G36*
G01X1701501Y493563D02*
X1701620Y493536D01*
G03X1701763Y493557I44J195D01*
G02X1702655Y493794I893J-1566D01*
G02X1703547Y493557I-1J-1803D01*
G03X1703690Y493536I99J174D01*
G01X1703809Y493563D01*
G03X1703928Y493642I-44J195D01*
G02X1705151Y494271I1222J-873D01*
G02Y491267I0J-1502D01*
G02X1704919Y491285I0J1502D01*
G01X1704876Y491292D01*
X1704792Y491268D01*
X1704527Y491042D01*
G03X1704458Y490890I131J-151D01*
G01Y489692D01*
G03X1704527Y489540I200J-1D01*
G01X1704792Y489314D01*
X1704876Y489290D01*
X1704919Y489297D01*
G02X1705151Y489315I232J-1484D01*
G02Y486311I0J-1502D01*
G02X1703928Y486940I-1J1502D01*
G03X1703809Y487019I-163J-116D01*
G01X1703690Y487046D01*
G03X1703547Y487025I-44J-195D01*
G02X1702655Y486788I-893J1566D01*
G02X1701763Y487025I1J1803D01*
G03X1701620Y487046I-99J-174D01*
G01X1701501Y487019D01*
G03X1701382Y486940I44J-195D01*
G02X1700159Y486311I-1222J873D01*
G02Y489315I0J1502D01*
G02X1700391Y489297I0J-1502D01*
G01X1700434Y489290D01*
X1700518Y489314D01*
X1700783Y489540D01*
G03X1700852Y489692I-131J151D01*
G01Y490890D01*
G03X1700783Y491042I-200J1D01*
G01X1700518Y491268D01*
X1700434Y491292D01*
X1700391Y491285D01*
G02X1700159Y491267I-232J1484D01*
G02Y494271I0J1502D01*
G02X1701382Y493642I1J-1502D01*
G03X1701501Y493563I163J116D01*
G37*
G36*
G01X1746515Y494089D02*
Y494383D01*
G03X1746450Y494530I-200J-1D01*
G02X1745965Y495636I1017J1105D01*
G02X1748969I1502J0D01*
G02X1748484Y494530I-1502J-1D01*
G03X1748419Y494383I135J-148D01*
G01Y494089D01*
G03X1748484Y493942I200J1D01*
G02X1748969Y492836I-1017J-1105D01*
G02X1745965I-1502J0D01*
G02X1746450Y493942I1502J1D01*
G03X1746515Y494089I-135J148D01*
G37*
G36*
G01X1672361Y330773D02*
G02X1671701Y332017I842J1244D01*
G02X1674705I1502J0D01*
G02X1674045Y330773I-1502J0D01*
G03Y330111I224J-331D01*
G02X1674705Y328867I-842J-1244D01*
G02X1671701I-1502J0D01*
G02X1672361Y330111I1502J0D01*
G03Y330773I-224J331D01*
G37*
G36*
G01X1607346Y330950D02*
G02X1606445Y332326I600J1376D01*
G02X1609449I1502J0D01*
G02X1608780Y331076I-1502J0D01*
G03X1608841Y330376I221J-333D01*
G02X1609742Y329000I-600J-1376D01*
G02X1606738I-1502J0D01*
G02X1607407Y330250I1502J0D01*
G03X1607346Y330950I-221J333D01*
G37*
G36*
G01X1629900Y349385D02*
G02X1629201Y350655I804J1270D01*
G02X1632205I1502J0D01*
G02X1631496Y349379I-1503J0D01*
G03X1631494Y348702I211J-339D01*
G02X1632193Y347432I-804J-1270D01*
G02X1629189I-1502J0D01*
G02X1629898Y348708I1503J0D01*
G03X1629900Y349385I-211J339D01*
G37*
G36*
G01X1665010Y352646D02*
G02X1663650Y351781I-1360J637D01*
G02Y354785I0J1502D01*
G02X1664825Y354219I0J-1503D01*
G03X1665500Y354298I313J249D01*
G02X1666860Y355163I1360J-637D01*
G02Y352159I0J-1502D01*
G02X1665685Y352725I0J1503D01*
G03X1665010Y352646I-313J-249D01*
G37*
G36*
G01X1690660Y355291D02*
X1690608Y355308D01*
G02X1689380Y357016I574J1708D01*
G02X1692984I1802J0D01*
G02X1692260Y355572I-1802J0D01*
G01X1692216Y355539D01*
X1692174Y355442D01*
X1692227Y354991D01*
X1692290Y354906D01*
X1692340Y354884D01*
G02X1693245Y353506I-597J-1378D01*
G02X1691743Y352004I-1502J0D01*
G02X1690509Y352650I0J1502D01*
G01X1690480Y352691D01*
X1690392Y352737D01*
X1689961Y352732D01*
X1689874Y352684D01*
X1689846Y352642D01*
G02X1688593Y351968I-1253J828D01*
G02Y354972I0J1502D01*
G02X1689827Y354326I0J-1502D01*
G01X1689856Y354285D01*
X1689944Y354239D01*
X1690375Y354244D01*
X1690462Y354292D01*
X1690490Y354334D01*
G02X1690746Y354630I1254J-826D01*
G01X1690787Y354666D01*
X1690820Y354766D01*
X1690730Y355211D01*
X1690660Y355291D01*
G37*
G36*
G01X1639648Y378798D02*
G02X1638340Y378034I-1308J738D01*
G02Y381038I0J1502D01*
G02X1639618Y380325I0J-1502D01*
G03X1640307Y380338I341J210D01*
G02X1641615Y381102I1308J-738D01*
G02Y378098I0J-1502D01*
G02X1640337Y378811I0J1502D01*
G03X1639648Y378798I-341J-210D01*
G37*
G36*
G01X1595862Y381766D02*
G02X1595212Y383003I852J1237D01*
G02X1598216I1502J0D01*
G02X1597424Y381679I-1503J0D01*
G03X1597386Y380997I189J-353D01*
G02X1598036Y379760I-852J-1237D01*
G02X1595032I-1502J0D01*
G02X1595824Y381084I1503J0D01*
G03X1595862Y381766I-189J353D01*
G37*
G36*
G01X1732039Y495243D02*
X1732015Y495271D01*
G02X1731645Y496258I1131J987D01*
G02X1734649I1502J0D01*
G02X1734279Y495271I-1501J0D01*
G01X1734255Y495243D01*
X1734230Y495176D01*
Y494840D01*
X1734255Y494773D01*
X1734279Y494745D01*
G02X1734649Y493758I-1131J-987D01*
G02X1733147Y492256I-1502J0D01*
G02X1732585Y492365I0J1503D01*
G01X1732537Y492385D01*
X1732436Y492372D01*
X1732077Y492112D01*
X1732033Y492020D01*
X1732037Y491968D01*
G02X1732040Y491870I-1499J-95D01*
G02X1730538Y490368I-1502J0D01*
G02X1729551Y490738I0J1501D01*
G01X1729523Y490762D01*
X1729456Y490787D01*
X1729120D01*
X1729053Y490762D01*
X1729025Y490738D01*
G02X1728038Y490368I-987J1131D01*
G02X1727002Y490782I0J1503D01*
G01X1726965Y490818D01*
X1726867Y490844D01*
X1726441Y490741D01*
X1726365Y490672D01*
X1726349Y490624D01*
G02X1726062Y490131I-1418J496D01*
G01X1726038Y490103D01*
X1726013Y490036D01*
Y489700D01*
X1726038Y489633D01*
X1726062Y489605D01*
G02X1726432Y488618I-1131J-987D01*
G02X1723428I-1502J0D01*
G02X1723798Y489605I1501J0D01*
G01X1723822Y489633D01*
X1723847Y489700D01*
Y490036D01*
X1723822Y490103D01*
X1723798Y490131D01*
G02Y492105I1131J987D01*
G01X1723822Y492133D01*
X1723847Y492200D01*
Y492536D01*
X1723822Y492603D01*
X1723798Y492631D01*
G02Y494605I1131J987D01*
G01X1723822Y494633D01*
X1723847Y494700D01*
Y495036D01*
X1723822Y495103D01*
X1723798Y495131D01*
G02X1723428Y496118I1131J987D01*
G02X1726432I1502J0D01*
G02X1726062Y495131I-1501J0D01*
G01X1726038Y495103D01*
X1726013Y495036D01*
Y494700D01*
X1726038Y494633D01*
X1726062Y494605D01*
G02Y492631I-1131J-987D01*
G01X1726038Y492603D01*
X1726013Y492536D01*
Y492200D01*
X1726038Y492133D01*
X1726062Y492105D01*
G02X1726180Y491950I-1133J-985D01*
G03X1726546Y492039I167J111D01*
G02X1728038Y493372I1492J-168D01*
G02X1729025Y493002I0J-1501D01*
G01X1729053Y492978D01*
X1729120Y492953D01*
X1729456D01*
X1729523Y492978D01*
X1729551Y493002D01*
G02X1730538Y493372I987J-1131D01*
G02X1731100Y493263I0J-1503D01*
G01X1731148Y493243D01*
X1731249Y493256D01*
X1731608Y493516D01*
X1731652Y493608D01*
X1731648Y493660D01*
G02X1731645Y493758I1499J95D01*
G02X1732015Y494745I1501J0D01*
G01X1732039Y494773D01*
X1732064Y494840D01*
Y495176D01*
X1732039Y495243D01*
G37*
G36*
G01X1621392Y84108D02*
Y84460D01*
X1621364Y84529D01*
X1621338Y84557D01*
G02X1620932Y85584I1096J1027D01*
G02X1623936I1502J0D01*
G02X1623530Y84557I-1502J0D01*
G01X1623504Y84529D01*
X1623476Y84460D01*
Y84108D01*
X1623504Y84039D01*
X1623530Y84011D01*
G02Y81957I-1096J-1027D01*
G01X1623504Y81929D01*
X1623476Y81860D01*
Y81508D01*
X1623504Y81439D01*
X1623530Y81411D01*
G02Y79357I-1096J-1027D01*
G01X1623504Y79329D01*
X1623476Y79260D01*
Y78908D01*
X1623504Y78839D01*
X1623530Y78811D01*
G02Y76757I-1096J-1027D01*
G01X1623504Y76729D01*
X1623476Y76660D01*
Y76308D01*
X1623504Y76239D01*
X1623530Y76211D01*
G02X1623936Y75184I-1096J-1027D01*
G02X1620932I-1502J0D01*
G02X1621338Y76211I1502J0D01*
G01X1621364Y76239D01*
X1621392Y76308D01*
Y76660D01*
X1621364Y76729D01*
X1621338Y76757D01*
G02Y78811I1096J1027D01*
G01X1621364Y78839D01*
X1621392Y78908D01*
Y79260D01*
X1621364Y79329D01*
X1621338Y79357D01*
G02Y81411I1096J1027D01*
G01X1621364Y81439D01*
X1621392Y81508D01*
Y81860D01*
X1621364Y81929D01*
X1621338Y81957D01*
G02Y84011I1096J1027D01*
G01X1621364Y84039D01*
X1621392Y84108D01*
G37*
G36*
G01X1630870Y101516D02*
X1630906Y101900D01*
X1630879Y101981D01*
X1630850Y102013D01*
G02X1630446Y103037I1098J1025D01*
G02X1633450I1502J0D01*
G02X1632983Y101948I-1503J0D01*
G01X1632951Y101918D01*
X1632919Y101839D01*
X1632932Y101454D01*
X1632970Y101377D01*
X1633003Y101350D01*
G02X1633657Y99961I-1148J-1389D01*
G02X1630053I-1802J0D01*
G02X1630793Y101417I1802J0D01*
G01X1630828Y101442D01*
X1630870Y101516D01*
G37*
G36*
G01X1650835Y116195D02*
X1650954Y116168D01*
G03X1651097Y116189I44J195D01*
G02X1651989Y116426I893J-1566D01*
G02X1652881Y116189I-1J-1803D01*
G03X1653024Y116168I99J174D01*
G01X1653143Y116195D01*
G03X1653262Y116274I-44J195D01*
G02X1654485Y116903I1222J-873D01*
G02Y113899I0J-1502D01*
G02X1654253Y113917I0J1502D01*
G01X1654210Y113924D01*
X1654126Y113900D01*
X1653861Y113674D01*
G03X1653792Y113522I131J-151D01*
G01Y112324D01*
G03X1653861Y112172I200J-1D01*
G01X1654126Y111946D01*
X1654210Y111922D01*
X1654253Y111929D01*
G02X1654485Y111947I232J-1484D01*
G02Y108943I0J-1502D01*
G02X1653262Y109572I-1J1502D01*
G03X1653143Y109651I-163J-116D01*
G01X1653024Y109678D01*
G03X1652881Y109657I-44J-195D01*
G02X1651989Y109420I-893J1566D01*
G02X1651097Y109657I1J1803D01*
G03X1650954Y109678I-99J-174D01*
G01X1650835Y109651D01*
G03X1650716Y109572I44J-195D01*
G02X1649493Y108943I-1222J873D01*
G02Y111947I0J1502D01*
G02X1649725Y111929I0J-1502D01*
G01X1649768Y111922D01*
X1649852Y111946D01*
X1650117Y112172D01*
G03X1650186Y112324I-131J151D01*
G01Y113522D01*
G03X1650117Y113674I-200J1D01*
G01X1649852Y113900D01*
X1649768Y113924D01*
X1649725Y113917D01*
G02X1649493Y113899I-232J1484D01*
G02Y116903I0J1502D01*
G02X1650716Y116274I1J-1502D01*
G03X1650835Y116195I163J116D01*
G37*
G36*
G01Y130368D02*
X1650954Y130341D01*
G03X1651097Y130362I44J195D01*
G02X1651989Y130598I892J-1566D01*
G02X1652881Y130362I0J-1802D01*
G03X1653024Y130341I99J174D01*
G01X1653143Y130368D01*
G03X1653262Y130447I-44J195D01*
G02X1654485Y131076I1222J-873D01*
G02Y128072I0J-1502D01*
G02X1654253Y128090I0J1502D01*
G01X1654210Y128097D01*
X1654126Y128073D01*
X1653861Y127847D01*
G03X1653792Y127695I131J-151D01*
G01Y126497D01*
G03X1653861Y126345I200J-1D01*
G01X1654126Y126119D01*
X1654210Y126095D01*
X1654253Y126102D01*
G02X1654485Y126120I232J-1484D01*
G02Y123116I0J-1502D01*
G02X1653262Y123745I-1J1502D01*
G03X1653143Y123824I-163J-116D01*
G01X1653024Y123851D01*
G03X1652881Y123830I-44J-195D01*
G02X1651989Y123594I-892J1566D01*
G02X1651097Y123830I0J1802D01*
G03X1650954Y123851I-99J-174D01*
G01X1650835Y123824D01*
G03X1650716Y123745I44J-195D01*
G02X1649493Y123116I-1222J873D01*
G02Y126120I0J1502D01*
G02X1649725Y126102I0J-1502D01*
G01X1649768Y126095D01*
X1649852Y126119D01*
X1650117Y126345D01*
G03X1650186Y126497I-131J151D01*
G01Y127695D01*
G03X1650117Y127847I-200J1D01*
G01X1649852Y128073D01*
X1649768Y128097D01*
X1649725Y128090D01*
G02X1649493Y128072I-232J1484D01*
G02Y131076I0J1502D01*
G02X1650716Y130447I1J-1502D01*
G03X1650835Y130368I163J116D01*
G37*
G36*
G01X1630204Y146186D02*
G02X1627028Y140292I-3176J-2091D01*
G01X1627027D01*
G02X1623851Y146186I0J3803D01*
G01X1623867Y146211D01*
X1623884Y146266D01*
Y146296D01*
G03X1623684Y146496I-200J0D01*
G01X1623377D01*
G02Y153898I0J3701D01*
G01X1630677D01*
G02Y146496I0J-3701D01*
G01X1630371D01*
G03X1630171Y146296I0J-200D01*
G01Y146236D01*
X1630204Y146186D01*
G37*
G36*
G01X1623498Y92655D02*
X1623493Y92709D01*
G02X1623486Y92849I1495J145D01*
G02X1626490I1502J0D01*
G02X1626487Y92747I-1502J-7D01*
G01X1626483Y92696D01*
X1626522Y92607D01*
X1626860Y92340D01*
X1626955Y92322D01*
X1627003Y92337D01*
G02X1627534Y92417I531J-1722D01*
G02X1625732Y90615I0J-1802D01*
G02X1625758Y90917I1802J-3D01*
G01X1625766Y90967D01*
X1625736Y91059D01*
X1625427Y91359D01*
X1625334Y91386D01*
X1625284Y91377D01*
G02X1624988Y91347I-299J1472D01*
G02X1624515Y91424I2J1502D01*
G01X1624463Y91441D01*
X1624361Y91420D01*
X1624020Y91124D01*
X1623985Y91026D01*
X1623995Y90972D01*
G02X1624024Y90650I-1773J-322D01*
G02X1622222Y92452I-1802J0D01*
G02X1622936Y92305I1J-1802D01*
G01X1622985Y92283D01*
X1623089Y92295D01*
X1623455Y92560D01*
X1623498Y92655D01*
G37*
G36*
G01X1648252Y100457D02*
G02X1647592Y101701I842J1244D01*
G02X1650596I1502J0D01*
G02X1649936Y100457I-1502J0D01*
G03Y99795I224J-331D01*
G02X1650596Y98551I-842J-1244D01*
G02X1647592I-1502J0D01*
G02X1648252Y99795I1502J0D01*
G03Y100457I-224J331D01*
G37*
G36*
G01X1640664Y108025D02*
G02X1640082Y107908I-581J1385D01*
G02Y110912I0J1502D01*
G02X1641570Y109616I0J-1502D01*
G01X1641576Y109569D01*
X1641629Y109492D01*
X1641988Y109290D01*
X1642081Y109285D01*
X1642125Y109304D01*
G02X1642840Y109452I715J-1655D01*
G02X1644642Y107649I-1J-1803D01*
G01Y104249D01*
G02X1642840Y102446I-1802J-1D01*
G02X1642137Y102589I1J1803D01*
G01X1642092Y102608D01*
X1641995Y102601D01*
X1641634Y102375D01*
X1641584Y102291D01*
X1641582Y102242D01*
G02X1640082Y100821I-1500J81D01*
G02Y103825I0J1502D01*
G02X1640523Y103759I1J-1502D01*
G01X1640570Y103744D01*
X1640666Y103762D01*
X1641001Y104023D01*
X1641042Y104112D01*
X1641040Y104161D01*
G02X1641038Y104249I1800J85D01*
G01Y107649D01*
G02X1641041Y107759I1802J6D01*
G03X1640956Y107935I-200J12D01*
G01X1640856Y108005D01*
G03X1640664Y108025I-114J-164D01*
G37*
G36*
G01X1723754Y84108D02*
Y84460D01*
X1723726Y84529D01*
X1723700Y84557D01*
G02X1723294Y85584I1096J1027D01*
G02X1726298I1502J0D01*
G02X1725892Y84557I-1502J0D01*
G01X1725866Y84529D01*
X1725838Y84460D01*
Y84108D01*
X1725866Y84039D01*
X1725892Y84011D01*
G02Y81957I-1096J-1027D01*
G01X1725866Y81929D01*
X1725838Y81860D01*
Y81508D01*
X1725866Y81439D01*
X1725892Y81411D01*
G02Y79357I-1096J-1027D01*
G01X1725866Y79329D01*
X1725838Y79260D01*
Y78908D01*
X1725866Y78839D01*
X1725892Y78811D01*
G02Y76757I-1096J-1027D01*
G01X1725866Y76729D01*
X1725838Y76660D01*
Y76308D01*
X1725866Y76239D01*
X1725892Y76211D01*
G02X1726298Y75184I-1096J-1027D01*
G02X1723294I-1502J0D01*
G02X1723700Y76211I1502J0D01*
G01X1723726Y76239D01*
X1723754Y76308D01*
Y76660D01*
X1723726Y76729D01*
X1723700Y76757D01*
G02Y78811I1096J1027D01*
G01X1723726Y78839D01*
X1723754Y78908D01*
Y79260D01*
X1723726Y79329D01*
X1723700Y79357D01*
G02Y81411I1096J1027D01*
G01X1723726Y81439D01*
X1723754Y81508D01*
Y81860D01*
X1723726Y81929D01*
X1723700Y81957D01*
G02Y84011I1096J1027D01*
G01X1723726Y84039D01*
X1723754Y84108D01*
G37*
G36*
G01X1733232Y101516D02*
X1733268Y101900D01*
X1733241Y101981D01*
X1733212Y102013D01*
G02X1732808Y103037I1098J1025D01*
G02X1735812I1502J0D01*
G02X1735345Y101948I-1503J0D01*
G01X1735313Y101918D01*
X1735281Y101839D01*
X1735294Y101454D01*
X1735332Y101377D01*
X1735365Y101350D01*
G02X1736019Y99961I-1148J-1389D01*
G02X1732415I-1802J0D01*
G02X1733155Y101417I1802J0D01*
G01X1733190Y101442D01*
X1733232Y101516D01*
G37*
G36*
G01X1753197Y116195D02*
X1753316Y116168D01*
G03X1753459Y116189I44J195D01*
G02X1754351Y116426I893J-1566D01*
G02X1755243Y116189I-1J-1803D01*
G03X1755386Y116168I99J174D01*
G01X1755505Y116195D01*
G03X1755624Y116274I-44J195D01*
G02X1756847Y116903I1222J-873D01*
G02Y113899I0J-1502D01*
G02X1756615Y113917I0J1502D01*
G01X1756572Y113924D01*
X1756488Y113900D01*
X1756223Y113674D01*
G03X1756154Y113522I131J-151D01*
G01Y112324D01*
G03X1756223Y112172I200J-1D01*
G01X1756488Y111946D01*
X1756572Y111922D01*
X1756615Y111929D01*
G02X1756847Y111947I232J-1484D01*
G02Y108943I0J-1502D01*
G02X1755624Y109572I-1J1502D01*
G03X1755505Y109651I-163J-116D01*
G01X1755386Y109678D01*
G03X1755243Y109657I-44J-195D01*
G02X1754351Y109420I-893J1566D01*
G02X1753459Y109657I1J1803D01*
G03X1753316Y109678I-99J-174D01*
G01X1753197Y109651D01*
G03X1753078Y109572I44J-195D01*
G02X1751855Y108943I-1222J873D01*
G02Y111947I0J1502D01*
G02X1752087Y111929I0J-1502D01*
G01X1752130Y111922D01*
X1752214Y111946D01*
X1752479Y112172D01*
G03X1752548Y112324I-131J151D01*
G01Y113522D01*
G03X1752479Y113674I-200J1D01*
G01X1752214Y113900D01*
X1752130Y113924D01*
X1752087Y113917D01*
G02X1751855Y113899I-232J1484D01*
G02Y116903I0J1502D01*
G02X1753078Y116274I1J-1502D01*
G03X1753197Y116195I163J116D01*
G37*
G36*
G01Y130368D02*
X1753316Y130341D01*
G03X1753459Y130362I44J195D01*
G02X1754351Y130598I892J-1566D01*
G02X1755243Y130362I0J-1802D01*
G03X1755386Y130341I99J174D01*
G01X1755505Y130368D01*
G03X1755624Y130447I-44J195D01*
G02X1756847Y131076I1222J-873D01*
G02Y128072I0J-1502D01*
G02X1756615Y128090I0J1502D01*
G01X1756572Y128097D01*
X1756488Y128073D01*
X1756223Y127847D01*
G03X1756154Y127695I131J-151D01*
G01Y126497D01*
G03X1756223Y126345I200J-1D01*
G01X1756488Y126119D01*
X1756572Y126095D01*
X1756615Y126102D01*
G02X1756847Y126120I232J-1484D01*
G02Y123116I0J-1502D01*
G02X1755624Y123745I-1J1502D01*
G03X1755505Y123824I-163J-116D01*
G01X1755386Y123851D01*
G03X1755243Y123830I-44J-195D01*
G02X1754351Y123594I-892J1566D01*
G02X1753459Y123830I0J1802D01*
G03X1753316Y123851I-99J-174D01*
G01X1753197Y123824D01*
G03X1753078Y123745I44J-195D01*
G02X1751855Y123116I-1222J873D01*
G02Y126120I0J1502D01*
G02X1752087Y126102I0J-1502D01*
G01X1752130Y126095D01*
X1752214Y126119D01*
X1752479Y126345D01*
G03X1752548Y126497I-131J151D01*
G01Y127695D01*
G03X1752479Y127847I-200J1D01*
G01X1752214Y128073D01*
X1752130Y128097D01*
X1752087Y128090D01*
G02X1751855Y128072I-232J1484D01*
G02Y131076I0J1502D01*
G02X1753078Y130447I1J-1502D01*
G03X1753197Y130368I163J116D01*
G37*
G36*
G01X1732566Y146186D02*
G02X1729390Y140292I-3176J-2091D01*
G01X1729389D01*
G02X1726213Y146186I0J3803D01*
G01X1726229Y146211D01*
X1726246Y146266D01*
Y146296D01*
G03X1726046Y146496I-200J0D01*
G01X1725739D01*
G02Y153898I0J3701D01*
G01X1733039D01*
G02Y146496I0J-3701D01*
G01X1732733D01*
G03X1732533Y146296I0J-200D01*
G01Y146236D01*
X1732566Y146186D01*
G37*
G36*
G01X1725860Y92655D02*
X1725855Y92709D01*
G02X1725848Y92849I1495J145D01*
G02X1728852I1502J0D01*
G02X1728849Y92747I-1502J-7D01*
G01X1728845Y92696D01*
X1728884Y92607D01*
X1729222Y92340D01*
X1729317Y92322D01*
X1729365Y92337D01*
G02X1729896Y92417I531J-1722D01*
G02X1728094Y90615I0J-1802D01*
G02X1728120Y90917I1802J-3D01*
G01X1728128Y90967D01*
X1728098Y91059D01*
X1727789Y91359D01*
X1727696Y91386D01*
X1727646Y91377D01*
G02X1727350Y91347I-299J1472D01*
G02X1726877Y91424I2J1502D01*
G01X1726825Y91441D01*
X1726723Y91420D01*
X1726382Y91124D01*
X1726347Y91026D01*
X1726357Y90972D01*
G02X1726386Y90650I-1773J-322D01*
G02X1724584Y92452I-1802J0D01*
G02X1725298Y92305I1J-1802D01*
G01X1725347Y92283D01*
X1725451Y92295D01*
X1725817Y92560D01*
X1725860Y92655D01*
G37*
G36*
G01X1750614Y100457D02*
G02X1749954Y101701I842J1244D01*
G02X1752958I1502J0D01*
G02X1752298Y100457I-1502J0D01*
G03Y99795I224J-331D01*
G02X1752958Y98551I-842J-1244D01*
G02X1749954I-1502J0D01*
G02X1750614Y99795I1502J0D01*
G03Y100457I-224J331D01*
G37*
G36*
G01X1743026Y108025D02*
G02X1742444Y107908I-581J1385D01*
G02Y110912I0J1502D01*
G02X1743932Y109616I0J-1502D01*
G01X1743938Y109569D01*
X1743991Y109492D01*
X1744350Y109290D01*
X1744443Y109285D01*
X1744487Y109304D01*
G02X1745202Y109452I715J-1655D01*
G02X1747004Y107649I-1J-1803D01*
G01Y104249D01*
G02X1745202Y102446I-1802J-1D01*
G02X1744499Y102589I1J1803D01*
G01X1744454Y102608D01*
X1744357Y102601D01*
X1743996Y102375D01*
X1743946Y102291D01*
X1743944Y102242D01*
G02X1742444Y100821I-1500J81D01*
G02Y103825I0J1502D01*
G02X1742885Y103759I1J-1502D01*
G01X1742932Y103744D01*
X1743028Y103762D01*
X1743363Y104023D01*
X1743404Y104112D01*
X1743402Y104161D01*
G02X1743400Y104249I1800J85D01*
G01Y107649D01*
G02X1743403Y107759I1802J6D01*
G03X1743318Y107935I-200J12D01*
G01X1743218Y108005D01*
G03X1743026Y108025I-114J-164D01*
G37*
G36*
G01X1763367Y379082D02*
X1763667Y379353D01*
X1763701Y379437D01*
X1763698Y379483D01*
G02X1763695Y379591I1799J104D01*
G02X1765497Y377789I1802J0D01*
G02X1765005Y377857I-2J1802D01*
G01X1764961Y377870D01*
X1764872Y377855D01*
X1764543Y377620D01*
X1764499Y377541D01*
X1764497Y377495D01*
G02X1762997Y376079I-1500J86D01*
G02Y379083I0J1502D01*
G02X1763235Y379064I0J-1502D01*
G01X1763281Y379057D01*
X1763367Y379082D01*
G37*
G36*
G01X1803499Y434358D02*
X1803308Y434652D01*
X1803246Y434697D01*
X1803209Y434706D01*
G02X1802068Y436164I361J1458D01*
G02X1805072I1502J0D01*
G02X1805047Y435893I-1502J2D01*
G01X1805041Y435856D01*
X1805055Y435781D01*
X1805246Y435487D01*
X1805308Y435442D01*
X1805345Y435433D01*
G02X1806486Y433975I-361J-1458D01*
G02X1805374Y432525I-1501J0D01*
G01X1805330Y432513D01*
X1805261Y432454D01*
X1805099Y432083D01*
X1805103Y431993D01*
X1805124Y431952D01*
G02X1805332Y431112I-1594J-840D01*
G02X1801728I-1802J0D01*
G02X1803268Y432895I1802J0D01*
G01X1803313Y432902D01*
X1803388Y432952D01*
X1803592Y433302D01*
X1803599Y433391D01*
X1803583Y433434D01*
G02X1803482Y433975I1401J541D01*
G02X1803507Y434246I1502J-2D01*
G01X1803513Y434283D01*
X1803499Y434358D01*
G37*
G36*
G01X1815686Y1095640D02*
X1815712Y1096014D01*
X1815684Y1096092D01*
X1815656Y1096122D01*
G02X1815254Y1097145I1101J1023D01*
G02X1818258I1502J0D01*
G02X1817856Y1096122I-1503J0D01*
G01X1817828Y1096092D01*
X1817800Y1096014D01*
X1817826Y1095640D01*
X1817864Y1095567D01*
X1817896Y1095540D01*
G02X1818558Y1094145I-1139J-1395D01*
G02X1814954I-1802J0D01*
G02X1815616Y1095540I1801J0D01*
G01X1815648Y1095567D01*
X1815686Y1095640D01*
G37*
G36*
G01X1795927Y1264627D02*
X1796263D01*
X1796330Y1264652D01*
X1796358Y1264676D01*
G02X1798332I987J-1131D01*
G01X1798360Y1264652D01*
X1798427Y1264627D01*
X1798763D01*
X1798830Y1264652D01*
X1798858Y1264676D01*
G02X1799845Y1265046I987J-1131D01*
G02X1801347Y1263544I0J-1502D01*
G02X1800977Y1262557I-1501J0D01*
G01X1800953Y1262529D01*
X1800928Y1262462D01*
Y1262126D01*
X1800953Y1262059D01*
X1800977Y1262031D01*
G02X1801347Y1261044I-1131J-987D01*
G02X1799845Y1259542I-1502J0D01*
G02X1798858Y1259912I0J1501D01*
G01X1798830Y1259936D01*
X1798763Y1259961D01*
X1798427D01*
X1798360Y1259936D01*
X1798332Y1259912D01*
G02X1796358I-987J1131D01*
G01X1796330Y1259936D01*
X1796263Y1259961D01*
X1795927D01*
X1795860Y1259936D01*
X1795832Y1259912D01*
G02X1794845Y1259542I-987J1131D01*
G02X1793343Y1261044I0J1502D01*
G02X1793713Y1262031I1501J0D01*
G01X1793737Y1262059D01*
X1793762Y1262126D01*
Y1262462D01*
X1793737Y1262529D01*
X1793713Y1262557D01*
G02X1793343Y1263544I1131J987D01*
G02X1794845Y1265046I1502J0D01*
G02X1795832Y1264676I0J-1501D01*
G01X1795860Y1264652D01*
X1795927Y1264627D01*
G37*
G54D123*
X1785918Y216864D03*
Y221864D03*
X1774679Y221642D03*
X1763112Y256535D03*
X1759112Y256303D03*
X1755112Y256535D03*
X1697984Y226320D03*
X1707086Y247292D03*
X1699876Y236121D03*
X1696910Y238589D03*
X1706312Y238689D03*
X1704671Y242078D03*
X1699795Y253198D03*
X1712866Y213539D03*
X1714547Y238714D03*
X1710547D03*
X1712248Y244297D03*
X1683556Y212864D03*
Y221864D03*
Y216864D03*
X1685313Y252371D03*
Y248371D03*
X1672317Y221642D03*
X1660750Y256535D03*
X1652750D03*
X1656750Y256303D03*
X1604724Y247292D03*
X1597514Y236121D03*
X1612185Y238714D03*
X1603950Y238689D03*
X1608185Y238714D03*
X1602309Y242078D03*
X1609886Y244297D03*
X1597433Y253198D03*
X1610504Y213539D03*
X1581194Y212864D03*
Y221864D03*
Y216864D03*
X1595622Y226320D03*
X1594548Y238589D03*
X1582951Y252371D03*
Y248371D03*
X1569955Y221642D03*
X1550388Y256535D03*
X1558388D03*
X1554388Y256303D03*
X1508142Y213539D03*
X1509823Y238714D03*
X1502362Y247292D03*
X1501588Y238689D03*
X1505823Y238714D03*
X1499947Y242078D03*
X1507524Y244297D03*
X1493260Y226320D03*
X1492186Y238589D03*
X1495152Y236121D03*
X1495071Y253198D03*
X1478832Y212864D03*
Y216864D03*
Y221864D03*
X1467593Y221642D03*
X1480589Y252371D03*
Y248371D03*
X1456026Y256535D03*
X1452026Y256303D03*
X1448026Y256535D03*
X1405780Y213539D03*
X1407461Y238714D03*
X1403461D03*
X1405162Y244297D03*
X1390898Y226320D03*
X1400000Y247292D03*
X1399226Y238689D03*
X1392790Y236121D03*
X1389824Y238589D03*
X1397585Y242078D03*
X1392709Y253198D03*
X1378227Y252371D03*
Y248371D03*
X1328831Y212864D03*
Y221864D03*
Y216864D03*
X1317592Y221642D03*
X1306025Y256535D03*
X1298025D03*
X1302025Y256303D03*
X1255779Y213539D03*
X1257460Y238714D03*
X1255161Y244297D03*
X1240897Y226320D03*
X1249999Y247292D03*
X1239823Y238589D03*
X1242789Y236121D03*
X1253460Y238714D03*
X1247584Y242078D03*
X1242708Y253198D03*
X1226469Y212864D03*
Y216864D03*
Y221864D03*
X1228226Y252371D03*
Y248371D03*
X1215230Y221642D03*
X1199663Y256303D03*
X1203663Y256535D03*
X1195663D03*
X1153417Y213539D03*
X1146863Y238689D03*
X1155098Y238714D03*
X1147637Y247292D03*
X1151098Y238714D03*
X1145222Y242078D03*
X1152799Y244297D03*
X1138535Y226320D03*
X1137461Y238589D03*
X1140427Y236121D03*
X1140346Y253198D03*
X1125864Y252371D03*
Y248371D03*
X1124107Y212864D03*
Y216864D03*
Y221864D03*
X1112868Y221642D03*
X1101301Y256535D03*
X1093301D03*
X1097301Y256303D03*
X1051055Y213539D03*
X1044501Y238689D03*
X1045275Y247292D03*
X1052736Y238714D03*
X1048736D03*
X1050437Y244297D03*
X1036173Y226320D03*
X1038065Y236121D03*
X1035099Y238589D03*
X1042860Y242078D03*
X1037984Y253198D03*
X1021745Y212864D03*
Y221864D03*
Y216864D03*
X1023502Y252371D03*
Y248371D03*
X1010506Y221642D03*
X994939Y256303D03*
X951040Y223885D03*
X947040D03*
X951278Y250583D03*
X938125Y230891D03*
X942805Y223860D03*
X936369Y221292D03*
X940158Y245707D03*
X933403Y245507D03*
X946064Y252998D03*
X919577Y245669D03*
Y255118D03*
X910977Y238583D03*
Y252756D03*
X891383Y243203D03*
X896034Y243307D03*
X871745Y212864D03*
Y216864D03*
Y221864D03*
X860506Y221642D03*
X848939Y256535D03*
X840939D03*
X844939Y256303D03*
X800374Y238714D03*
X798693Y213539D03*
X792913Y247292D03*
X792139Y238689D03*
X785703Y236121D03*
X796374Y238714D03*
X790498Y242078D03*
X785622Y253198D03*
X769383Y212864D03*
Y221864D03*
X783811Y226320D03*
X769383Y216864D03*
X782737Y238589D03*
X771140Y252371D03*
Y248371D03*
X758144Y221642D03*
X763653Y224536D03*
X738577Y256535D03*
X746577D03*
X742577Y256303D03*
X696331Y213539D03*
X698012Y238714D03*
X689777Y238689D03*
X690551Y247292D03*
X694012Y238714D03*
X688136Y242078D03*
X681449Y226320D03*
X680375Y238589D03*
X683341Y236121D03*
X683260Y253198D03*
X667021Y212864D03*
Y221864D03*
Y216864D03*
X655782Y221642D03*
X668778Y252371D03*
X668886Y248371D03*
X644215Y256535D03*
X640215Y256303D03*
X636215Y256535D03*
X593969Y213539D03*
X595650Y238714D03*
X591650D03*
X579087Y226320D03*
X587415Y238689D03*
X588189Y247292D03*
X580979Y236121D03*
X578013Y238589D03*
X585774Y242078D03*
X580898Y253198D03*
X564659Y212864D03*
Y221864D03*
Y216864D03*
X566416Y252371D03*
Y248371D03*
X553420Y221642D03*
X541853Y256535D03*
X533853D03*
X537853Y256303D03*
X478536Y253198D03*
X493288Y238714D03*
X491607Y213539D03*
X476725Y226320D03*
X485827Y247292D03*
X478617Y236121D03*
X475651Y238589D03*
X485053Y238689D03*
X483412Y242078D03*
X489288Y238714D03*
X464054Y252371D03*
Y248371D03*
X414658Y212864D03*
Y216864D03*
Y221864D03*
X403419Y221642D03*
X391852Y256535D03*
X383852D03*
X387852Y256303D03*
X335052Y238689D03*
X335826Y247292D03*
X343287Y238714D03*
X339287D03*
X333411Y242078D03*
X341606Y213539D03*
X326724Y226320D03*
X325650Y238589D03*
X328616Y236121D03*
X328535Y253198D03*
X314053Y252371D03*
Y248371D03*
X312296Y212864D03*
Y221864D03*
Y216864D03*
X301057Y221642D03*
X281490Y256535D03*
X289490D03*
X285490Y256303D03*
X226173Y253198D03*
X239244Y213539D03*
X232690Y238689D03*
X240925Y238714D03*
X233464Y247292D03*
X236925Y238714D03*
X238626Y244297D03*
X224362Y226320D03*
X226254Y236121D03*
X223288Y238589D03*
X231049Y242078D03*
X209934Y212864D03*
Y216864D03*
Y221864D03*
X211691Y252371D03*
Y248371D03*
X198695Y221642D03*
X187128Y256535D03*
X183128Y256303D03*
X179128Y256535D03*
X124961Y228646D03*
X131102Y247292D03*
X130328Y238689D03*
X123892Y236121D03*
X120926Y238589D03*
X128687Y242078D03*
X123811Y253198D03*
X136882Y213539D03*
X134563Y238714D03*
X107572Y212864D03*
Y216864D03*
Y221864D03*
X109329Y252371D03*
Y248371D03*
X122000Y226320D03*
X96333Y221642D03*
X76766Y256535D03*
X84766D03*
X80766Y256303D03*
X36201Y238714D03*
X21530Y236121D03*
X27966Y238689D03*
X28740Y247292D03*
X32201Y238714D03*
X23844Y239299D03*
X33902Y244297D03*
X21449Y253198D03*
X34520Y213539D03*
X19638Y226320D03*
X18564Y238589D03*
X34845Y291756D03*
X26629Y295619D03*
X31682Y266874D03*
X359376Y290592D03*
X718338Y305272D03*
X805952Y301675D03*
X876622Y293721D03*
X895140Y265236D03*
X85904Y152367D03*
X73381Y94017D03*
X69381D03*
X77804Y95879D03*
X76660Y103783D03*
X80660D03*
X75194Y141247D03*
X71422Y147540D03*
Y151540D03*
X83756Y168697D03*
X64098Y137756D03*
X51550Y90615D03*
X46240Y109410D03*
X45988Y102323D03*
X46240Y116496D03*
X46931Y130670D03*
X49236Y121658D03*
X46932Y137756D03*
X52437D03*
X45984Y163264D03*
X55921Y95236D03*
X56098Y109410D03*
Y116496D03*
X64098D03*
X56098Y123583D03*
Y130670D03*
X64098Y123583D03*
Y130670D03*
X48596Y458466D03*
X41643Y473419D03*
X59670Y500086D03*
X40009Y481467D03*
X45643Y472905D03*
X58224Y473045D03*
X66224D03*
X71730Y579475D03*
X157090Y562003D03*
X157375Y555234D03*
X186118Y168697D03*
X188820Y80140D03*
Y84140D03*
X183752Y94017D03*
X183022Y103783D03*
X185957Y106186D03*
X188266Y152367D03*
X179743Y94017D03*
X175743D03*
X171743D03*
X179022Y103783D03*
X173784Y147540D03*
X177556Y141247D03*
X173784Y151540D03*
X158283Y95236D03*
X158460Y116496D03*
Y109410D03*
X166460Y116496D03*
X158460Y130670D03*
Y123583D03*
X166460D03*
Y130670D03*
X155051Y137756D03*
X166460D03*
X148350Y95236D03*
X148602Y109410D03*
Y116496D03*
X148350Y102323D03*
X148774Y124576D03*
X149827Y130670D03*
X149822Y137756D03*
X397315Y479560D03*
X393746Y478382D03*
X393652Y482382D03*
X292316Y486752D03*
X284516D03*
X220349Y465622D03*
X221375Y455024D03*
X228267Y400718D03*
Y408718D03*
Y392718D03*
X257993Y307994D03*
X257226Y312081D03*
X265011Y410394D03*
X286940Y315039D03*
X310013Y316731D03*
X315904Y336324D03*
X323882Y303839D03*
X306673Y418838D03*
X306812Y342319D03*
X302966Y324139D03*
X345050Y454334D03*
Y458334D03*
X366443Y472189D03*
X376099Y462309D03*
Y454309D03*
Y458309D03*
X393837Y466409D03*
X397315Y471560D03*
X274205Y509626D03*
X274163Y495088D03*
X274347Y489435D03*
X284516Y509626D03*
X292316D03*
X284516Y493839D03*
X292316D03*
X373971Y489036D03*
X393823Y487382D03*
X250336Y456386D03*
X249125Y465874D03*
X266405Y493839D03*
X288480Y168697D03*
X291182Y84140D03*
Y80140D03*
X282105Y94017D03*
X286114D03*
X285384Y103783D03*
X288319Y106186D03*
X281384Y103783D03*
X290628Y152367D03*
X268822Y116496D03*
Y130670D03*
Y123583D03*
Y137756D03*
X276146Y147540D03*
X279918Y141247D03*
X276146Y151540D03*
X260645Y95236D03*
X250712D03*
X250964Y109410D03*
X250712Y102323D03*
X250964Y116496D03*
X260822D03*
Y109410D03*
X251136Y124576D03*
X260822Y130670D03*
Y123583D03*
X252189Y130670D03*
X257413Y137756D03*
X252184D03*
X274105Y94017D03*
X278105D03*
X361767Y392228D03*
X376992Y395248D03*
X364551Y409032D03*
X361811Y396866D03*
X368587Y401066D03*
X357173Y392183D03*
X357218Y396866D03*
X361234Y402867D03*
X393544Y84140D03*
Y80140D03*
X384467Y94017D03*
X388476D03*
X380467D03*
X390681Y106186D03*
X387746Y103783D03*
X383746D03*
X390842Y168697D03*
X376467Y94017D03*
X363007Y95236D03*
X363184Y116496D03*
Y109410D03*
X371184Y116496D03*
X363184Y130670D03*
Y123583D03*
X371184Y130670D03*
Y123583D03*
Y137756D03*
X353074Y95236D03*
Y102323D03*
X353326Y109410D03*
Y116496D03*
X353498Y124576D03*
X354551Y130670D03*
X359525Y137756D03*
X354546D03*
X396306Y864409D03*
X396182Y955858D03*
X392910Y948536D03*
X385467Y959950D03*
X390150Y959905D03*
X385512Y955356D03*
X390150Y955312D03*
X413432Y346797D03*
X456469Y638302D03*
X509471Y981608D03*
X514690Y996766D03*
Y1004766D03*
X514649Y1020266D03*
X506566Y1016266D03*
Y1000766D03*
Y1004766D03*
X448999Y994483D03*
X543545Y84140D03*
Y80140D03*
X540682Y106186D03*
X544089Y146461D03*
X542991Y152367D03*
X540843Y168697D03*
X526468Y94017D03*
X537747Y103783D03*
X533747D03*
X532281Y141247D03*
X528509Y147540D03*
Y151540D03*
X513185Y116496D03*
Y109410D03*
X521185Y116496D03*
X513185Y130670D03*
Y123583D03*
X521185Y130670D03*
Y123583D03*
X509251Y137756D03*
X521185D03*
X534468Y94017D03*
X538477D03*
X530468D03*
X503075Y95236D03*
Y102323D03*
X503327Y109410D03*
Y116496D03*
X506653Y121652D03*
X504552Y130670D03*
X504547Y137756D03*
X513008Y95236D03*
X516756Y500086D03*
X508729Y469905D03*
X521310Y470045D03*
X513310D03*
X517310D03*
X500729Y469905D03*
X496729Y470419D03*
X497095Y481467D03*
X614176Y562003D03*
X614461Y555234D03*
X591872Y1518071D03*
X645907Y84140D03*
Y80140D03*
X640839Y94017D03*
X640109Y103783D03*
X643044Y106186D03*
X646451Y146461D03*
X645353Y152367D03*
X643205Y168697D03*
X636830Y94017D03*
X628830D03*
X632830D03*
X623547Y116496D03*
X636109Y103783D03*
X623547Y123583D03*
Y130670D03*
Y137756D03*
X630871Y147540D03*
X634643Y141247D03*
X630871Y151540D03*
X615370Y95236D03*
X605437D03*
Y102323D03*
X605689Y109410D03*
Y116496D03*
X615547D03*
Y109410D03*
X605861Y124576D03*
X615547Y130670D03*
Y123583D03*
X606914Y130670D03*
X606909Y137756D03*
X612138D03*
X747715Y152367D03*
X745567Y168697D03*
X748269Y84140D03*
Y80140D03*
X743201Y94017D03*
X739192D03*
X742471Y103783D03*
X738471D03*
X745406Y106186D03*
X748813Y146461D03*
X737005Y141247D03*
X725909Y130670D03*
Y123583D03*
Y137756D03*
X733233Y147540D03*
Y151540D03*
X735192Y94017D03*
X731192D03*
X725909Y116496D03*
X717732Y95236D03*
X707799D03*
Y102323D03*
X708051Y109410D03*
Y116496D03*
X717909D03*
Y109410D03*
X708223Y124576D03*
X717909Y130670D03*
Y123583D03*
X709276Y130670D03*
X714500Y137756D03*
X709271D03*
X744924Y1617709D03*
X735878Y1617010D03*
X748924Y1617709D03*
X771383Y1616917D03*
X747590Y1627871D03*
X743331D03*
X752150D03*
X773822Y1627418D03*
X762776Y1629415D03*
X861468Y491303D03*
X858169Y495032D03*
X833269Y506683D03*
X823529Y467189D03*
X850738Y477382D03*
X861468Y483303D03*
X850832Y473382D03*
X850909Y482382D03*
X850631Y84140D03*
Y80140D03*
X841554Y94017D03*
X837554D03*
X845563D03*
X833554D03*
X844833Y103783D03*
X847768Y106186D03*
X840833Y103783D03*
X847929Y168697D03*
X820094Y95236D03*
X820271Y116496D03*
Y109410D03*
X828271Y116496D03*
X820271Y130670D03*
Y123583D03*
X828271Y130670D03*
Y123583D03*
X816637Y137756D03*
X828271D03*
X810161Y95236D03*
Y102323D03*
X810413Y109410D03*
Y116496D03*
X810585Y124576D03*
X811638Y130670D03*
X811633Y137756D03*
X862020Y410899D03*
X916992Y1076659D03*
X916749Y1084659D03*
X916875Y1098643D03*
X916749Y1104659D03*
X909077Y1232724D03*
X899699Y1283872D03*
X931627Y577578D03*
Y573578D03*
X921217Y589216D03*
X913998Y597103D03*
X917803Y811365D03*
X913716Y811954D03*
X980726Y1092664D03*
Y1088659D03*
Y1084659D03*
X965716Y1091346D03*
X965671Y1095940D03*
X961033Y1091391D03*
Y1095984D03*
X986645Y1108465D03*
X1093474Y1638213D03*
X1101474Y1637820D03*
X1085474Y1629028D03*
X1082176Y1600598D03*
X1104233Y1587983D03*
X1086469Y1588435D03*
X1107620Y1603602D03*
X995563Y94017D03*
X997768Y106186D03*
X1000077Y152367D03*
X997929Y168697D03*
X1000631Y84140D03*
Y80140D03*
X983554Y94017D03*
X987554D03*
X991554D03*
X994833Y103783D03*
X990833D03*
X985595Y147540D03*
X989367Y141247D03*
X985595Y151540D03*
X961638Y130670D03*
X961633Y137756D03*
X970094Y95236D03*
X970271Y116496D03*
Y109410D03*
X978271Y116496D03*
X970271Y130670D03*
Y123583D03*
X978271Y130670D03*
Y123583D03*
X963360Y121459D03*
X966347Y137756D03*
X978271D03*
X960161Y95236D03*
Y102323D03*
X960413Y109410D03*
Y116496D03*
X959816Y472905D03*
X954182Y481467D03*
X955816Y473419D03*
X950315Y464851D03*
X962769Y458466D03*
X973843Y500086D03*
X964012Y546830D03*
X1055885Y554555D03*
X1071263Y562003D03*
X1071548Y555234D03*
X1102993Y84140D03*
Y80140D03*
X1097925Y94017D03*
X1093916D03*
X1097195Y103783D03*
X1093195D03*
X1100130Y106186D03*
X1102439Y152367D03*
X1100291Y168697D03*
X1080633Y116496D03*
Y130670D03*
Y123583D03*
Y137756D03*
X1087957Y147540D03*
X1091729Y141247D03*
X1087957Y151540D03*
X1089916Y94017D03*
X1085916D03*
X1072456Y95236D03*
X1062523D03*
Y102323D03*
X1062775Y109410D03*
Y116496D03*
X1072633D03*
Y109410D03*
X1062947Y124576D03*
X1072633Y130670D03*
Y123583D03*
X1064000Y130670D03*
X1069224Y137756D03*
X1063995D03*
X1804758Y294429D03*
X1793524Y303343D03*
X1805196Y300952D03*
X1700223Y292141D03*
X1703609Y287320D03*
X1698292Y303962D03*
X1596691Y287397D03*
X1596197Y293477D03*
X1503884Y295549D03*
X1497446Y295877D03*
X1348419Y265222D03*
X1340104Y279117D03*
X1544736Y305156D03*
X1271571Y281185D03*
X1266962Y302167D03*
X1262665Y302730D03*
X1263328Y309003D03*
X1179901Y306366D03*
X1181706Y310131D03*
X1173559Y304948D03*
X1787674Y303130D03*
X1090876Y1554183D03*
X1100876D03*
X1199557Y103783D03*
X1202492Y106186D03*
X1195557Y103783D03*
X1190319Y147540D03*
X1194091Y141247D03*
X1204801Y152367D03*
X1190319Y151540D03*
X1202653Y168697D03*
X1205355Y84140D03*
Y80140D03*
X1196278Y94017D03*
X1200287D03*
X1192278D03*
X1188278D03*
X1174818Y95236D03*
X1174995Y116496D03*
Y109410D03*
X1182995Y116496D03*
X1174995Y130670D03*
Y123583D03*
X1182995Y130670D03*
Y123583D03*
Y137756D03*
X1164885Y95236D03*
Y102323D03*
X1165137Y109410D03*
Y116496D03*
X1165309Y124576D03*
X1166362Y130670D03*
X1171586Y137756D03*
X1166357D03*
X1308010Y466409D03*
X1311488Y471560D03*
X1290272Y458309D03*
Y454309D03*
Y462309D03*
X1280616Y472189D03*
X1259223Y454334D03*
Y458334D03*
X1311488Y479560D03*
X1307919Y478382D03*
X1263873Y1148000D03*
X1307717Y84140D03*
Y80140D03*
X1304854Y106186D03*
X1305015Y168697D03*
X1302649Y94017D03*
X1298640D03*
X1290640D03*
X1294640D03*
X1301919Y103783D03*
X1297919D03*
X1285357Y123583D03*
X1273555Y137756D03*
X1285357D03*
X1267499Y116496D03*
X1267671Y124576D03*
X1268724Y130670D03*
X1268719Y137756D03*
X1277180Y95236D03*
X1277357Y116496D03*
Y109410D03*
X1285357Y116496D03*
X1277357Y130670D03*
Y123583D03*
X1285357Y130670D03*
X1267247Y95236D03*
Y102323D03*
X1267499Y109410D03*
X1291165Y395248D03*
X1275940Y392228D03*
X1271346Y392183D03*
X1275407Y402867D03*
X1271391Y396866D03*
X1275984D03*
X1278724Y409032D03*
X1282760Y401066D03*
X1285500Y855500D03*
Y859500D03*
Y863500D03*
X1285493Y892175D03*
X1279539Y772576D03*
X1281388Y827388D03*
X1285500Y827500D03*
Y835500D03*
X1281331Y843331D03*
X1283025Y848305D03*
X1329626Y455039D03*
X1316017Y349889D03*
X1308857Y836076D03*
X1413500Y900000D03*
Y904000D03*
Y852000D03*
Y856000D03*
Y860000D03*
Y864000D03*
Y868000D03*
Y872000D03*
Y888000D03*
X1457718Y84140D03*
Y80140D03*
X1452650Y94017D03*
X1451920Y103783D03*
X1454855Y106186D03*
X1457164Y152367D03*
X1455016Y168697D03*
X1444641Y94017D03*
X1448641D03*
X1435358Y116496D03*
X1447920Y103783D03*
X1435358Y130670D03*
Y123583D03*
Y137756D03*
X1442682Y147540D03*
X1446454Y141247D03*
X1442682Y151540D03*
X1427181Y95236D03*
X1417500Y109410D03*
Y116496D03*
X1427358D03*
Y109410D03*
X1421700Y122900D03*
X1427358Y130670D03*
Y123583D03*
X1418725Y130670D03*
X1423515Y137756D03*
X1418720D03*
X1440641Y94017D03*
X1417248Y95236D03*
Y102323D03*
X1430930Y500086D03*
X1435484Y470045D03*
X1427484D03*
X1422903Y469905D03*
X1431484Y470045D03*
X1414903Y469905D03*
X1411269Y481467D03*
X1425558Y1537432D03*
X1425260Y1558072D03*
X1436801Y1568803D03*
X1423806Y1524252D03*
X1437293Y1546125D03*
X1404239Y1547755D03*
X1423701Y1563978D03*
X1424245Y1543338D03*
X1433558Y1555366D03*
X1528350Y562003D03*
X1528635Y555234D03*
X1570331Y691851D03*
X1568872Y686971D03*
X1575942Y705043D03*
X1478710Y685630D03*
X1578000Y678776D03*
X1557378Y168697D03*
X1560080Y84140D03*
Y80140D03*
X1555012Y94017D03*
X1551003D03*
X1554282Y103783D03*
X1550282D03*
X1557217Y106186D03*
X1548816Y141247D03*
X1559526Y152367D03*
X1547003Y94017D03*
X1543003D03*
X1537720Y116496D03*
Y130670D03*
Y123583D03*
Y137756D03*
X1545044Y147540D03*
Y151540D03*
X1529543Y95236D03*
X1519610D03*
Y102323D03*
X1519862Y109410D03*
Y116496D03*
X1529720D03*
Y109410D03*
X1520034Y124576D03*
X1529720Y130670D03*
Y123583D03*
X1521087Y130670D03*
X1526311Y137756D03*
X1521082D03*
X1750879Y541940D03*
X1710174Y553101D03*
X1689920Y539315D03*
X1692379Y622912D03*
X1693000Y626912D03*
X1656112Y768669D03*
X1657042Y773604D03*
X1614538Y618288D03*
X1627224Y643252D03*
X1619950Y678519D03*
X1616260Y678462D03*
X1611316Y685800D03*
X1616622Y542712D03*
Y546712D03*
X1611327Y735973D03*
X1615913Y692245D03*
X1630327Y774627D03*
X1628027Y801427D03*
X1629927Y787327D03*
X1635283Y728117D03*
X1613117Y828117D03*
X1628200Y711417D03*
X1612800Y705900D03*
X1789363Y969160D03*
X1802000Y892447D03*
X1780016Y874400D03*
X1746884Y884649D03*
X1746600Y935100D03*
X1750915Y902055D03*
X1749267Y918413D03*
X1789537Y930498D03*
X1746897Y879199D03*
X1741800Y917900D03*
X1793474Y930374D03*
X1775904Y924546D03*
X1751200Y931100D03*
X1778047Y916120D03*
X1648375Y886766D03*
X1648387Y945554D03*
X1551163Y952888D03*
X1647470Y952125D03*
X1650205Y925911D03*
X1647763Y919268D03*
X1797365Y930761D03*
X1765083Y487382D03*
X1745231Y489036D03*
X1663576Y493839D03*
Y509626D03*
X1645607Y489435D03*
X1645423Y495088D03*
X1655776Y493839D03*
X1645465Y509626D03*
X1655776D03*
X1637665Y493839D03*
X1765097Y466409D03*
X1768586Y467560D03*
X1747359Y454309D03*
Y458309D03*
Y462309D03*
X1737703Y472189D03*
X1716310Y458334D03*
Y454334D03*
X1681273Y316731D03*
X1691117Y321649D03*
X1677810Y324466D03*
X1687164Y336324D03*
X1678072Y342319D03*
X1686408Y332584D03*
X1677933Y418838D03*
X1674226Y324139D03*
X1673723Y353881D03*
X1670323Y353534D03*
X1663760Y410394D03*
X1658200Y315039D03*
X1654771Y352088D03*
X1635987Y335616D03*
X1640030Y335550D03*
X1640197Y374690D03*
X1636271Y410394D03*
X1598223Y351003D03*
X1602138Y351047D03*
X1599527Y392718D03*
Y408718D03*
Y400718D03*
X1626147Y351033D03*
X1621596Y456386D03*
X1592635Y455911D03*
X1591443Y465332D03*
X1764912Y482382D03*
X1768575Y479560D03*
X1765006Y478382D03*
X1655776Y486752D03*
Y479665D03*
X1645607Y482666D03*
Y475262D03*
X1663576Y479665D03*
Y486752D03*
Y472579D03*
X1662442Y84140D03*
Y80140D03*
X1661888Y152367D03*
X1647406Y151540D03*
X1659740Y168697D03*
X1649365Y94017D03*
X1657374D03*
X1653365D03*
X1645365D03*
X1656644Y103783D03*
X1659579Y106186D03*
X1652644Y103783D03*
X1647406Y147540D03*
X1651178Y141247D03*
X1631905Y95236D03*
X1632082Y116496D03*
Y109410D03*
X1640082Y116496D03*
X1632082Y130670D03*
Y123583D03*
X1640082Y130670D03*
Y123583D03*
X1628673Y137756D03*
X1640082D03*
X1621972Y95236D03*
Y102323D03*
X1622224Y109410D03*
Y116496D03*
X1622396Y124576D03*
X1623449Y130670D03*
X1623444Y137756D03*
X1759006Y103783D03*
X1761941Y106186D03*
X1762102Y168697D03*
X1764804Y84140D03*
Y80140D03*
X1759736Y94017D03*
X1755727D03*
X1747727D03*
X1751727D03*
X1742444Y116496D03*
X1755006Y103783D03*
X1742444Y130670D03*
Y123583D03*
Y137756D03*
X1734267Y95236D03*
X1734444Y116496D03*
Y109410D03*
Y130670D03*
Y123583D03*
X1730647Y137756D03*
X1724334Y95236D03*
Y102323D03*
X1724586Y109410D03*
Y116496D03*
X1724758Y124576D03*
X1725811Y130670D03*
X1725806Y137756D03*
X1748252Y395248D03*
X1733027Y392228D03*
X1728433Y392183D03*
X1735811Y409032D03*
X1732494Y402867D03*
X1728478Y396866D03*
X1733071D03*
X1739847Y401066D03*
X1824706Y1093150D03*
X1811482Y1226423D03*
X1824949Y1077145D03*
X1824706Y1085145D03*
Y1100185D03*
Y1106145D03*
G54D128*
X292500Y410394D03*
X292316Y479665D03*
X284516D03*
X292316Y472579D03*
X274347Y482666D03*
Y475262D03*
X978614Y1210568D03*
Y1214838D03*
X914637Y1210568D03*
Y1214838D03*
X976397Y473045D03*
X980397D03*
G54D127*
X180610Y1133169D03*
Y1129429D03*
Y1125688D03*
Y1140649D03*
X173129Y1129428D03*
Y1140649D03*
X176870Y1136909D03*
Y1133169D03*
Y1129429D03*
Y1125688D03*
Y1140649D03*
X173129Y1133169D03*
X180610Y1121948D03*
Y1118208D03*
X176870Y1121948D03*
Y1118208D03*
X173129Y1144389D03*
X180610Y1136909D03*
X270373Y1144389D03*
Y1148129D03*
Y1151869D03*
X277854Y1133169D03*
X637697D03*
Y1118208D03*
Y1121948D03*
Y1136909D03*
Y1125688D03*
Y1129429D03*
X630216Y1118208D03*
X626476D03*
X633957D03*
Y1121948D03*
Y1140649D03*
Y1125688D03*
Y1129429D03*
Y1133169D03*
Y1136909D03*
X630216Y1140649D03*
Y1129428D03*
Y1136909D03*
Y1144389D03*
X727460Y1151869D03*
Y1148129D03*
Y1144389D03*
X734941Y1133169D03*
X1094783Y1136909D03*
Y1133169D03*
Y1129429D03*
Y1125688D03*
Y1121948D03*
Y1118208D03*
X1083562D03*
X1087302D03*
X1091043Y1121948D03*
Y1118208D03*
Y1125688D03*
Y1140649D03*
X1087302Y1129428D03*
Y1140649D03*
X1091043Y1136909D03*
Y1133169D03*
Y1129429D03*
X1087302Y1144389D03*
X1184546Y1151869D03*
Y1148129D03*
Y1144389D03*
X1192027Y1133169D03*
X1544389Y1144389D03*
Y1129428D03*
Y1140649D03*
X1540649Y1118208D03*
X1544389D03*
X1548130Y1121948D03*
X1551870D03*
X1548130Y1118208D03*
X1551870D03*
Y1140649D03*
X1548130Y1136909D03*
X1551870D03*
X1548130Y1133169D03*
X1551870D03*
X1548130Y1129429D03*
X1551870D03*
X1548130Y1125688D03*
X1551870D03*
X1548130Y1140649D03*
X1641633Y1151869D03*
Y1148129D03*
Y1144389D03*
X1649114Y1133169D03*
G54D133*
X1329504Y842470D03*
X1332654Y855068D03*
X1329504D03*
X1326355D03*
X1323204Y855067D03*
X1320055Y855068D03*
X1329504Y851918D03*
X1326355D03*
X1323205D03*
X1320055D03*
X1329504Y848769D03*
X1326355D03*
X1323205D03*
X1320055D03*
X1329504Y845619D03*
X1326355D03*
X1323205D03*
X1320055D03*
X1326355Y842470D03*
X1323205D03*
X1313756Y855066D03*
X1316906Y855068D03*
X1313756Y848769D03*
X1310555Y848675D03*
X1316906Y848769D03*
X1354699D03*
X1345252D03*
X1342103D03*
X1351550D03*
Y880263D03*
X1345252D03*
X1351550Y883413D03*
X1373597Y880263D03*
X1376747D03*
Y877114D03*
X1370447D03*
X1373597D03*
X1376747Y873964D03*
X1373598Y873965D03*
X1370447Y873964D03*
X1367298D03*
X1364148Y870814D03*
X1367298D03*
X1376747D03*
Y867665D03*
X1364148D03*
X1367298D03*
X1364148Y861367D03*
X1373597D03*
X1376747D03*
X1367298D03*
X1373597Y858218D03*
X1376747D03*
X1370447D03*
X1367298D03*
X1364148D03*
X1367298Y855068D03*
X1370447D03*
X1373598Y855067D03*
X1376747Y855068D03*
X1367298Y851918D03*
X1370447D03*
X1373597D03*
X1376747D03*
X1367298Y848769D03*
X1370447D03*
X1373597D03*
X1376747D03*
X1370447Y845619D03*
X1373597D03*
X1383046Y842470D03*
X1379896Y848769D03*
X1383046Y845619D03*
Y861367D03*
Y858218D03*
X1379896Y851918D03*
X1383046D03*
X1379896Y861367D03*
Y855068D03*
Y858218D03*
Y873964D03*
Y880263D03*
Y867665D03*
Y877114D03*
Y870814D03*
G54D122*
X1777378Y212455D03*
X1782187Y228631D03*
X1705686Y230556D03*
X1709941Y228747D03*
X1700945Y228646D03*
X1696552Y244571D03*
X1703895Y256394D03*
X1714531Y230117D03*
X1693932Y249108D03*
X1675016Y212455D03*
X1679825Y228631D03*
X1603324Y230556D03*
X1607579Y227824D03*
X1612169Y230117D03*
X1598583Y228646D03*
X1604677Y253198D03*
X1594190Y244571D03*
X1591570Y249108D03*
X1572654Y212455D03*
X1577463Y228631D03*
X1509807Y230117D03*
X1500962Y230556D03*
X1505217Y227824D03*
X1496221Y228646D03*
X1491828Y244571D03*
X1489208Y249108D03*
X1499171Y256394D03*
X1470292Y212455D03*
X1475101Y228631D03*
X1407445Y230117D03*
X1402855Y227824D03*
X1398600Y230556D03*
X1393859Y228646D03*
X1389466Y244571D03*
X1396809Y256394D03*
X1386846Y249108D03*
X1325100Y228631D03*
X1320291Y212455D03*
X1257444Y230117D03*
X1248599Y230556D03*
X1252854Y227824D03*
X1243858Y228646D03*
X1246808Y256394D03*
X1239465Y244571D03*
X1236845Y249108D03*
X1217929Y212455D03*
X1222738Y228631D03*
X1146237Y230556D03*
X1155082Y230117D03*
X1150492Y227824D03*
X1147590Y253198D03*
X1141496Y228646D03*
X1137103Y244571D03*
X1134483Y249108D03*
X1115567Y212455D03*
X1120376Y228631D03*
X1052720Y230117D03*
X1048130Y227824D03*
X1043875Y230556D03*
X1039134Y228646D03*
X1034741Y244571D03*
X1032121Y249108D03*
X1042084Y256394D03*
X1018014Y228631D03*
X1013205Y212455D03*
X950177Y215730D03*
X948741Y229468D03*
X948785Y242464D03*
X946234Y213390D03*
X942179Y215727D03*
X936962Y249807D03*
X944248Y239844D03*
X895064Y250186D03*
X863205Y212455D03*
X866015Y224536D03*
X800358Y230117D03*
X795768Y227824D03*
X791513Y230556D03*
X786772Y228646D03*
X798075Y244297D03*
X789722Y256394D03*
X782379Y244571D03*
X779759Y249108D03*
X760843Y212455D03*
X697996Y230117D03*
X689151Y230556D03*
X693406Y227824D03*
X695713Y244297D03*
X690504Y253198D03*
X684410Y228646D03*
X677397Y249108D03*
X680017Y244571D03*
X658481Y212455D03*
X663290Y228631D03*
X595634Y230117D03*
X593351Y244297D03*
X586789Y230556D03*
X591044Y227824D03*
X582048Y228646D03*
X577655Y244571D03*
X584998Y256394D03*
X560928Y228631D03*
X575035Y249108D03*
X556119Y212455D03*
X490989Y244297D03*
X482636Y256394D03*
X493272Y230117D03*
X484427Y230556D03*
X488682Y227824D03*
X479686Y228646D03*
X475293Y244571D03*
X472673Y249108D03*
X410927Y228631D03*
X340988Y244297D03*
X332635Y256394D03*
X343271Y230117D03*
X338681Y227824D03*
X334426Y230556D03*
X329685Y228646D03*
X322672Y249108D03*
X325292Y244571D03*
X303756Y212455D03*
X308565Y228631D03*
X222930Y244571D03*
X233417Y253198D03*
X240909Y230117D03*
X236319Y227824D03*
X232064Y230556D03*
X227323Y228646D03*
X220310Y249108D03*
X206203Y228631D03*
X201394Y212455D03*
X129702Y230556D03*
X133957Y227824D03*
X120568Y244571D03*
X127911Y256394D03*
X138547Y230117D03*
X117948Y249108D03*
X99032Y212455D03*
X103841Y228631D03*
X27340Y230556D03*
X36185Y230117D03*
X31595Y227824D03*
X22599Y228646D03*
X18206Y244571D03*
X15586Y249108D03*
X406118Y212455D03*
X18206Y264571D03*
X15499Y288542D03*
X15586Y269108D03*
X14807Y282181D03*
X8335Y280663D03*
X25549Y276394D03*
X37117Y279991D03*
X29116Y281129D03*
X77073Y281716D03*
X83014Y281982D03*
X80525Y265896D03*
X85541Y266114D03*
X182887Y265896D03*
X179435Y281716D03*
X185376Y281982D03*
X187903Y266114D03*
X281797Y281716D03*
X287738Y281982D03*
X285249Y265896D03*
X290265Y266114D03*
X390100Y281982D03*
X384159Y281716D03*
X392627Y266114D03*
X387611Y265896D03*
X540101Y281982D03*
X534160Y281716D03*
X537612Y265896D03*
X542628Y266114D03*
X636522Y281716D03*
X639974Y265896D03*
X642463Y281982D03*
X644990Y266114D03*
X738884Y281716D03*
X744825Y281982D03*
X742336Y265896D03*
X747352Y266114D03*
X784118Y303962D03*
X790280Y287421D03*
X786461Y293028D03*
X809490Y305368D03*
X817456D03*
X847187Y281982D03*
X841246Y281716D03*
X849714Y266114D03*
X844698Y265896D03*
X886496Y268968D03*
X55699Y1072761D03*
X61588Y1074481D03*
X62109Y1079656D03*
Y1091656D03*
X47314Y1072228D03*
X41172Y1079064D03*
X51023Y1201416D03*
X48842Y1211109D03*
X82661Y143740D03*
X80041Y148277D03*
X64829Y92874D03*
X49643Y464419D03*
X41643Y464919D03*
X44563Y482165D03*
X43804Y500202D03*
X78733Y578405D03*
X84159Y578986D03*
X186026Y97475D03*
X185023Y143740D03*
X182403Y148277D03*
X167191Y92874D03*
X385694Y477318D03*
X385634Y472020D03*
X393646Y474382D03*
X228267Y412718D03*
Y404718D03*
X233258Y359186D03*
X265011Y403307D03*
X291396Y350223D03*
X297719Y339559D03*
X315079Y314890D03*
X321416Y348015D03*
X316067Y347937D03*
X315944Y332584D03*
X312263Y324518D03*
X353367Y459330D03*
X353320Y454214D03*
X367564Y461034D03*
X385293Y466409D03*
X288388Y97475D03*
X287385Y143740D03*
X284765Y148277D03*
X269553Y92874D03*
X368587Y409016D03*
X347058Y399918D03*
X353894Y406060D03*
X390750Y97475D03*
X371915Y92874D03*
X432440Y440101D03*
X425062Y883981D03*
X404468Y864407D03*
X406770Y869767D03*
X405466Y881299D03*
X397431Y870654D03*
X392584Y875845D03*
X397252Y962861D03*
X396671Y968287D03*
X384856Y947987D03*
X379928Y949774D03*
X441296Y325061D03*
X436666Y322583D03*
X427713Y321965D03*
X447279Y637031D03*
X447921Y630789D03*
X453552Y631779D03*
X443144Y628667D03*
X441162Y638313D03*
X498524Y997590D03*
X512232Y985172D03*
X540751Y97475D03*
X539748Y143740D03*
X537128Y148277D03*
X538170Y172190D03*
X521916Y92874D03*
X501224Y492050D03*
X502493Y495917D03*
X500890Y500202D03*
X518240Y459371D03*
X522756Y461818D03*
X496729Y461919D03*
X504729Y461419D03*
X501649Y482165D03*
X506925Y546830D03*
X591487Y1501687D03*
X591481Y1509313D03*
X581803Y1493687D03*
X578859Y1497758D03*
X588859Y1490895D03*
X590826Y1495688D03*
X588507Y1514141D03*
X582027Y1502800D03*
X577931Y1505687D03*
X581803Y1509687D03*
X643113Y97475D03*
X642110Y143740D03*
X640532Y172190D03*
X624278Y92874D03*
X639490Y148277D03*
X741852D03*
X742894Y172190D03*
X745475Y97475D03*
X744472Y143740D03*
X726640Y92874D03*
X756358Y1616917D03*
X732268Y1618260D03*
X767310Y1599164D03*
X768361Y1610083D03*
X736067Y1611892D03*
X749704Y1608631D03*
X738775Y1597866D03*
X850732Y469382D03*
X842916Y467009D03*
X842779Y473076D03*
X847837Y97475D03*
X829002Y92874D03*
X855017Y411969D03*
X849591Y411388D03*
X958690Y1210419D03*
X956509Y1220112D03*
X916749Y1092664D03*
X902389Y1081764D03*
X908799Y1088659D03*
X908278Y1083484D03*
X908799Y1100659D03*
X902353Y1104333D03*
X887862Y1088067D03*
X894004Y1081231D03*
X894713Y1210419D03*
X892532Y1220112D03*
X921343Y376888D03*
X929947Y376821D03*
X916330Y377748D03*
X910646Y376084D03*
X966366Y1081764D03*
X972255Y1083484D03*
X972776Y1088659D03*
X966330Y1104333D03*
X972776Y1100659D03*
X944238Y360828D03*
X1089474Y1638213D03*
X1097474Y1637753D03*
X1105474Y1629450D03*
X1096941Y1627905D03*
X1090093Y1628297D03*
X1101946Y1614709D03*
X1098904Y1602138D03*
X1088021Y1606949D03*
X1090469Y1588435D03*
X1083900Y1593206D03*
X1100476Y1579318D03*
X1086904Y1599004D03*
X1105474Y1638426D03*
X997837Y97475D03*
X996834Y143740D03*
X994214Y148277D03*
X979002Y92874D03*
X991246Y281716D03*
X997187Y281982D03*
X958736Y482165D03*
X955816Y464919D03*
X963816Y464419D03*
X977327Y462371D03*
X981843Y464818D03*
X957977Y500202D03*
X1002580Y309619D03*
X987517Y314092D03*
X1001105Y318006D03*
X993552Y318175D03*
X1100199Y97475D03*
X1099196Y143740D03*
X1096576Y148277D03*
X1097618Y172190D03*
X1081364Y92874D03*
X1763887Y266114D03*
X1761360Y281982D03*
X1758871Y265896D03*
X1755419Y281716D03*
X1656509Y265896D03*
X1661525Y266114D03*
X1653057Y281716D03*
X1658998Y281982D03*
X1559163Y266114D03*
X1554147Y265896D03*
X1556636Y281982D03*
X1550695Y281716D03*
X1550931Y305158D03*
X1456801Y266114D03*
X1454274Y281982D03*
X1451785Y265896D03*
X1448333Y281716D03*
X1344007Y279054D03*
X1306800Y266114D03*
X1301784Y265896D03*
X1304273Y281982D03*
X1298332Y281716D03*
X1241205Y303962D03*
X1199422Y265896D03*
X1204438Y266114D03*
X1201911Y281982D03*
X1195970Y281716D03*
X1102076Y266114D03*
X1097060Y265896D03*
X1099549Y281982D03*
X1093608Y281716D03*
X1099371Y1561153D03*
X1098617Y1546183D03*
X1202561Y97475D03*
X1201558Y143740D03*
X1198938Y148277D03*
X1183726Y92874D03*
X1319474Y467560D03*
X1299466Y466409D03*
X1281737Y461034D03*
X1267540Y459330D03*
X1267493Y454214D03*
X1299867Y477318D03*
X1299807Y472020D03*
X1307819Y474382D03*
X1319974Y475560D03*
X1266718Y1142666D03*
X1304923Y97475D03*
X1302342Y172190D03*
X1286088Y92874D03*
X1282760Y409016D03*
X1268067Y406060D03*
X1261231Y399918D03*
X1296687Y839500D03*
X1293500Y835500D03*
Y843500D03*
Y851500D03*
X1291604Y776576D03*
Y781576D03*
X1279460Y854487D03*
X1285500Y851500D03*
X1279460Y889487D03*
Y884487D03*
X1279539Y776576D03*
X1281777Y823500D03*
X1281269Y835492D03*
X1285500Y843500D03*
X1279460Y859487D03*
X1274264Y898591D03*
X1335440Y452799D03*
X1346613Y440101D03*
X1346248Y452718D03*
X1340820Y452987D03*
X1341169Y325926D03*
X1413500Y884000D03*
Y892000D03*
X1417081Y896000D03*
X1405500D03*
Y888000D03*
Y904000D03*
Y860000D03*
X1417797Y879501D03*
X1413500Y876000D03*
X1405500Y868000D03*
Y880000D03*
X1402000Y864000D03*
Y876000D03*
Y884000D03*
X1454924Y97475D03*
X1453921Y143740D03*
X1451301Y148277D03*
X1436089Y92874D03*
X1415064Y500202D03*
X1436930Y461818D03*
X1432414Y459371D03*
X1410903Y461919D03*
X1418903Y461419D03*
X1415823Y482165D03*
X1410903Y470419D03*
X1421099Y546830D03*
X1479500Y697630D03*
X1557286Y97475D03*
X1556283Y143740D03*
X1553663Y148277D03*
X1538451Y92874D03*
X1698716Y550065D03*
X1618538Y618288D03*
X1644325Y942120D03*
X1647402Y881460D03*
X1637771Y952120D03*
X1635176Y886761D03*
X1644552Y871353D03*
X1635000Y919263D03*
X1644718Y909263D03*
X1756553Y466409D03*
X1738824Y461034D03*
X1724627Y459330D03*
X1724580Y454214D03*
X1686339Y314890D03*
X1683523Y324518D03*
X1687424Y347937D03*
X1692676Y348015D03*
X1668979Y339559D03*
X1636271Y403307D03*
X1599527Y404718D03*
Y412718D03*
X1620385Y465874D03*
X1594466Y350984D03*
X1756894Y472020D03*
X1756954Y477318D03*
X1658645Y143740D03*
X1656025Y148277D03*
X1659648Y97475D03*
X1640813Y92874D03*
X1762010Y97475D03*
X1743175Y92874D03*
X1718318Y399918D03*
X1725154Y406060D03*
X1739847Y409016D03*
X1803700Y440101D03*
X1816756Y1089145D03*
X1816235Y1083970D03*
X1810346Y1082250D03*
X1816756Y1101145D03*
X1795819Y1088553D03*
X1806835Y1214668D03*
X1800489Y1220598D03*
X1807243Y1219955D03*
X1802670Y1210905D03*
G54D125*
X43948Y492108D03*
X45256Y495993D03*
X959600Y496486D03*
X958124Y492354D03*
G54D124*
X923336Y226772D03*
G54D135*
X1650620Y630650D03*
G54D121*
X909360Y230906D03*
G54D129*
X401108Y878487D03*
G54D136*
X1795900Y852600D03*
G54D137*
X1817323Y1567323D03*
G54D126*
X116731Y1066535D03*
Y1263386D03*
X352952Y1066535D03*
Y1263386D03*
X573818Y1066535D03*
Y1263386D03*
X810038Y1066535D03*
Y1263386D03*
X1030905Y1066535D03*
Y1263386D03*
X1267125Y1066535D03*
Y1263386D03*
X1487991Y1066535D03*
Y1263386D03*
X1724212Y1066535D03*
Y1263386D03*
G54D132*
X1377559Y286220D03*
G54D130*
X770472Y1490945D03*
X820079Y388583D03*
X1020866D03*
X1070472Y1490945D03*
G54D134*
X1627965Y584471D03*
Y570297D03*
Y534431D03*
Y520258D03*
Y612817D03*
Y598644D03*
X1635265Y563210D03*
Y527344D03*
Y605730D03*
Y591557D03*
Y577384D03*
X1692253Y591525D03*
Y605699D03*
Y577352D03*
Y563179D03*
Y527313D03*
X1702655Y534425D03*
Y520252D03*
Y612811D03*
Y598638D03*
Y584465D03*
Y570291D03*
G54D131*
X854291Y1225118D03*
%LPD*%
G75*
G36*
G01X200697Y1149497D02*
X266867D01*
G02X267009Y1149438I0J-200D01*
G01X267391Y1149056D01*
G02X267450Y1148914I-141J-142D01*
G01Y1147880D01*
G02X267391Y1147738I-200J0D01*
G01X266809Y1147156D01*
G02X266667Y1147097I-142J141D01*
G01X201003D01*
X200500Y1147600D01*
Y1149300D01*
X200697Y1149497D01*
G37*
G36*
G01X199365Y1180448D02*
X198655Y1181158D01*
G02X198596Y1181300I141J142D01*
G01Y1182247D01*
G02X198655Y1182389I200J0D01*
G01X198872Y1182606D01*
G02X199014Y1182665I142J-141D01*
G01X267065D01*
G02X267207Y1182606I0J-200D01*
G01X267391Y1182422D01*
G02X267450Y1182280I-141J-142D01*
G01Y1181542D01*
G02X267391Y1181400I-200J0D01*
G01X266439Y1180448D01*
G02X266297Y1180389I-142J141D01*
G01X199507D01*
G02X199365Y1180448I0J200D01*
G37*
G36*
G01X390114Y935151D02*
X425614D01*
X426114Y935651D01*
Y940151D01*
X425114Y941151D01*
X390114D01*
X389614Y940651D01*
Y935651D01*
X390114Y935151D01*
G37*
G36*
G01X400735Y1551293D02*
X413138D01*
G02X413280Y1551234I0J-200D01*
G01X414142Y1550372D01*
G02X414201Y1550230I-141J-142D01*
G01Y1537649D01*
G02X414142Y1537507I-200J0D01*
G01X412833Y1536198D01*
G02X412691Y1536140I-141J142D01*
G01X403524D01*
G03X402678Y1535789I3J-1201D01*
G01X400933Y1534044D01*
G02X400791Y1533985I-142J141D01*
G01X399413D01*
G02X399271Y1534044I0J200D01*
G01X399194Y1534121D01*
G02X399136Y1534263I142J141D01*
G01Y1549693D01*
G02X399194Y1549835I200J1D01*
G01X400593Y1551234D01*
G02X400735Y1551293I142J-141D01*
G37*
G36*
G01X490720Y989521D02*
G03I-577J0D01*
G37*
G36*
G01X657637Y1149497D02*
X723954D01*
G02X724094Y1149440I0J-200D01*
G01X724095Y1149439D01*
X724478Y1149056D01*
G02X724480Y1149054I-140J-142D01*
G02X724537Y1148914I-143J-140D01*
G01Y1147923D01*
G02X724478Y1147781I-200J0D01*
G01X723853Y1147156D01*
G02X723711Y1147097I-142J141D01*
G01X657720D01*
G02X657578Y1147156I0J200D01*
G01X657486Y1147248D01*
X657469Y1147386D01*
X657506Y1147445D01*
G03X657700Y1148129I-1109J684D01*
G03X657473Y1148864I-1302J0D01*
G01X657472Y1148866D01*
X657455Y1148891D01*
X657447Y1148917D01*
G02X657437Y1148978I190J62D01*
G01Y1149297D01*
G02X657637Y1149497I200J0D01*
G37*
G36*
G01X655742Y1182389D02*
X655959Y1182606D01*
G02X656101Y1182665I142J-141D01*
G01X724152D01*
G02X724294Y1182606I0J-200D01*
G01X724478Y1182422D01*
G02X724537Y1182280I-141J-142D01*
G01Y1181588D01*
X723338Y1180389D01*
X656701D01*
X655683Y1181407D01*
Y1182247D01*
G02X655742Y1182389I200J0D01*
G37*
G36*
G01X915448Y369965D02*
X928112D01*
G02X928254Y369906I0J-200D01*
G01X928658Y369502D01*
G02X928717Y369360I-141J-142D01*
G01Y357741D01*
G02X928658Y357599I-200J0D01*
G01X927733Y356674D01*
G02X927591Y356615I-142J141D01*
G01X922255D01*
G03X922113Y356556I0J-200D01*
G01X921933Y356376D01*
G02X921792Y356318I-141J142D01*
G01X920778D01*
G02X920637Y356376I0J200D01*
G01X920249Y356764D01*
G03X920107Y356823I-142J-141D01*
G01X917274D01*
G03X917132Y356764I0J-200D01*
G01X916442Y356074D01*
G02X916300Y356015I-142J141D01*
G01X915580D01*
G02X915438Y356074I0J200D01*
G01X914408Y357104D01*
G02X914349Y357246I141J142D01*
G01Y368866D01*
G02X914408Y369008I200J0D01*
G01X915306Y369906D01*
G02X915448Y369965I142J-141D01*
G37*
G36*
G01X1114553Y1149427D02*
X1114564Y1149438D01*
G02X1114706Y1149497I142J-141D01*
G01X1181040D01*
G02X1181182Y1149438I0J-200D01*
G01X1181564Y1149056D01*
G02X1181623Y1148914I-141J-142D01*
G01Y1147880D01*
G02X1181564Y1147738I-200J0D01*
G01X1180982Y1147156D01*
G02X1180840Y1147097I-142J141D01*
G01X1114806D01*
G02X1114664Y1147156I0J200D01*
G01X1114523Y1147297D01*
Y1147344D01*
G03X1114786Y1148129I-1040J785D01*
G03X1114558Y1148865I-1302J0D01*
G01X1114541Y1148891D01*
X1114523Y1148947D01*
Y1149354D01*
X1114553Y1149427D01*
G37*
G36*
G01X1112828Y1182389D02*
X1113045Y1182606D01*
G02X1113187Y1182665I142J-141D01*
G01X1181238D01*
G02X1181380Y1182606I0J-200D01*
G01X1181564Y1182422D01*
G02X1181623Y1182280I-141J-142D01*
G01Y1181542D01*
G02X1181564Y1181400I-200J0D01*
G01X1180612Y1180448D01*
X1180584Y1180419D01*
X1180510Y1180389D01*
X1113680D01*
G02X1113538Y1180448I0J200D01*
G01X1112828Y1181158D01*
X1112799Y1181186D01*
X1112769Y1181260D01*
Y1182247D01*
G02X1112828Y1182389I200J0D01*
G37*
G36*
G01X1272730Y1159455D02*
G03I-610J0D01*
G37*
G36*
G01X1474205Y710052D02*
G03I-680J0D01*
G37*
G36*
G01X1571957Y1149497D02*
X1638127D01*
G02X1638269Y1149438I0J-200D01*
G01X1638651Y1149056D01*
G02X1638710Y1148914I-141J-142D01*
G01Y1147880D01*
G02X1638651Y1147738I-200J0D01*
G01X1638069Y1147156D01*
G02X1637927Y1147097I-142J141D01*
G01X1572263D01*
X1571760Y1147600D01*
Y1149300D01*
X1571957Y1149497D01*
G37*
G36*
G01X1570625Y1180448D02*
X1569915Y1181158D01*
G02X1569856Y1181300I141J142D01*
G01Y1182247D01*
G02X1569915Y1182389I200J0D01*
G01X1570132Y1182606D01*
G02X1570274Y1182665I142J-141D01*
G01X1638325D01*
G02X1638467Y1182606I0J-200D01*
G01X1638651Y1182422D01*
G02X1638710Y1182280I-141J-142D01*
G01Y1181542D01*
G02X1638651Y1181400I-200J0D01*
G01X1637699Y1180448D01*
G02X1637557Y1180389I-142J141D01*
G01X1570767D01*
G02X1570625Y1180448I0J200D01*
G37*
G54D100*
X1153433Y782873D03*
Y772243D03*
X1157173D03*
X1160913Y782873D03*
Y772243D03*
G54D110*
G01X891031Y694107D02*
X884915D01*
X884903Y694119D01*
G01X896234Y690656D02*
X894752Y692138D01*
X893984D01*
G54D101*
X1185312Y895751D03*
X1187871D03*
Y910317D03*
X1185312D03*
X1190431Y895751D03*
X1192990D03*
X1190431Y910317D03*
X1192990D03*
G54D120*
G01X289074Y1189271D02*
X288014D01*
X287624Y1189661D01*
Y1190561D01*
X286624Y1191561D01*
X280644D01*
X280144Y1192061D01*
Y1209044D01*
X278926Y1210262D01*
X235426D01*
X233392Y1212296D01*
Y1260182D01*
X233722Y1260512D01*
Y1260664D01*
G01X285334Y1189271D02*
X286394D01*
X286784Y1189661D01*
Y1190213D01*
X286276Y1190721D01*
X280296D01*
X279304Y1191713D01*
Y1208696D01*
X278578Y1209422D01*
X235078D01*
X232552Y1211948D01*
Y1260182D01*
X232222Y1260512D01*
Y1260664D01*
G01X742421Y1189271D02*
X743481D01*
X743871Y1189661D01*
Y1190213D01*
X743363Y1190721D01*
X737679D01*
X736391Y1192009D01*
Y1208621D01*
X735590Y1209422D01*
X692478D01*
X689639Y1212261D01*
Y1260350D01*
X689309Y1260680D01*
Y1260832D01*
G01X746161Y1189271D02*
X745101D01*
X744711Y1189661D01*
Y1190561D01*
X743711Y1191561D01*
X738027D01*
X737231Y1192357D01*
Y1208969D01*
X735938Y1210262D01*
X692826D01*
X690479Y1212609D01*
Y1260350D01*
X690809Y1260680D01*
Y1260832D01*
G01X1203247Y1189271D02*
X1202187D01*
X1201797Y1189661D01*
Y1190561D01*
X1200797Y1191561D01*
X1194939D01*
X1194317Y1192183D01*
Y1209083D01*
X1193138Y1210262D01*
X1148926D01*
X1147565Y1211623D01*
Y1260518D01*
X1147895Y1260848D01*
Y1261000D01*
G01X1199507Y1189271D02*
X1200567D01*
X1200957Y1189661D01*
Y1190213D01*
X1200449Y1190721D01*
X1194591D01*
X1193477Y1191835D01*
Y1208735D01*
X1192790Y1209422D01*
X1148578D01*
X1146725Y1211275D01*
Y1260518D01*
X1146395Y1260848D01*
Y1261000D01*
G01X1603482D02*
Y1260848D01*
X1603812Y1260518D01*
Y1212288D01*
X1606678Y1209422D01*
X1649778D01*
X1650564Y1208636D01*
Y1191754D01*
X1651597Y1190721D01*
X1657536D01*
X1658044Y1190213D01*
Y1189661D01*
X1657654Y1189271D01*
X1656594D01*
G01X1604982Y1261000D02*
Y1260848D01*
X1604652Y1260518D01*
Y1212636D01*
X1607026Y1210262D01*
X1650126D01*
X1651404Y1208984D01*
Y1192102D01*
X1651945Y1191561D01*
X1657884D01*
X1658884Y1190561D01*
Y1189661D01*
X1659274Y1189271D01*
X1660334D01*
G54D111*
G01X182950Y1148129D02*
X180610D01*
G01X181450Y1151870D02*
X180610D01*
G01X181450Y1155610D02*
X180610D01*
G01X181430Y1144389D02*
X180610D01*
G01X181450Y1159350D02*
X180610D01*
G01X182950Y1174310D02*
X180610D01*
G01X194750Y1136909D02*
X195570D01*
G01X192650D02*
X191830D01*
G01Y1156430D02*
Y1155610D01*
G01X194750Y1144389D02*
X195570D01*
G01X192650Y1148129D02*
X191830D01*
G01X194750Y1151869D02*
X195570D01*
G01X188090Y1153970D02*
Y1155610D01*
G01Y1156950D02*
Y1155610D01*
G01X184350Y1151870D02*
X183550D01*
G01Y1155610D02*
X184350Y1154810D01*
Y1151870D01*
G01X188090Y1146489D02*
Y1148129D01*
G01X185050D02*
X188090D01*
G01X195570Y1158530D02*
Y1159350D01*
G01X188090Y1172210D02*
Y1170570D01*
G01Y1168930D02*
Y1170570D01*
G01X195570Y1171390D02*
Y1170570D01*
G01X192830Y1166830D02*
X191830D01*
G01X188090Y1161850D02*
Y1159350D01*
G01X183550D02*
X184350D01*
G01X183550Y1162450D02*
X184350Y1161650D01*
Y1159350D01*
G01X183550Y1170570D02*
X184350D01*
G01X183550Y1166830D02*
X184350Y1167630D01*
Y1170570D01*
G01X188090Y1163950D02*
Y1166830D01*
G01X194550Y1185100D02*
X195139D01*
X195570Y1185531D01*
G01X192650Y1181791D02*
X191830D01*
G01X194750Y1178250D02*
X195371D01*
X195570Y1178051D01*
G01X191830Y1173490D02*
Y1174310D01*
G01X194750Y1181791D02*
X195570D01*
G01X183550Y1185200D02*
X184019D01*
X184350Y1185531D01*
G01X188100Y1183200D02*
Y1181801D01*
X188090Y1181791D01*
G01X188100Y1180350D02*
Y1181781D01*
X188090Y1181791D01*
G01X185050Y1174310D02*
X188090D01*
G01X183550Y1181800D02*
Y1178000D01*
G01D02*
X184299D01*
X184350Y1178051D01*
G01X214271Y1156430D02*
Y1155610D01*
G01X206791Y1156430D02*
Y1155610D01*
G01X199311Y1156430D02*
Y1155610D01*
G01X201181Y1148949D02*
X200131D01*
X199311Y1148129D01*
G01X208242Y1162291D02*
X210070Y1160463D01*
X210531Y1159350D01*
G01Y1158530D02*
Y1159350D01*
G01X203051Y1158530D02*
Y1159350D01*
G01Y1171390D02*
Y1170570D01*
G01X210531Y1171390D02*
Y1170570D01*
G01X200311Y1166830D02*
X199311D01*
G01X207791D02*
X206791D01*
G01X215271D02*
X214271D01*
G01X199311Y1173490D02*
Y1174310D01*
G01X206791Y1173490D02*
Y1174310D01*
G01X214271Y1173490D02*
Y1174310D01*
G01X221752Y1156430D02*
Y1155611D01*
X221751Y1155610D01*
G01X229232Y1156430D02*
Y1155610D01*
G01X223203Y1162291D02*
X225492Y1160002D01*
Y1159350D01*
G01Y1158530D02*
Y1159350D01*
G01X218011Y1158530D02*
Y1159350D01*
G01Y1171390D02*
Y1170570D01*
G01X225492Y1171390D02*
Y1170570D01*
G01X222752Y1166830D02*
X221752D01*
G01X230132D02*
X229232D01*
G01X221752Y1173490D02*
Y1174309D01*
X221751Y1174310D01*
G01X229292Y1173490D02*
Y1174250D01*
X229232Y1174310D01*
G01X240452Y1156430D02*
Y1155610D01*
G01X244192Y1159350D02*
Y1160003D01*
X241904Y1162291D01*
G01X236712Y1158530D02*
Y1159350D01*
G01X244192Y1158530D02*
Y1159350D01*
G01X236712Y1171390D02*
Y1170570D01*
G01X244192Y1171390D02*
Y1170570D01*
G01X239050Y1166900D02*
X240382D01*
X240452Y1166830D01*
G01X241950Y1166900D02*
X240522D01*
X240452Y1166830D01*
G01Y1173490D02*
Y1174310D01*
G01X247932Y1156430D02*
Y1155611D01*
X247933Y1155610D01*
G01X255413Y1156430D02*
Y1155610D01*
G01X262900Y1156430D02*
Y1155617D01*
X262893Y1155610D01*
G01X251673Y1158530D02*
Y1159350D01*
G01X259153Y1158530D02*
Y1159350D01*
G01X263713Y1166830D02*
X262893D01*
G01X251673Y1171390D02*
Y1170570D01*
G01X259153Y1171390D02*
Y1170570D01*
G01X248833Y1166830D02*
X247933D01*
G01X256313D02*
X255413D01*
G01X262893Y1173490D02*
Y1174310D01*
G01X247933Y1173490D02*
Y1174310D01*
G01X255413Y1173490D02*
Y1174310D01*
G01X277034Y1136909D02*
X277854D01*
G01X274934D02*
X274114D01*
G01X269553Y1155610D02*
X270373D01*
G01X277034Y1144389D02*
X277854D01*
G01X277034Y1140649D02*
X277854D01*
G01X267453Y1155610D02*
X266633D01*
G01X274934Y1144389D02*
X274114D01*
G01X274934Y1140649D02*
X274114D01*
G01X273294Y1159350D02*
X274114D01*
G01X273294Y1166830D02*
X274114D01*
G01X273294Y1170570D02*
X274114D01*
G01X269553Y1174310D02*
X270373D01*
G01X273294Y1181791D02*
X274114D01*
G01X271194Y1185531D02*
X270373D01*
G01X267453Y1174310D02*
X266633D01*
G01X271194Y1181791D02*
X270373D01*
G01X273294Y1185531D02*
X274114D01*
G01X271194Y1189271D02*
X270373D01*
G01X271194Y1193011D02*
X270373D01*
G01X274114Y1198851D02*
Y1200491D01*
G01Y1202132D02*
Y1200491D01*
G01X273294Y1189271D02*
X274114D01*
G01X273294Y1193011D02*
X274114D01*
G01X283234Y1181791D02*
X281594D01*
G01X279954D02*
X281594D01*
G01X391757Y1383480D02*
Y1381025D01*
G01X419977Y1288843D02*
X422432D01*
G01X423517Y1376002D02*
Y1375480D01*
X425039Y1373958D01*
X425283D01*
G01X410152Y1408528D02*
Y1410928D01*
G01X558241Y826212D02*
Y823649D01*
X559741Y822149D01*
G01X583501Y810973D02*
Y804985D01*
G01X651837Y1136909D02*
X652657D01*
G01X649737D02*
X648917D01*
G01Y1156430D02*
Y1155610D01*
G01X651837Y1151869D02*
X652657D01*
G01X649737Y1148129D02*
X648917D01*
G01X651837Y1144389D02*
X652657D01*
G01X645177Y1145209D02*
Y1144389D01*
G01X638517D02*
X637697D01*
G01X640600Y1151870D02*
X641437D01*
G01X640600Y1155610D02*
Y1151870D01*
G01X645177Y1154450D02*
Y1155610D01*
G01Y1157250D02*
Y1155610D01*
G01Y1147309D02*
Y1148129D01*
G01X642137D02*
X645177D01*
G01X652657Y1158530D02*
Y1159350D01*
G01Y1171390D02*
Y1170570D01*
G01X649817Y1166830D02*
X648917D01*
G01X645177Y1162150D02*
Y1159350D01*
G01Y1172210D02*
Y1170570D01*
G01Y1169350D02*
Y1170570D01*
G01X640600Y1166830D02*
Y1170570D01*
G01X641437D02*
X640600D01*
G01X645177Y1164250D02*
Y1166830D01*
G01X640600Y1162500D02*
Y1159350D01*
G01D02*
X641437D01*
G01X648917Y1173490D02*
Y1174310D01*
G01X651637Y1185100D02*
X652226D01*
X652657Y1185531D01*
G01X649737Y1181791D02*
X648917D01*
G01X651837Y1178250D02*
X652458D01*
X652657Y1178051D01*
G01X640600Y1185342D02*
X641248D01*
X641437Y1185531D01*
G01X640637Y1181800D02*
Y1178000D01*
G01X641437Y1178051D02*
X640688D01*
X640637Y1178000D01*
G01X645177Y1183431D02*
Y1181791D01*
G01Y1180151D02*
Y1181791D01*
G01X641950Y1174900D02*
X644587D01*
X645177Y1174310D01*
G01X663878Y1156430D02*
Y1155610D01*
G01X656398Y1156430D02*
Y1155610D01*
G01X667618Y1159350D02*
Y1160002D01*
X665329Y1162291D01*
G01X667618Y1158530D02*
Y1159350D01*
G01X660138Y1158530D02*
Y1159350D01*
G01X667618Y1171390D02*
Y1170570D01*
G01X664778Y1166830D02*
X663878D01*
G01X660138Y1171390D02*
Y1170570D01*
G01X657298Y1166830D02*
X656398D01*
G01X663878Y1173490D02*
Y1174310D01*
G01X656398Y1173490D02*
Y1174310D01*
G01X678838Y1156430D02*
Y1155610D01*
G01X671358Y1156430D02*
Y1155610D01*
G01X682579Y1171390D02*
Y1170570D01*
G01Y1158530D02*
Y1159350D01*
G01X675098Y1158530D02*
Y1159350D01*
G01X682579D02*
Y1160002D01*
X680290Y1162291D01*
G01X679739Y1166830D02*
X678839D01*
G01X675098Y1171390D02*
Y1170570D01*
G01X672258Y1166830D02*
X671358D01*
G01X678838Y1173490D02*
Y1174310D01*
G01X671358Y1173490D02*
Y1174310D01*
G01X697539Y1156430D02*
Y1155610D01*
G01X686319Y1156430D02*
Y1155610D01*
G01X701279Y1171390D02*
Y1170570D01*
G01X693799Y1171390D02*
Y1170570D01*
G01X701279Y1159350D02*
Y1160003D01*
X698991Y1162291D01*
G01X701279Y1158530D02*
Y1159350D01*
G01X693799Y1158530D02*
Y1159350D01*
G01X687219Y1166830D02*
X686319D01*
G01X699179D02*
X697539D01*
G01X695899D02*
X697539D01*
G01Y1173490D02*
Y1174310D01*
G01X686319Y1173490D02*
Y1174310D01*
G01X712500Y1156430D02*
Y1155610D01*
G01X705020Y1156430D02*
Y1155610D01*
G01X716240Y1171390D02*
Y1170570D01*
G01X713400Y1166830D02*
X712500D01*
G01X708760Y1171390D02*
Y1170570D01*
G01X716240Y1158530D02*
Y1159350D01*
G01X708760Y1158530D02*
Y1159350D01*
G01X705920Y1166830D02*
X705020D01*
G01X712500Y1173490D02*
Y1174310D01*
G01X705020Y1173490D02*
Y1174310D01*
G01X734121Y1136909D02*
X734941D01*
G01X732021D02*
X731201D01*
G01X726640Y1155610D02*
X727460D01*
G01X734121Y1144389D02*
X734941D01*
G01X734121Y1140649D02*
X734941D01*
G01X719980Y1156430D02*
Y1155610D01*
G01X724540D02*
X723720D01*
G01X732021Y1144389D02*
X731201D01*
G01X732021Y1140649D02*
X731201D01*
G01X730381Y1170570D02*
X731201D01*
G01X730381Y1166830D02*
X731201D01*
G01X730450Y1162800D02*
Y1159419D01*
X730381Y1159350D01*
G01X731201D02*
X730381D01*
G01X720800Y1166830D02*
X719980D01*
G01X728281Y1185531D02*
X727460D01*
G01X730381Y1181791D02*
X731201D01*
G01X726640Y1174310D02*
X727460D01*
G01X719980Y1173490D02*
Y1174310D01*
G01X724540D02*
X723720D01*
G01X728281Y1181791D02*
X727460D01*
G01X730381Y1185531D02*
X731201D01*
G01X728281Y1193011D02*
X727460D01*
G01X728281Y1189271D02*
X727460D01*
G01X731201Y1202132D02*
Y1200491D01*
G01Y1198851D02*
Y1200491D01*
G01X730381Y1193011D02*
X731201D01*
G01X730381Y1189271D02*
X731201D01*
G01X737041Y1181791D02*
X738681D01*
G01D02*
X740321D01*
G01X828149Y859484D02*
X827991Y859642D01*
Y861958D01*
X826949Y863000D01*
X826165D01*
G01X825490Y890047D02*
X829819D01*
X829852Y890080D01*
G01X825774Y895553D02*
X826992D01*
X830025Y892520D01*
Y890253D01*
X829852Y890080D01*
G01X832711Y993268D02*
X832610Y993369D01*
X832583D01*
X826634Y999318D01*
Y1002089D01*
G01X840162Y863413D02*
Y867413D01*
G01X840209Y871459D02*
X837396D01*
G01X840162Y867413D02*
Y871412D01*
X840209Y871459D01*
G01X839883Y879459D02*
X839812Y879530D01*
X837383D01*
G01X853731Y851924D02*
X853684Y851971D01*
Y855459D01*
G01X851161Y855205D02*
X851414Y855458D01*
X853683D01*
X853684Y855459D01*
G01X892392Y856316D02*
X890818Y854742D01*
G01X892392Y862615D02*
X890818Y864189D01*
G01X892392Y859465D02*
X890818Y857891D01*
G01X892392Y868914D02*
X890818Y870488D01*
G01X912864Y845293D02*
X912417D01*
X911515Y846195D01*
Y846642D01*
X911290Y846867D01*
G01X909714Y838994D02*
X910029Y838679D01*
Y836875D01*
G01X913066Y862098D02*
X913120Y862152D01*
G01X900267Y851592D02*
X901841Y853166D01*
G01X908140Y875213D02*
X909714Y876787D01*
G01X898692Y875213D02*
X897118Y876787D01*
G01X901841Y875213D02*
X900267Y876787D01*
G01X904991Y875213D02*
X906565Y876787D01*
G01X920739Y846867D02*
Y846868D01*
X922313Y848442D01*
Y851592D01*
G01X920739Y853166D02*
X922313Y851592D01*
G01X913120Y862152D02*
X914786D01*
X915347Y861591D01*
X919293D01*
X920317Y862615D01*
X920739D01*
G01Y859465D02*
X920737D01*
X919163Y857891D01*
G01X916014D02*
X914440Y859465D01*
G01Y865764D02*
Y865763D01*
X916014Y864189D01*
G01X914440Y868914D02*
Y868912D01*
X916014Y867338D01*
G01X938752Y885136D02*
X934944D01*
G01D02*
Y886264D01*
X933700Y887508D01*
G01X948272Y860671D02*
Y855472D01*
X947735Y854935D01*
G01X948297Y868168D02*
Y868246D01*
X950291Y870240D01*
G01X948180Y864721D02*
X948772D01*
X950291Y866240D01*
G01X1106823Y1136909D02*
X1106003D01*
G01X1095603Y1142579D02*
Y1143569D01*
X1094783Y1144389D01*
G01X1106003Y1156430D02*
Y1155610D01*
G01X1106823Y1148129D02*
X1106003D01*
G01X1097123D02*
X1094783D01*
G01X1097703Y1142579D02*
Y1143569D01*
X1098523Y1144389D01*
G01X1097723Y1155610D02*
Y1151870D01*
G01X1098523D02*
X1097723D01*
G01X1102263Y1146489D02*
Y1148129D01*
G01X1099223D02*
X1102263D01*
G01Y1156950D02*
Y1155610D01*
G01Y1153970D02*
Y1155610D01*
G01X1107003Y1166830D02*
X1106003D01*
G01X1102263Y1172210D02*
Y1170570D01*
G01Y1168930D02*
Y1170570D01*
G01Y1161850D02*
Y1159350D01*
G01Y1163950D02*
Y1166830D01*
G01X1097723Y1162450D02*
Y1159350D01*
G01X1098523D02*
X1097723D01*
G01Y1166830D02*
Y1170570D01*
G01X1098523D02*
X1097723D01*
G01X1106003Y1173490D02*
Y1174310D01*
G01X1106823Y1181791D02*
X1106003D01*
G01X1097723Y1185200D02*
X1098192D01*
X1098523Y1185531D01*
G01X1099223Y1174310D02*
X1102263D01*
G01X1097723Y1181800D02*
Y1178000D01*
G01X1098523Y1178051D02*
X1097774D01*
X1097723Y1178000D01*
G01X1102273Y1183200D02*
Y1181801D01*
X1102263Y1181791D01*
G01X1102273Y1180350D02*
Y1181781D01*
X1102263Y1181791D01*
G01X1108923Y1136909D02*
X1109743D01*
G01X1120964Y1156430D02*
Y1155610D01*
G01X1113484Y1156430D02*
Y1155610D01*
G01X1108923Y1151869D02*
X1109743D01*
G01X1108923Y1144389D02*
X1109743D01*
G01X1124704Y1159350D02*
Y1160002D01*
X1122415Y1162291D01*
G01X1117224Y1158530D02*
Y1159350D01*
G01X1121964Y1166830D02*
X1120964D01*
G01X1117224Y1171390D02*
Y1170570D01*
G01X1114484Y1166830D02*
X1113484D01*
G01X1109743Y1171390D02*
Y1170570D01*
G01Y1158530D02*
Y1159350D01*
G01X1120964Y1173490D02*
Y1174310D01*
G01X1113484Y1173490D02*
Y1174310D01*
G01X1108923Y1178250D02*
X1109544D01*
X1109743Y1178051D01*
G01X1108723Y1185100D02*
X1109312D01*
X1109743Y1185531D01*
G01X1135925Y1156430D02*
Y1155611D01*
X1135924Y1155610D01*
G01X1128444Y1156430D02*
Y1155610D01*
G01X1139665Y1159350D02*
Y1160002D01*
X1137376Y1162291D01*
G01X1139665Y1158530D02*
Y1159350D01*
G01X1132184Y1158530D02*
Y1159350D01*
G01X1124704Y1158530D02*
Y1159350D01*
G01X1139665Y1171390D02*
Y1170570D01*
G01X1136925Y1166830D02*
X1135925D01*
G01X1132184Y1171390D02*
Y1170570D01*
G01X1129444Y1166830D02*
X1128444D01*
G01X1124704Y1171390D02*
Y1170570D01*
G01X1135925Y1173490D02*
Y1174309D01*
X1135924Y1174310D01*
G01X1128444Y1173490D02*
Y1174310D01*
G01X1154625Y1156430D02*
Y1155610D01*
G01X1143405Y1156430D02*
Y1155610D01*
G01X1156077Y1162291D02*
X1158365Y1160003D01*
Y1159350D01*
G01X1150885Y1158530D02*
Y1159350D01*
G01X1156123Y1166900D02*
X1154695D01*
X1154625Y1166830D01*
G01X1153223Y1166900D02*
X1154555D01*
X1154625Y1166830D01*
G01X1150885Y1171390D02*
Y1170570D01*
G01X1144305Y1166830D02*
X1143405D01*
G01X1154625Y1173490D02*
Y1174310D01*
G01X1143465Y1173490D02*
Y1174250D01*
X1143405Y1174310D01*
G01X1169586Y1156430D02*
Y1155610D01*
G01X1162105Y1156430D02*
Y1155611D01*
X1162106Y1155610D01*
G01X1165846Y1158530D02*
Y1159350D01*
G01X1158365Y1158530D02*
Y1159350D01*
G01X1170486Y1166830D02*
X1169586D01*
G01X1163006D02*
X1162106D01*
G01X1165846Y1171390D02*
Y1170570D01*
G01X1158365Y1171390D02*
Y1170570D01*
G01X1169586Y1173490D02*
Y1174310D01*
G01X1162106Y1173490D02*
Y1174310D01*
G01X1189107Y1136909D02*
X1188287D01*
G01X1183726Y1155610D02*
X1184546D01*
G01X1177073Y1156430D02*
Y1155617D01*
X1177066Y1155610D01*
G01X1181626D02*
X1180806D01*
G01X1189107Y1144389D02*
X1188287D01*
G01X1189107Y1140649D02*
X1188287D01*
G01X1187467Y1170570D02*
X1188287D01*
G01X1187467Y1166830D02*
X1188287D01*
G01X1177886D02*
X1177066D01*
G01X1187467Y1159350D02*
X1188287D01*
G01X1173326Y1158530D02*
Y1159350D01*
G01Y1171390D02*
Y1170570D01*
G01X1185367Y1185531D02*
X1184546D01*
G01X1187467Y1181791D02*
X1188287D01*
G01X1183726Y1174310D02*
X1184546D01*
G01X1177066Y1173490D02*
Y1174310D01*
G01X1181626D02*
X1180806D01*
G01X1185367Y1181791D02*
X1184546D01*
G01X1187467Y1185531D02*
X1188287D01*
G01X1185367Y1193011D02*
X1184546D01*
G01X1185367Y1189271D02*
X1184546D01*
G01X1188287Y1202132D02*
Y1200491D01*
G01Y1198851D02*
Y1200491D01*
G01X1187467Y1193011D02*
X1188287D01*
G01X1187467Y1189271D02*
X1188287D01*
G01X1191207Y1136909D02*
X1192027D01*
G01X1191207Y1140649D02*
X1192027D01*
G01X1191207Y1144389D02*
X1192027D01*
G01X1197407Y1181791D02*
X1195767D01*
G01X1194127D02*
X1195767D01*
G01X1282317Y880193D02*
X1283005Y879505D01*
X1286752D01*
X1287889Y880642D01*
Y881802D01*
G01X1303195Y832247D02*
X1300716D01*
X1300516Y832047D01*
G01X1303183Y835985D02*
X1300504D01*
G01X1302883Y859088D02*
X1300204D01*
G01X1302776Y851193D02*
X1300097D01*
G01X1302770Y854824D02*
X1300091D01*
G01X1310482Y896580D02*
Y897471D01*
X1309856Y898097D01*
Y899161D01*
G01X1306387Y896580D02*
Y897539D01*
X1305761Y898165D01*
Y899161D01*
G01X1362574Y853492D02*
X1362573D01*
X1360999Y851918D01*
G01X1393970Y862829D02*
X1396916D01*
G01X1393001Y871018D02*
Y876191D01*
X1392988Y876204D01*
G01D02*
X1395561D01*
G01X1393947Y866620D02*
X1394186D01*
X1396163Y868597D01*
G01X1500638Y876339D02*
X1506626D01*
G01X1523000Y953563D02*
Y951000D01*
X1524500Y949500D01*
G01X1552690Y1144389D02*
X1551870D01*
G01X1559350Y1156950D02*
Y1155610D01*
G01Y1153970D02*
Y1155610D01*
G01X1554810Y1151870D02*
X1555610D01*
G01X1554810Y1155610D02*
Y1151870D01*
G01X1556310Y1148129D02*
X1559350D01*
G01Y1146489D02*
Y1148129D01*
G01Y1168930D02*
Y1170570D01*
G01Y1172210D02*
Y1170570D01*
G01Y1161850D02*
Y1159350D01*
G01D02*
Y1159050D01*
G01X1554810Y1166830D02*
Y1170570D01*
G01D02*
X1555610D01*
G01X1559350Y1163950D02*
Y1166830D01*
G01X1554810Y1162450D02*
Y1159350D01*
G01X1555610D02*
X1554810D01*
G01Y1185200D02*
X1555279D01*
X1555610Y1185531D01*
G01X1556310Y1174310D02*
X1559350D01*
G01X1559360Y1183200D02*
Y1181801D01*
X1559350Y1181791D01*
G01X1559360Y1180350D02*
Y1181781D01*
X1559350Y1181791D01*
G01X1554810Y1181800D02*
Y1178000D01*
G01X1555610Y1178051D02*
X1554861D01*
X1554810Y1178000D01*
G01X1566010Y1136909D02*
X1566830D01*
G01X1563910D02*
X1563090D01*
G01Y1156430D02*
Y1155610D01*
G01X1566010Y1151869D02*
X1566830D01*
G01X1563910Y1148129D02*
X1563090D01*
G01X1566010Y1144389D02*
X1566830D01*
G01X1570571Y1156430D02*
Y1155610D01*
G01X1578051Y1156430D02*
Y1155610D01*
G01X1579051Y1166830D02*
X1578051D01*
G01X1574311Y1171390D02*
Y1170570D01*
G01X1571571Y1166830D02*
X1570571D01*
G01X1566830Y1171390D02*
Y1170570D01*
G01X1564090Y1166830D02*
X1563090D01*
G01X1566830Y1158530D02*
Y1159350D01*
G01X1574311Y1158530D02*
Y1159350D01*
G01X1578051Y1173490D02*
Y1174310D01*
G01X1563090Y1173490D02*
Y1174310D01*
G01X1566010Y1178250D02*
X1566631D01*
X1566830Y1178051D01*
G01X1563910Y1181791D02*
X1563090D01*
G01X1565810Y1185100D02*
X1566399D01*
X1566830Y1185531D01*
G01X1570571Y1173490D02*
Y1174310D01*
G01X1593012Y1156430D02*
Y1155611D01*
X1593011Y1155610D01*
G01X1585531Y1156430D02*
Y1155610D01*
G01X1594012Y1166830D02*
X1593012D01*
G01X1586531D02*
X1585531D01*
G01X1589271Y1171390D02*
Y1170570D01*
G01X1581791Y1171390D02*
Y1170570D01*
G01X1596752Y1159350D02*
Y1160002D01*
X1594463Y1162291D01*
G01X1589271Y1158530D02*
Y1159350D01*
G01X1579502Y1162291D02*
X1581791Y1160002D01*
Y1159350D01*
G01Y1158530D02*
Y1159350D01*
G01X1585531Y1173490D02*
Y1174310D01*
G01X1593012Y1173490D02*
Y1174309D01*
X1593011Y1174310D01*
G01X1600492Y1156430D02*
Y1155610D01*
G01X1613210Y1166900D02*
X1611782D01*
X1611712Y1166830D01*
G01D02*
X1610380D01*
X1610310Y1166900D01*
G01X1607972Y1171390D02*
Y1170570D01*
G01X1601392Y1166830D02*
X1600492D01*
G01X1596752Y1171390D02*
Y1170570D01*
G01X1607972Y1158530D02*
Y1159350D01*
G01X1596752Y1158530D02*
Y1159350D01*
G01X1600552Y1173490D02*
Y1174250D01*
X1600492Y1174310D01*
G01X1626673Y1156430D02*
Y1155610D01*
G01X1619192Y1156430D02*
Y1155611D01*
X1619193Y1155610D01*
G01X1611712Y1156430D02*
Y1155610D01*
G01X1627573Y1166830D02*
X1626673D01*
G01X1622933Y1171390D02*
Y1170570D01*
G01X1620093Y1166830D02*
X1619193D01*
G01X1615452Y1171390D02*
Y1170570D01*
G01X1622933Y1158530D02*
Y1159350D01*
G01X1615452Y1158530D02*
Y1159350D01*
G01X1613164Y1162291D02*
X1615452Y1160003D01*
Y1159350D01*
G01X1626673Y1173490D02*
Y1174310D01*
G01X1619193Y1173490D02*
Y1174310D01*
G01X1611712D02*
Y1173490D01*
G01X1640813Y1155610D02*
X1641633D01*
G01X1634160Y1156430D02*
Y1155617D01*
X1634153Y1155610D01*
G01X1638713D02*
X1637893D01*
G01X1630413Y1171390D02*
Y1170570D01*
G01Y1158530D02*
Y1159350D01*
G01X1634973Y1166830D02*
X1634153D01*
G01Y1173490D02*
Y1174310D01*
G01X1640813D02*
X1641633D01*
G01X1642454Y1185531D02*
X1641633D01*
G01X1642454Y1181791D02*
X1641633D01*
G01X1638713Y1174310D02*
X1637893D01*
G01X1642454Y1193011D02*
X1641633D01*
G01X1642454Y1189271D02*
X1641633D01*
G01X1648294Y1136909D02*
X1649114D01*
G01X1646194D02*
X1645374D01*
G01X1648294Y1144389D02*
X1649114D01*
G01X1648294Y1140649D02*
X1649114D01*
G01X1646194Y1144389D02*
X1645374D01*
G01X1646194Y1140649D02*
X1645374D01*
G01X1644554Y1170570D02*
X1645374D01*
G01X1644554Y1166830D02*
X1645374D01*
G01X1644554Y1159350D02*
X1645374D01*
G01X1644554Y1181791D02*
X1645374D01*
G01X1651214D02*
X1652854D01*
G01X1654494D02*
X1652854D01*
G01X1644554Y1185531D02*
X1645374D01*
G01Y1202132D02*
Y1200491D01*
G01Y1198851D02*
Y1200491D01*
G01X1644554Y1193011D02*
X1645374D01*
G01X1644554Y1189271D02*
X1645374D01*
G54D102*
X1187951Y959596D03*
Y976722D03*
X1196219Y959596D03*
Y976722D03*
G54D112*
G01X5882Y1504559D02*
Y1516331D01*
X10648Y1521097D01*
Y1533194D01*
X9113Y1534729D01*
Y1537129D01*
X16840Y1544856D01*
X41573D01*
X50438Y1553721D01*
X58578D01*
X60747Y1555890D01*
G01X68778Y876608D02*
X69028Y876858D01*
Y883233D01*
G01X499947Y846830D02*
X503741D01*
G01X501267Y833027D02*
X497467D01*
G01X514682Y831662D02*
X513228D01*
X511863Y833027D01*
X509141D01*
G01X507821Y846830D02*
X511560D01*
X511741Y846649D01*
G01X525718Y876608D02*
X525968Y876858D01*
Y883233D01*
G01X558241Y834086D02*
Y840574D01*
G01X798484Y980041D02*
Y966186D01*
X800067Y964603D01*
G01X796193Y1436240D02*
X795274Y1437159D01*
X793744D01*
G01X818347Y939610D02*
Y940610D01*
X816107Y942850D01*
X805067D01*
X800067Y947850D01*
Y961453D01*
G01X824168Y949538D02*
X822183D01*
X810605Y961116D01*
X807225D01*
X803738Y964603D01*
X800067D01*
G01X983054Y883233D02*
Y876858D01*
X982804Y876608D01*
G01X1185312Y895751D02*
Y891885D01*
X1184812Y891385D01*
X1183750D01*
G01X1192990Y910317D02*
Y914873D01*
G01X1439891Y876608D02*
X1440141Y876858D01*
Y883233D01*
G01X1466026Y960378D02*
X1462000D01*
G01X1464706Y974181D02*
X1468500D01*
G01X1473900Y960378D02*
X1476622D01*
X1477987Y959013D01*
X1479441D01*
G01X1472580Y974181D02*
X1476319D01*
X1476500Y974000D01*
G54D103*
X1190805Y959596D03*
X1193365D03*
X1190805Y976722D03*
X1193365D03*
G54D10*
G01X8970Y254871D02*
X12965D01*
X17577Y259483D01*
X25242D01*
X25247Y259478D01*
X27403D01*
X27408Y259483D01*
X31177D01*
X35874Y264180D01*
X58062D01*
G01X31631Y1198651D02*
X33816Y1196466D01*
X52999D01*
X58972Y1202439D01*
Y1210919D01*
X60107Y1212054D01*
X63981D01*
G01X71006Y1228684D02*
X69289Y1230401D01*
Y1259758D01*
X64223Y1264824D01*
Y1387549D01*
X79160Y1402486D01*
Y1550059D01*
X69403Y1559816D01*
X45396D01*
X44254Y1558674D01*
Y1552709D01*
X42316Y1550771D01*
X23766D01*
X22381Y1552156D01*
Y1554152D01*
G01X58443Y1272257D02*
Y1390326D01*
X74581Y1406464D01*
Y1544878D01*
X68126Y1551333D01*
X53339D01*
X51043Y1549037D01*
Y1543839D01*
G01X79043Y667391D02*
X76514Y664862D01*
Y662707D01*
X73914Y660107D01*
G01X394929Y1307238D02*
X391284D01*
G01X391852Y1389931D02*
Y1392591D01*
G01Y1395159D02*
Y1392591D01*
G01X396035D02*
X391852D01*
G01X395112Y1395690D02*
X392383D01*
X391852Y1395159D01*
G01X410866Y1288938D02*
X408298D01*
G01D02*
X407767Y1289469D01*
Y1292198D01*
G01X398079Y1307238D02*
X400991D01*
X401011Y1307258D01*
G01X403798Y1305859D02*
X402410D01*
X401011Y1307258D01*
G01X410172Y1402446D02*
X408773Y1401047D01*
Y1399659D01*
G01X410152Y1405378D02*
Y1402466D01*
X410172Y1402446D01*
G01X423963Y625778D02*
X430351Y619390D01*
X447660D01*
X464776Y636506D01*
G01X413526Y1288938D02*
X410866D01*
G01Y1293121D02*
Y1288938D01*
G01X425725Y1331356D02*
X426174D01*
X428939Y1328591D01*
G01X425725Y1331356D02*
X424739Y1330370D01*
G01Y1321323D02*
X425378Y1320684D01*
G01X425283Y1373958D02*
Y1370972D01*
G01X423517Y1379152D02*
X427650D01*
X428084Y1378718D01*
G01X432485Y1322369D02*
Y1325784D01*
G01X428528Y1320684D02*
X430213Y1322369D01*
X432485D01*
G01X429530Y1325051D02*
Y1327276D01*
X428939Y1327867D01*
Y1328591D01*
G01X464776Y636506D02*
Y644087D01*
G01X532426Y576484D02*
Y579114D01*
X535198Y581886D01*
X544511D01*
X544738Y581659D01*
G01X566058Y1185164D02*
X560211D01*
G01X757721Y617468D02*
X753320Y621869D01*
X707945D01*
X704364Y618288D01*
G01X765105Y572830D02*
Y511708D01*
X771440Y505373D01*
X785165D01*
X795423Y495115D01*
Y481985D01*
X797268Y480140D01*
X806687D01*
G01X765105Y572830D02*
Y600537D01*
G01D02*
Y610084D01*
X757721Y617468D01*
G01X806687Y480140D02*
X810756Y476071D01*
G01X878382Y554942D02*
X877949Y555375D01*
Y560463D01*
G01X910633Y1222799D02*
X905539D01*
X902662Y1219922D01*
Y1211442D01*
X896689Y1205469D01*
X877506D01*
X875321Y1207654D01*
G01X889949Y553963D02*
X886549D01*
G01X971648Y1221057D02*
X967774D01*
X966639Y1219922D01*
Y1211442D01*
X960666Y1205469D01*
X941483D01*
X939298Y1207654D01*
G01X947411Y1443901D02*
X942088D01*
G01X952695Y1444139D02*
X952457Y1443901D01*
X947411D01*
G01X978934Y1444392D02*
X973806D01*
G01D02*
X968388D01*
X968306Y1444474D01*
X968133D01*
G01X1001825Y581659D02*
X1001598Y581886D01*
X992285D01*
X989513Y579114D01*
Y576484D01*
G01X1420699Y958452D02*
X1410126Y969025D01*
X1348293D01*
X1342849Y974469D01*
X1323444D01*
X1322209Y973234D01*
X1295633D01*
X1284368Y961969D01*
X1266463D01*
X1232530Y928036D01*
Y889506D01*
X1206061Y863037D01*
X1169184D01*
X1165130Y867091D01*
Y874448D01*
X1125506Y914072D01*
X1021262D01*
X1017823Y914756D01*
X1017810D01*
X995824Y923864D01*
X987003D01*
X979498Y916359D01*
Y907500D01*
G01X994994Y1444240D02*
X990318D01*
G01X997020Y341954D02*
Y345354D01*
G01X1003520Y353954D02*
X1000420D01*
G01X1002194Y1444392D02*
X1002042Y1444240D01*
X994994D01*
G01X1025615Y1444492D02*
X1020196D01*
G01D02*
X1014605D01*
X1014585Y1444512D01*
X1014429D01*
G01X1045218Y1444596D02*
X1040095D01*
G01X1048403Y1444608D02*
X1045230D01*
X1045218Y1444596D01*
G01X1480231Y1185164D02*
X1474384D01*
G01X1779404Y826570D02*
X1787179Y818795D01*
X1791041D01*
G01X1817766Y1202325D02*
X1817278Y1201837D01*
X1808470D01*
X1804489Y1205818D01*
Y1205955D01*
X1785463D01*
X1783278Y1208140D01*
X3704Y5374D03*
X3017Y24773D03*
Y44773D03*
Y64773D03*
Y84773D03*
Y104773D03*
Y124773D03*
Y144773D03*
Y164773D03*
Y184773D03*
Y204773D03*
Y224773D03*
Y244773D03*
Y264773D03*
Y284773D03*
Y304773D03*
X3221Y324773D03*
X3035Y978036D03*
Y998036D03*
Y1018036D03*
Y1038036D03*
Y1058036D03*
Y1078036D03*
Y1098036D03*
Y1118036D03*
Y1138036D03*
Y1158036D03*
Y1178036D03*
Y1198036D03*
Y1238036D03*
Y1258036D03*
Y1278036D03*
Y1298036D03*
Y1318036D03*
Y1338036D03*
Y1358036D03*
Y1378036D03*
Y1398036D03*
Y1418036D03*
Y1438036D03*
Y1458036D03*
Y1478036D03*
Y1498036D03*
Y1538036D03*
Y1558036D03*
Y1578036D03*
X3017Y1639466D03*
X15972Y3000D03*
X20408Y51296D03*
Y55296D03*
X14751Y62381D03*
X7271Y70981D03*
X12601Y92110D03*
X8786Y88425D03*
X14264Y94236D03*
X18000Y90000D03*
X9364Y107501D03*
X16728Y107910D03*
X12652Y116894D03*
X18298Y102141D03*
X8000Y102500D03*
X15143Y115581D03*
X14996Y133034D03*
X11442Y132719D03*
X9057Y138939D03*
X19184Y144728D03*
X15184D03*
X9082Y135789D03*
X19855Y141362D03*
X11999Y141415D03*
X13615Y153263D03*
X10966Y155873D03*
Y152873D03*
Y162073D03*
Y159073D03*
X12709Y175777D03*
X16709Y175943D03*
X15139Y198883D03*
X15520Y195176D03*
X13020D03*
X10520D03*
X12880Y203393D03*
X10380D03*
X19068Y206838D03*
X16568D03*
X19572Y219470D03*
Y221970D03*
X10259Y218085D03*
X13059D03*
X19638Y226320D03*
X16859Y216385D03*
X19572Y216970D03*
X18564Y238589D03*
X9745Y245784D03*
X13715Y259381D03*
X8970Y254871D03*
X19075Y278429D03*
X7036Y268371D03*
Y272371D03*
X10971Y333342D03*
X17964Y349298D03*
Y369298D03*
Y389298D03*
Y409298D03*
Y429298D03*
Y449298D03*
Y469298D03*
Y489298D03*
Y509298D03*
Y529298D03*
Y549298D03*
Y569298D03*
Y589298D03*
Y609298D03*
Y629298D03*
Y649298D03*
Y669298D03*
Y689298D03*
Y709298D03*
Y729298D03*
Y749298D03*
Y769298D03*
Y789298D03*
Y809298D03*
Y829298D03*
Y849298D03*
Y869298D03*
Y889298D03*
Y909298D03*
Y929298D03*
X9554Y961954D03*
X17964Y949298D03*
X17033Y1006819D03*
X14357Y1009906D03*
X20216Y1009748D03*
X14197Y1017759D03*
X20197Y1014205D03*
Y1017759D03*
X6161Y1075991D03*
X6108Y1070611D03*
Y1065318D03*
X6059Y1091964D03*
X6055Y1086546D03*
X6053Y1081305D03*
X14252Y1121333D03*
X11552D03*
X16752D03*
X8952D03*
X14152Y1111633D03*
X11452D03*
X8852D03*
X16652D03*
X14252Y1130333D03*
X16752D03*
X14306Y1138705D03*
X16806D03*
X20079Y1429347D03*
X13606Y1476707D03*
X6690Y1496782D03*
X19365Y1494298D03*
X6489Y1501334D03*
X19745Y1508846D03*
X8042Y1522199D03*
X12327Y1519202D03*
X19735Y1530499D03*
X19859Y1520657D03*
X7922Y1532494D03*
X11995Y1535134D03*
X6951Y1538547D03*
X18879Y1534334D03*
X6567Y1554215D03*
X14375Y1553121D03*
X18409Y1554202D03*
X10367Y1553080D03*
X12000Y1644980D03*
X26956Y4469D03*
X28317Y24773D03*
Y44773D03*
X24316Y67527D03*
Y63527D03*
Y59527D03*
X35638Y53597D03*
X32350Y67562D03*
X28442Y55340D03*
X32350Y59562D03*
Y63562D03*
X33288Y109410D03*
Y116497D03*
X30788D03*
X25988D03*
X22439Y106495D03*
Y102495D03*
X35207Y106561D03*
X30788Y123584D03*
X33288Y123583D03*
X25988Y123584D03*
X33288Y130670D03*
X30788D03*
X25988D03*
X30788Y137757D03*
X25988D03*
X23184Y144728D03*
X29201Y151651D03*
X26201D03*
X22935Y162073D03*
Y159073D03*
X20709Y175777D03*
X30567Y195176D03*
X28067D03*
X25567D03*
X33067D03*
X29585Y199248D03*
X34520Y213539D03*
X29921Y206806D03*
X32585Y202048D03*
X25648Y210509D03*
X28148D03*
X29585Y201748D03*
X27421Y206806D03*
X36201Y238714D03*
X21530Y236121D03*
X27966Y238689D03*
X28740Y247292D03*
X32201Y238714D03*
X23844Y239299D03*
X21556Y232971D03*
X31682Y246874D03*
X33902Y244297D03*
X21449Y253198D03*
X26325Y262078D03*
X28740Y267292D03*
X21386Y273198D03*
X31682Y266874D03*
X23479Y295619D03*
X34845Y291756D03*
X26629Y295619D03*
X35650Y487982D03*
Y478982D03*
Y483982D03*
Y499982D03*
Y491982D03*
Y495982D03*
X25819Y531726D03*
Y536726D03*
X30177Y534211D03*
X25819Y527726D03*
Y552726D03*
Y540726D03*
Y548726D03*
Y544726D03*
X32452Y581222D03*
X29652D03*
X35252D03*
Y591215D03*
X29652D03*
X32452D03*
X34254Y611091D03*
X30123Y611071D03*
X27686Y621311D03*
X29451Y633560D03*
X27686Y629311D03*
X36692Y641817D03*
X30369Y663048D03*
X27625Y663094D03*
X35293Y662952D03*
X25818Y682139D03*
X27854Y671553D03*
X30414Y671508D03*
X35250D03*
X34565Y699082D03*
X26596Y874520D03*
X26844Y920354D03*
X24132Y958151D03*
X25371Y980696D03*
X36529Y1006321D03*
X24456Y1006401D03*
X32093Y1009748D03*
X26155Y1009985D03*
X29197Y1014205D03*
X32197Y1017759D03*
X26197D03*
X35197Y1014205D03*
X21196Y1065529D03*
Y1063029D03*
X36089Y1062601D03*
Y1065101D03*
X35925Y1075663D03*
X33425D03*
X28996Y1065529D03*
X23796D03*
X26396D03*
Y1063029D03*
X23796D03*
X28996D03*
X28606Y1082678D03*
X23406D03*
X26006D03*
Y1080178D03*
X23406D03*
X28606D03*
X20806Y1082678D03*
Y1080178D03*
X21321Y1098769D03*
X26521D03*
X29121D03*
X23921D03*
Y1101335D03*
X29121D03*
X26521D03*
X21321D03*
X32574Y1111633D03*
X29874D03*
X27274D03*
X24674D03*
Y1121333D03*
X27274D03*
X29874D03*
X32574D03*
X24674Y1130333D03*
X21974D03*
X21209Y1138705D03*
X23709D03*
X27934Y1204311D03*
X30934D03*
X30410Y1218497D03*
Y1220997D03*
X27934Y1215511D03*
X30934D03*
X34314Y1215403D03*
X27934Y1212711D03*
Y1209911D03*
Y1207111D03*
X30934Y1212711D03*
Y1209911D03*
Y1207111D03*
X30410Y1234797D03*
Y1232297D03*
Y1227897D03*
Y1225397D03*
Y1241697D03*
Y1239197D03*
X29860Y1438552D03*
X23603Y1449735D03*
X22284Y1464612D03*
X21544Y1479662D03*
X33536Y1467485D03*
X21544Y1489648D03*
X32195Y1511279D03*
X33189Y1501373D03*
X32079Y1525641D03*
Y1521641D03*
Y1517641D03*
X35237Y1532096D03*
X31237D03*
X35850Y1556096D03*
X22381Y1554152D03*
X26231Y1554167D03*
X32000Y1644980D03*
X46450Y82984D03*
Y77784D03*
Y75184D03*
Y80384D03*
X48364Y92473D03*
X46450Y85584D03*
X51550Y90615D03*
X37988Y109410D03*
X46240D03*
X45988Y102323D03*
X46240Y116496D03*
X37988Y102323D03*
Y116496D03*
X46931Y130670D03*
X49236Y121658D03*
X37988Y130670D03*
Y123583D03*
X46932Y137756D03*
X52437D03*
X37988D03*
X45984Y163264D03*
X48476Y180812D03*
X37284Y285272D03*
X42690Y451466D03*
X48596Y458466D03*
X48643Y442919D03*
X45643Y472905D03*
X41643Y473419D03*
X49643Y472905D03*
X48390Y485128D03*
X51239Y485138D03*
X40009Y481467D03*
X39801Y504825D03*
X42301D03*
X44801D03*
X45293Y522569D03*
X39742Y517401D03*
X42242D03*
X44742D03*
X46993Y529169D03*
X41408Y531882D03*
X43908D03*
X45293Y525369D03*
X46408Y531882D03*
X38358Y531948D03*
X52869Y537958D03*
X39643Y555194D03*
X36843D03*
X49839Y546830D03*
X46643Y555194D03*
X52869Y540458D03*
X43843Y555194D03*
X39643Y563194D03*
X36843D03*
X39643Y571194D03*
X36843D03*
X46643D03*
X43843D03*
Y563194D03*
X46643D03*
X51000Y581222D03*
X45400D03*
X48200D03*
X51000Y591215D03*
X45400D03*
X48200D03*
X51172Y607762D03*
X48372D03*
X45572D03*
Y610562D03*
X48372D03*
X51172D03*
X37847Y662910D03*
X39549Y682108D03*
X36910D03*
X37804Y671508D03*
X40165Y699082D03*
X37365D03*
X51449Y822718D03*
X49249Y837718D03*
X52349D03*
X46049D03*
X49265Y886660D03*
X52922Y900295D03*
X48429Y916430D03*
X47264Y919649D03*
X47916Y947622D03*
X48683Y1006510D03*
X50541Y1009589D03*
X44999Y1009510D03*
X38823Y1009273D03*
X47197Y1014205D03*
X41197D03*
X44197Y1017759D03*
X38197D03*
X48704Y1017982D03*
X43889Y1062601D03*
X38689D03*
X41289D03*
Y1065101D03*
X38689D03*
X43889D03*
X50366Y1086981D03*
Y1082388D03*
X38200Y1089721D03*
X44365Y1086404D03*
X38216Y1093757D03*
X46166D03*
X39659Y1105100D03*
X42259D03*
X44859D03*
X47559D03*
X48585Y1123867D03*
X47559Y1114800D03*
X44859D03*
X42259D03*
X39659D03*
X48547Y1133688D03*
X51047D03*
X44960Y1190619D03*
X49500Y1199066D03*
X49638Y1203884D03*
X51197Y1218206D03*
X43198Y1254055D03*
X45698D03*
X48198D03*
X45698Y1251555D03*
X43198D03*
X48198D03*
X47621Y1343672D03*
X40996Y1467703D03*
X44195Y1511279D03*
X48195D03*
X40195D03*
X48089Y1501387D03*
X39095Y1501361D03*
X48079Y1525641D03*
Y1529641D03*
Y1521641D03*
X39237Y1532096D03*
X52048Y1556062D03*
X47074Y1555923D03*
X40951Y1555932D03*
X52000Y1644980D03*
X55638Y53597D03*
X64785Y79993D03*
Y82593D03*
Y85193D03*
Y74793D03*
Y77393D03*
X55921Y95236D03*
X56098Y109410D03*
Y116496D03*
X55964Y103037D03*
X64098Y102323D03*
Y109410D03*
Y116496D03*
X66856Y104249D03*
Y107649D03*
X56098Y123583D03*
Y130670D03*
X64098Y123583D03*
Y130670D03*
Y137756D03*
X66478Y162368D03*
X63878D03*
X69261Y211695D03*
Y208695D03*
X65189Y210713D03*
Y213213D03*
Y208213D03*
X54733Y212978D03*
Y215478D03*
Y207978D03*
Y210478D03*
X65189Y228961D03*
Y231461D03*
Y226461D03*
X68896Y226141D03*
X54733Y231226D03*
Y228726D03*
Y223726D03*
Y226226D03*
X65189Y215713D03*
X69139Y236611D03*
X68841Y248891D03*
X57987Y258880D03*
X60562Y264180D03*
X58062D03*
X66956Y267526D03*
Y270026D03*
X58279Y293796D03*
X66293Y285690D03*
X68793D03*
X66293Y288190D03*
X68793D03*
X60779Y293796D03*
X65759Y437508D03*
X61759D03*
X57759D03*
X54936Y449352D03*
X59522Y448874D03*
X68619Y447269D03*
X68497Y450201D03*
X54167Y457339D03*
X56667D03*
X66224Y473045D03*
X58224D03*
X53643Y472905D03*
X56667Y459839D03*
X54167D03*
Y462339D03*
X56667D03*
X62224Y473045D03*
X66371Y482134D03*
Y484634D03*
X55124Y478625D03*
X53739Y485138D03*
X56239D03*
X56824Y482425D03*
X55124Y475825D03*
X62700Y491214D03*
X59670Y500086D03*
X64550Y504699D03*
X62050D03*
X59550D03*
X66403Y495487D03*
X62700Y493714D03*
X66403Y492987D03*
X68236Y519458D03*
X61752Y516979D03*
X64252D03*
X59252D03*
X60233Y521804D03*
X68202Y522129D03*
X64495Y527449D03*
X60233Y524304D03*
X56540Y531378D03*
Y528878D03*
X61695Y527449D03*
X68202Y527129D03*
Y524629D03*
Y529629D03*
Y537877D03*
X56572Y539731D03*
X68202Y542877D03*
Y545377D03*
Y540377D03*
X56572Y542231D03*
X64130Y541895D03*
Y544895D03*
X61630Y541895D03*
X68188Y548358D03*
X67622Y572842D03*
X64408Y572975D03*
Y582747D03*
X67684Y597232D03*
X62789Y608311D03*
X61854Y617853D03*
Y620653D03*
X53972Y607762D03*
Y610562D03*
X59684Y605443D03*
X63684D03*
X55318Y629362D03*
X53129Y627948D03*
X66530Y625013D03*
X64692Y642184D03*
X55307Y688473D03*
X60849Y826818D03*
X64649D03*
X58949Y821018D03*
X56049Y827218D03*
X68649D03*
X64849Y840418D03*
X60249D03*
X69049Y847718D03*
X65549Y850718D03*
X66342Y880067D03*
X67316Y865869D03*
X68778Y873821D03*
X64175Y897500D03*
X67461Y912983D03*
X63303Y912835D03*
X68100Y910122D03*
X64632Y901500D03*
X57178Y981386D03*
X53197Y1014205D03*
Y1017759D03*
X69263Y1053152D03*
X55049Y1082343D03*
X55004Y1086937D03*
X62109Y1087656D03*
X58981Y1105100D03*
X56381D03*
X61581D03*
X64281D03*
X61681Y1114800D03*
X56481D03*
X59081D03*
X64381D03*
X57218Y1123867D03*
X55397Y1133688D03*
X57897D03*
X58250Y1220896D03*
X65940Y1209382D03*
X68245Y1212054D03*
X58250Y1227796D03*
Y1230296D03*
Y1237196D03*
Y1234696D03*
Y1223396D03*
X58443Y1272257D03*
X57185Y1480808D03*
X57144Y1491047D03*
X54843Y1501625D03*
X60227Y1514751D03*
X60277Y1528395D03*
X55862Y1541791D03*
X60303Y1534436D03*
X56114Y1556061D03*
X60747Y1555890D03*
X68743Y1583498D03*
X60864Y1583484D03*
X58064D03*
X55264D03*
X60554Y1615152D03*
X74432Y5374D03*
X73745Y24773D03*
Y44773D03*
X73381Y94017D03*
X69381D03*
X73110Y101701D03*
Y98551D03*
X77804Y95879D03*
X73509Y110445D03*
X78501D03*
X73509Y115401D03*
X78501D03*
X83911Y117557D03*
X80660Y103783D03*
X76660D03*
X73509Y129574D03*
Y124618D03*
X78501Y129574D03*
Y124618D03*
X83911Y122513D03*
Y131731D03*
Y136687D03*
X75194Y141247D03*
X71422Y147540D03*
Y151540D03*
X73578Y165393D03*
Y162793D03*
Y170493D03*
Y167993D03*
X72575Y181426D03*
X75786Y181366D03*
X78581Y181009D03*
X83756Y168697D03*
X75072Y191941D03*
X81572Y184619D03*
X84844Y191941D03*
X75400Y184012D03*
X72783Y184221D03*
X83552Y206760D03*
X71761Y211695D03*
X76819Y213859D03*
Y211359D03*
X80522Y213132D03*
X73158Y229286D03*
X76851Y222212D03*
Y224712D03*
X80522Y215632D03*
X74139Y236611D03*
X71639D03*
X73158Y231786D03*
X71341Y248891D03*
X73841D03*
X76766Y256535D03*
X84766D03*
X80766Y256303D03*
X72256Y267526D03*
X69756D03*
Y270026D03*
X72256D03*
X71593Y285690D03*
Y288190D03*
X75819Y290755D03*
X79819D03*
X71130Y462152D03*
Y459652D03*
Y464652D03*
X73630Y459652D03*
Y462152D03*
Y464652D03*
X71826Y480705D03*
X74326D03*
X69816Y475946D03*
Y478446D03*
X78033Y478586D03*
Y481086D03*
Y476086D03*
Y483586D03*
Y491133D03*
X71461Y498151D03*
Y495151D03*
X73961D03*
X78033Y498633D03*
Y496133D03*
Y493633D03*
X73961Y498151D03*
X75736Y519458D03*
X73236D03*
X70736D03*
X71995Y532749D03*
X74795D03*
X78133Y553297D03*
Y555897D03*
X75688Y548358D03*
X73188D03*
X70688D03*
X78133Y558497D03*
Y563697D03*
Y561097D03*
X72128Y570686D03*
X74923Y570478D03*
X75777Y585507D03*
X71184D03*
X71730Y579475D03*
X75340Y576484D03*
X74983Y573689D03*
X72337Y573303D03*
X71228Y590145D03*
X75822Y590190D03*
X75684Y605443D03*
X83684D03*
X81740Y619758D03*
Y616958D03*
Y614158D03*
X69670Y619513D03*
Y616713D03*
Y613913D03*
X79684Y605443D03*
X81740Y636250D03*
X69670Y633205D03*
Y636005D03*
X81740Y633450D03*
X69670Y638805D03*
X81740Y639050D03*
X79043Y667391D03*
X72314Y680207D03*
Y683407D03*
X82714Y674707D03*
X74414Y681907D03*
X84314Y686107D03*
X72149Y827318D03*
X74349Y824718D03*
Y821918D03*
X72549Y838818D03*
X71928Y873683D03*
X84367Y878286D03*
X76528Y878533D03*
X74028Y889065D03*
X83079Y888515D03*
X72035Y898346D03*
X80339Y897943D03*
X76203Y897910D03*
X76991Y946134D03*
X78167Y949261D03*
X76332Y953421D03*
X84679Y1018368D03*
X70059Y1071656D03*
X69373Y1063389D03*
X70059Y1075656D03*
X70302Y1067656D03*
X70059Y1079656D03*
X77734Y1095676D03*
X70947Y1201565D03*
Y1205835D03*
X71006Y1228684D03*
X71020Y1224323D03*
X76005Y1580680D03*
X82433Y1580590D03*
X74291Y1633801D03*
X82291D03*
X78291D03*
X70291D03*
X72000Y1644980D03*
X93334Y3000D03*
X88080Y103603D03*
X88903Y117557D03*
Y122513D03*
Y131731D03*
X87002Y146461D03*
X88903Y136687D03*
X92337Y144172D03*
X85904Y152367D03*
X97961Y152562D03*
X87604Y180572D03*
X92287Y180527D03*
X96010Y192421D03*
X92242Y185121D03*
X87604Y185165D03*
X99639Y186629D03*
X89353Y206767D03*
X86853D03*
X91853D03*
X89483Y221708D03*
X86983D03*
X86398Y224421D03*
X88098Y228221D03*
X96333Y221642D03*
X91983Y221708D03*
X93649Y236189D03*
X91149D03*
X88649D03*
X91090Y248765D03*
X88590D03*
X93590D03*
X85796Y279208D03*
X97747Y265897D03*
X100247D03*
X94087Y270695D03*
X91287D03*
X88787D03*
Y268195D03*
X91287D03*
X94087D03*
X94390Y293645D03*
Y290845D03*
Y288345D03*
X91890Y293645D03*
Y290845D03*
Y288345D03*
X98255Y374510D03*
X100120Y377898D03*
X100066Y381976D03*
X90257Y445506D03*
X86788Y581659D03*
X87684Y605443D03*
X93456Y649838D03*
X89432Y668293D03*
X92134D03*
X95973Y655660D03*
X92897Y658359D03*
X95917Y658374D03*
X95539Y664443D03*
X85614Y674707D03*
X87714Y684607D03*
X86289Y822088D03*
X86367Y848086D03*
X91581Y877859D03*
Y874859D03*
X87853Y899220D03*
X100058Y977651D03*
X99836Y980330D03*
X100200Y988800D03*
X91128Y1006487D03*
X99836Y997860D03*
X95836D03*
X85706Y998507D03*
X101025Y1009655D03*
X94586Y1023900D03*
X88287Y1026537D03*
X97609Y1018469D03*
X97247Y1030568D03*
X90450Y1033542D03*
X93496Y1547768D03*
X86291Y1633801D03*
X92000Y1644980D03*
X113334Y3000D03*
X107364Y113394D03*
Y110394D03*
X111582Y102249D03*
X110013Y110784D03*
X115582Y102249D03*
X107364Y116594D03*
X110152Y130898D03*
X117607Y133298D03*
X107364Y119594D03*
X111754Y134579D03*
X106205Y161306D03*
X107540Y172665D03*
Y180665D03*
Y176665D03*
Y168665D03*
X117501Y198883D03*
X115382Y195176D03*
X112882D03*
X117882D03*
X107540Y196665D03*
X107653Y186778D03*
X115242Y203393D03*
X112742D03*
X107572Y200864D03*
Y212864D03*
Y204864D03*
Y216864D03*
Y221864D03*
X112621Y218085D03*
X115421D03*
X103213Y219379D03*
X109329Y252371D03*
Y248371D03*
X112474Y716315D03*
X111993Y710102D03*
X114397Y727974D03*
X113505Y796856D03*
X113601Y881266D03*
X107641Y865224D03*
X102355Y874267D03*
X102947Y877196D03*
X102320Y891043D03*
X103972Y977609D03*
X103836Y980330D03*
X115836Y988813D03*
X107836D03*
X103836Y997860D03*
X111836D03*
X111275Y1008262D03*
X114770Y1009354D03*
X107836Y997860D03*
X115836D03*
X103825Y1009655D03*
X111275Y1011762D03*
X105971Y1025745D03*
X114770Y1016827D03*
Y1029427D03*
X110970Y1030672D03*
X101970D03*
X104970D03*
X107970D03*
X108933Y1102091D03*
X112433D03*
X103124D03*
X102761Y1096233D03*
X112433Y1114691D03*
X103124D03*
X108933D03*
X103124Y1109564D03*
Y1122164D03*
X108971D03*
X108933Y1127291D03*
X112433D03*
X103124D03*
X112433Y1139891D03*
X103124Y1134764D03*
X108971D03*
X103124Y1152491D03*
X108933D03*
X112433D03*
X103124Y1147364D03*
X108933Y1165091D03*
X112433D03*
X103124Y1172564D03*
X108971D03*
X103124Y1159964D03*
X108971D03*
X103184Y1177691D03*
X108933D03*
X112433D03*
X103861Y1182703D03*
X106586Y1204932D03*
X112795Y1223749D03*
X107669Y1456451D03*
Y1465913D03*
X116330Y1465513D03*
X107669Y1461182D03*
X116330Y1460782D03*
X107669Y1481267D03*
X116330Y1480867D03*
X107669Y1476536D03*
X116330Y1476136D03*
Y1470244D03*
X107669Y1471805D03*
X116330Y1491490D03*
Y1485598D03*
X107669Y1487159D03*
Y1496621D03*
X116330Y1496221D03*
X107669Y1491890D03*
X116330Y1506845D03*
Y1500952D03*
X107669Y1502514D03*
X116330Y1511576D03*
X107669Y1511976D03*
Y1507245D03*
X116330Y1516307D03*
X107669Y1563544D03*
X116330Y1563144D03*
X107669Y1558813D03*
Y1568275D03*
X116330Y1567875D03*
X107669Y1578898D03*
X116330Y1578498D03*
Y1572606D03*
X107669Y1574167D03*
Y1583629D03*
X116330Y1583229D03*
X107669Y1594253D03*
X116330Y1593853D03*
Y1587960D03*
X107669Y1589522D03*
Y1609607D03*
X116330Y1609207D03*
X107669Y1598984D03*
X116330Y1598584D03*
Y1603315D03*
X107669Y1604876D03*
X116330Y1613938D03*
Y1618669D03*
X107669Y1614338D03*
X112000Y1644980D03*
X129318Y4469D03*
X130679Y24773D03*
Y44773D03*
X133200Y95111D03*
X128350Y116497D03*
X133150D03*
X124606Y106495D03*
X125599Y109172D03*
X122599D03*
X124606Y102495D03*
X119333Y116594D03*
X133150Y123584D03*
X128350D03*
X133150Y130670D03*
X128350D03*
X119333Y119594D03*
X128350Y137757D03*
X133150D03*
X126246Y141228D03*
X124340Y146012D03*
Y142862D03*
X129134Y150847D03*
X131947Y199248D03*
X127929Y195176D03*
X130429D03*
X132929D03*
X118930Y206838D03*
X121430D03*
X128010Y210509D03*
X130510D03*
X132283Y206806D03*
X129783D03*
X131947Y201748D03*
X122000Y226320D03*
X119221Y216385D03*
X121934Y216970D03*
Y219470D03*
Y221970D03*
X124961Y228646D03*
X131102Y247292D03*
X130328Y238689D03*
X123892Y236121D03*
X120926Y238589D03*
X128687Y242078D03*
X123918Y232971D03*
X134044Y246874D03*
X123811Y253198D03*
X125125Y362403D03*
X118122Y747565D03*
X119099Y755052D03*
X118467Y796785D03*
X125698Y857515D03*
X122432Y857540D03*
X129666Y857514D03*
X133424Y857303D03*
X122887Y884000D03*
X127067Y891495D03*
X122887Y888000D03*
X131836Y988813D03*
X123836D03*
X124079Y1009354D03*
X119836Y997860D03*
X131836D03*
X127836D03*
X123836D03*
X120579Y1009354D03*
Y1021954D03*
X120617Y1016827D03*
X133870Y1105091D03*
X133579Y1097469D03*
X124880Y1105091D03*
X133870Y1117691D03*
X124880D03*
X133870Y1130291D03*
X124880D03*
X133870Y1142891D03*
Y1155491D03*
X124474Y1142997D03*
X124880Y1155491D03*
X133870Y1168091D03*
X124474Y1168197D03*
X124765Y1180691D03*
X121211Y1215195D03*
X126937Y1209607D03*
X129250Y1227650D03*
X124992Y1465913D03*
Y1456451D03*
Y1461182D03*
X133653Y1465513D03*
Y1460782D03*
X124992Y1471805D03*
Y1476536D03*
Y1481267D03*
X133653Y1476136D03*
Y1470244D03*
Y1480867D03*
Y1496221D03*
X124992Y1487159D03*
Y1491890D03*
Y1496621D03*
X133653Y1491490D03*
Y1485598D03*
Y1506845D03*
Y1500952D03*
Y1511576D03*
X124992Y1511976D03*
Y1507245D03*
Y1502514D03*
X133653Y1516307D03*
X124992Y1558813D03*
Y1563544D03*
X133653Y1563144D03*
Y1567875D03*
X124992Y1574167D03*
Y1578898D03*
X133653Y1578498D03*
Y1572606D03*
X124992Y1568275D03*
Y1589522D03*
Y1594253D03*
X133653Y1593853D03*
Y1587960D03*
X124992Y1583629D03*
X133653Y1583229D03*
X124992Y1609607D03*
Y1604876D03*
Y1598984D03*
X133653Y1609207D03*
Y1598584D03*
Y1603315D03*
X124992Y1614338D03*
X133653Y1613938D03*
Y1618669D03*
X132000Y1644980D03*
X138000Y53597D03*
X148812Y80384D03*
Y82984D03*
Y75184D03*
Y77784D03*
Y85584D03*
X148350Y95236D03*
X135650Y109410D03*
X148602D03*
Y116496D03*
X148350Y102323D03*
X140350Y116496D03*
Y109410D03*
Y102323D03*
X135650Y116497D03*
X137569Y106561D03*
X148774Y124576D03*
X149827Y130670D03*
X135650Y123583D03*
Y130670D03*
X140350D03*
Y123583D03*
X149822Y137756D03*
X140350D03*
X135429Y195176D03*
X136882Y213539D03*
X134947Y202048D03*
X138563Y238714D03*
X134563D03*
X138664Y241699D03*
X146196Y390223D03*
X148061Y382600D03*
X143186Y402291D03*
X138194Y397335D03*
X143186D03*
X146196Y395179D03*
Y404396D03*
Y409352D03*
X138194Y402291D03*
X140786Y416465D03*
Y411509D03*
X135794Y416465D03*
Y411509D03*
X146196Y418569D03*
Y423525D03*
X140786Y425682D03*
X135794D03*
X140786Y430638D03*
X135794D03*
X146196Y432743D03*
Y437699D03*
X140786Y439855D03*
X135794D03*
X148176Y458711D03*
X140786Y444811D03*
X135794D03*
X136604Y450750D03*
X148940Y455921D03*
X145376Y458711D03*
X135794Y468609D03*
X140786D03*
X135794Y473565D03*
X140786D03*
X147520Y463600D03*
X146196Y489895D03*
X135794Y487738D03*
X140786D03*
X146196Y480677D03*
Y475721D03*
X135794Y482782D03*
X140786D03*
X146196Y494851D03*
X135794Y512743D03*
X140786D03*
X135794Y517699D03*
X140786D03*
X146196Y519855D03*
X135794Y526916D03*
X140786Y531872D03*
X135794D03*
X146196Y524811D03*
Y538984D03*
Y534028D03*
X140786Y526916D03*
X140703Y536382D03*
X142024Y552466D03*
X145670Y597580D03*
X147893Y599588D03*
X147155Y589556D03*
X147094Y592354D03*
X145609Y594668D03*
X147896Y596095D03*
X147925Y603600D03*
X147893Y607588D03*
X147925Y619600D03*
Y623600D03*
X147836Y988813D03*
X139836D03*
Y997860D03*
X147836D03*
X143836D03*
X135836D03*
X145516Y1024954D03*
Y1012354D03*
X136526D03*
Y1024954D03*
X148534Y1046476D03*
X146595Y1053457D03*
X134457Y1180654D03*
X136432Y1224472D03*
X142315Y1456451D03*
Y1461182D03*
Y1465913D03*
Y1471805D03*
Y1476536D03*
Y1481267D03*
Y1487159D03*
Y1491890D03*
Y1496621D03*
Y1507245D03*
Y1502514D03*
Y1511976D03*
Y1558813D03*
Y1563544D03*
Y1574167D03*
Y1578898D03*
Y1568275D03*
Y1589522D03*
Y1594253D03*
Y1583629D03*
Y1609607D03*
Y1604876D03*
Y1598984D03*
Y1614338D03*
X158000Y53597D03*
X151366Y92849D03*
X158283Y95236D03*
X158233Y99961D03*
X158460Y116496D03*
X158326Y103037D03*
X158460Y109410D03*
X166460Y116496D03*
Y109410D03*
Y102323D03*
X158460Y130670D03*
Y123583D03*
X166460D03*
Y130670D03*
X155051Y137756D03*
X166460D03*
X166240Y162368D03*
X157095Y210478D03*
Y207978D03*
Y215478D03*
Y212978D03*
Y228726D03*
Y231226D03*
Y226226D03*
Y223726D03*
X160424Y264180D03*
X162924D03*
X160349Y258880D03*
X163141Y293796D03*
X160641D03*
X166528Y312392D03*
X151188Y390223D03*
Y395179D03*
Y404396D03*
Y409352D03*
Y423525D03*
Y418569D03*
Y432743D03*
Y437699D03*
X150703Y453682D03*
X151188Y489895D03*
Y480677D03*
Y475721D03*
Y494851D03*
Y519855D03*
Y538984D03*
Y534028D03*
Y524811D03*
X157375Y555234D03*
X157090Y562003D03*
X152386Y634946D03*
X151836Y997860D03*
X159836D03*
X164028Y1041468D03*
X160733Y1056594D03*
X160547Y1049283D03*
X160627Y1053561D03*
X160807Y1043955D03*
X155513Y1065148D03*
X166188Y1066551D03*
X163191Y1065313D03*
X159228Y1065613D03*
X159637Y1461182D03*
X150976Y1465513D03*
Y1460782D03*
X159637Y1465913D03*
Y1456451D03*
X150976Y1476136D03*
Y1470244D03*
Y1480867D03*
X159637Y1471805D03*
Y1476536D03*
Y1481267D03*
Y1496621D03*
X150976Y1491490D03*
Y1485598D03*
Y1496221D03*
X159637Y1487159D03*
Y1491890D03*
X150976Y1500952D03*
Y1511576D03*
X159637Y1507245D03*
Y1502514D03*
Y1511976D03*
X150976Y1506845D03*
Y1516307D03*
X159637Y1558813D03*
Y1563544D03*
X150976Y1563144D03*
X159637Y1578898D03*
X150976Y1567875D03*
Y1578498D03*
Y1572606D03*
X159637Y1568275D03*
Y1574167D03*
X150976Y1583229D03*
Y1593853D03*
Y1587960D03*
X159637Y1583629D03*
Y1589522D03*
Y1594253D03*
X150976Y1609207D03*
Y1598584D03*
Y1603315D03*
X159637Y1609607D03*
Y1604876D03*
Y1598984D03*
X150976Y1613938D03*
Y1618669D03*
X159637Y1614338D03*
X152000Y1644980D03*
X176794Y5374D03*
X176107Y24773D03*
Y44773D03*
X167147Y77393D03*
Y74793D03*
Y85193D03*
Y82593D03*
Y79993D03*
X179743Y94017D03*
X175743D03*
X171743D03*
X175472Y101701D03*
Y98551D03*
X175871Y110445D03*
X180863Y115401D03*
Y110445D03*
X175871Y115401D03*
X179022Y103783D03*
X169218Y107649D03*
Y104249D03*
X180863Y129574D03*
Y124618D03*
X175871Y129574D03*
Y124618D03*
X173784Y147540D03*
X177556Y141247D03*
X173784Y151540D03*
X175940Y162793D03*
Y165393D03*
X168840Y162368D03*
X175940Y167993D03*
Y170493D03*
X178148Y181366D03*
X180943Y181009D03*
X174937Y181426D03*
X177434Y191941D03*
X175145Y184221D03*
X177762Y184012D03*
X171623Y211695D03*
X182884Y213132D03*
X179181Y211359D03*
Y213859D03*
X174123Y211695D03*
X167551Y208213D03*
Y213213D03*
Y210713D03*
X171623Y208695D03*
X175520Y229286D03*
X179213Y224712D03*
Y222212D03*
X171258Y226141D03*
X167551Y231461D03*
Y228961D03*
Y226461D03*
Y215713D03*
X182884Y215632D03*
X174001Y236611D03*
X176501D03*
X175520Y231786D03*
X171501Y236611D03*
X176203Y248891D03*
X173703D03*
X171203D03*
X179128Y256535D03*
X174618Y267526D03*
Y270026D03*
X169318Y267526D03*
X172118D03*
Y270026D03*
X169318D03*
X173955Y285690D03*
Y288190D03*
X171155Y285690D03*
X168655Y288190D03*
X171155D03*
X168655Y285690D03*
X182181Y290755D03*
X178181D03*
X170215Y311671D03*
X177369Y389154D03*
Y396240D03*
Y403327D03*
Y410413D03*
Y417500D03*
Y424587D03*
Y431673D03*
Y438760D03*
Y445847D03*
Y467539D03*
Y474626D03*
Y488799D03*
Y481713D03*
Y495886D03*
Y511673D03*
Y518760D03*
Y525847D03*
Y532933D03*
Y540020D03*
Y547106D03*
X175615Y550907D03*
X173115D03*
X175615Y553407D03*
X173115D03*
X174923Y545263D03*
Y541863D03*
X177385Y566929D03*
X171339Y572070D03*
X172686Y569928D03*
X175033Y570962D03*
X174776Y568475D03*
X177099Y569426D03*
X176650Y602197D03*
X177114Y595108D03*
X168299Y1465513D03*
Y1460782D03*
X176960Y1465914D03*
Y1456452D03*
Y1461183D03*
X168299Y1476136D03*
Y1470244D03*
Y1480867D03*
X176960Y1476537D03*
Y1471806D03*
Y1481268D03*
X168299Y1491490D03*
Y1485598D03*
Y1496221D03*
X176960Y1491891D03*
Y1487160D03*
Y1496622D03*
Y1507246D03*
Y1502515D03*
X168299Y1506845D03*
Y1500952D03*
Y1511576D03*
X176960Y1511977D03*
X168299Y1516307D03*
Y1563144D03*
X176960Y1563544D03*
Y1558813D03*
Y1568275D03*
X168299Y1578498D03*
Y1572606D03*
Y1567875D03*
Y1583229D03*
X176960Y1583629D03*
X168299Y1593853D03*
Y1587960D03*
X176960Y1594253D03*
Y1589522D03*
X168299Y1609207D03*
Y1598584D03*
Y1603315D03*
X176960Y1609607D03*
Y1598984D03*
Y1604876D03*
X168299Y1613938D03*
Y1618669D03*
X176960Y1614338D03*
X172000Y1644980D03*
X195697Y3000D03*
X188820Y80140D03*
Y84140D03*
Y76140D03*
X191568Y76587D03*
Y72615D03*
X183752Y94017D03*
X186273Y117557D03*
X191265D03*
X183022Y103783D03*
X194189Y103621D03*
X185957Y106186D03*
X197380Y112083D03*
X186273Y131731D03*
Y122513D03*
X191265D03*
Y131731D03*
X189364Y146461D03*
X186273Y136687D03*
X191265D03*
X188266Y152367D03*
X194649Y180527D03*
X189966Y180572D03*
X186118Y168697D03*
X198372Y192421D03*
X189966Y185165D03*
X194604Y185121D03*
X183934Y184619D03*
X187206Y191941D03*
X185914Y206760D03*
X189215Y206767D03*
X191715D03*
X194215D03*
X194345Y221708D03*
X198695Y221642D03*
X190460Y228221D03*
Y231021D03*
X191845Y221708D03*
X188760Y224421D03*
X189345Y221708D03*
X191011Y236189D03*
X193511D03*
X196011D03*
X187128Y256535D03*
X190952Y248765D03*
X193452D03*
X195952D03*
X183128Y256303D03*
X188158Y279208D03*
X196449Y268195D03*
X193649D03*
X196449Y270695D03*
X193649D03*
X191149D03*
Y268195D03*
X196752Y293645D03*
Y290845D03*
Y288345D03*
X194252Y293645D03*
Y290845D03*
Y288345D03*
X191988Y389154D03*
X185169D03*
Y396240D03*
X186448Y404911D03*
X190518Y396240D03*
X194603Y422864D03*
X186589Y426299D03*
X185402Y412571D03*
X195295Y414823D03*
X194673Y429832D03*
X194278Y436447D03*
X186900Y445847D03*
X196313Y447953D03*
X185169Y467539D03*
X195480D03*
X185169Y474626D03*
X194222Y472772D03*
X194956Y487711D03*
X195069Y479104D03*
X185430Y480828D03*
X187380Y498834D03*
X195480Y495886D03*
X190829Y516841D03*
X194080Y510565D03*
X185169Y518760D03*
Y511673D03*
Y525847D03*
X185654Y552872D03*
X185776Y550123D03*
X185099Y562443D03*
X186867Y560675D03*
X187408Y572334D03*
X185640Y574102D03*
X194063Y577716D03*
X191125Y602400D03*
Y598400D03*
Y594400D03*
Y606400D03*
Y614400D03*
Y610400D03*
X193723Y656942D03*
X185622Y1465513D03*
Y1460782D03*
Y1480868D03*
Y1476137D03*
Y1470244D03*
Y1485599D03*
X192000Y1644980D03*
X211262Y60922D03*
X206398Y55513D03*
X203248D03*
X199473Y68581D03*
X208645Y60369D03*
X199486Y80581D03*
X208463Y96472D03*
X203591Y91951D03*
X203616Y88801D03*
X214389Y94374D03*
X206533Y94351D03*
X209530Y86046D03*
X205976Y85731D03*
X202195Y117261D03*
X209726Y113394D03*
Y110394D03*
X213944Y102249D03*
X212375Y110784D03*
X209726Y116594D03*
X201669Y103621D03*
X211969Y133298D03*
X209726Y119594D03*
X214116Y134579D03*
X208567Y161306D03*
X200323Y152562D03*
X205818Y157370D03*
X209902Y172665D03*
Y180665D03*
Y176665D03*
Y168665D03*
X215244Y195176D03*
X202001Y186629D03*
X209902Y192665D03*
X210015Y186778D03*
X209934Y200864D03*
X215104Y203393D03*
X209934Y212864D03*
Y204864D03*
Y216864D03*
Y221864D03*
X205575Y219379D03*
X211691Y252371D03*
Y248371D03*
X200109Y265897D03*
X202609D03*
X215380Y389153D03*
X210580D03*
X203280Y389154D03*
X215380Y396240D03*
X208080Y403327D03*
X215380Y403326D03*
X210580D03*
X208080Y410413D03*
X210580D03*
X215380D03*
X203280Y396240D03*
Y403327D03*
Y410413D03*
X208080Y396240D03*
X210580D03*
X208080Y417500D03*
X215380Y417499D03*
X210580D03*
X208080Y424586D03*
X210580D03*
X215380D03*
X203280Y417500D03*
Y424586D03*
X208080Y431673D03*
Y438760D03*
X210580D03*
X215380D03*
Y431673D03*
X210580D03*
X203280D03*
Y438760D03*
Y445847D03*
X208080D03*
X215380Y467539D03*
X210580D03*
X203280D03*
X208080Y474626D03*
X210580D03*
X215380D03*
X203280D03*
X215380Y488799D03*
X203280D03*
X208080D03*
X210580D03*
X203280Y481713D03*
X210580Y481712D03*
X208080D03*
X215380D03*
X208080Y495886D03*
X203280D03*
X215380Y518760D03*
X210580D03*
X208080D03*
X210580Y511673D03*
X215380D03*
X203280D03*
Y518760D03*
X210580Y532933D03*
X208080D03*
Y540020D03*
Y525846D03*
X210580D03*
X215380D03*
Y532933D03*
X203280Y525847D03*
Y532933D03*
Y540020D03*
Y547106D03*
Y554193D03*
X212460Y560500D03*
X203740Y567914D03*
Y565414D03*
Y570414D03*
X204674Y558917D03*
Y561420D03*
X203740Y575414D03*
Y572914D03*
X200495Y577937D03*
X203280Y602205D03*
Y595118D03*
X209429Y625300D03*
X208540Y621591D03*
X205941Y668934D03*
X201115Y695581D03*
X203046Y693716D03*
X213296Y1438215D03*
X215697Y3000D03*
X231681Y4469D03*
X224961Y109172D03*
X226968Y106495D03*
X230712Y116497D03*
X217944Y102249D03*
X227961Y109172D03*
X221695Y116594D03*
X226968Y102495D03*
X230712Y123584D03*
Y130670D03*
X219969Y133298D03*
X221695Y119594D03*
X228608Y141228D03*
X230712Y137757D03*
X226702Y146012D03*
Y142862D03*
X231496Y150847D03*
X220244Y195176D03*
X219863Y198883D03*
X217744Y195176D03*
X230291D03*
X223792Y206838D03*
X221292D03*
X217604Y203393D03*
X230372Y210509D03*
X224362Y226320D03*
X224296Y216970D03*
Y219470D03*
Y221970D03*
X221583Y216385D03*
X217783Y218085D03*
X226254Y236121D03*
X223288Y238589D03*
X231049Y242078D03*
X226280Y232971D03*
X226173Y253198D03*
X228760Y316122D03*
X230842Y313888D03*
X228267Y392718D03*
Y408718D03*
Y400718D03*
Y396718D03*
X221375Y455024D03*
X220349Y465622D03*
X225500Y530000D03*
X225000Y540500D03*
X223925Y543925D03*
X224500Y555000D03*
X224000Y547075D03*
X224200Y549800D03*
X224104Y562800D03*
X224040Y558800D03*
X222289Y590895D03*
X222646Y607542D03*
X220255Y629749D03*
X217945Y1423924D03*
X217799Y1433684D03*
X217906Y1430452D03*
Y1427052D03*
X222253Y1438483D03*
X219525Y1440028D03*
X216125D03*
X229260Y1469587D03*
X218171Y1474460D03*
X224176Y1492816D03*
X217614Y1489671D03*
X223235Y1506770D03*
X222908Y1502028D03*
X226957Y1510442D03*
X216342Y1515642D03*
X217519Y1537172D03*
X233042Y24773D03*
Y44773D03*
X240363Y53597D03*
X235562Y95111D03*
X242712Y116496D03*
Y109410D03*
Y102323D03*
X238012Y116497D03*
X235512D03*
X238012Y109410D03*
X239931Y106561D03*
X238012Y123583D03*
Y130670D03*
X235512D03*
X242712D03*
Y123583D03*
X235512Y123584D03*
Y137757D03*
X242712Y137756D03*
X233843Y143762D03*
X232791Y195176D03*
X235291D03*
X234309Y199248D03*
X237791Y195176D03*
X239244Y213539D03*
X237309Y202048D03*
X232872Y210509D03*
X234645Y206806D03*
X232145D03*
X234309Y201748D03*
X232690Y238689D03*
X240925Y238714D03*
X233464Y247292D03*
X236925Y238714D03*
X236406Y246874D03*
X238626Y244297D03*
X236349Y339428D03*
X245362Y542712D03*
X247333Y599506D03*
X247536Y602689D03*
X241967Y616063D03*
X247278Y618288D03*
X243278D03*
X243078Y636486D03*
X240249Y628328D03*
X241084Y638243D03*
X240194Y643113D03*
X246583Y665140D03*
X242102Y656321D03*
X246102D03*
X241850Y678462D03*
X245000D03*
X244267Y696911D03*
X241204Y814841D03*
X237591Y815266D03*
X247600Y848500D03*
X232675Y1466801D03*
X240466Y1503857D03*
X243268Y1501903D03*
X237700Y1531600D03*
X260363Y53597D03*
X251174Y77784D03*
Y80384D03*
Y82984D03*
Y75184D03*
Y85584D03*
X253728Y92849D03*
X260645Y95236D03*
X250712D03*
X260688Y103037D03*
X250964Y109410D03*
X250712Y102323D03*
X250964Y116496D03*
X260822D03*
Y109410D03*
X251136Y124576D03*
X260822Y130670D03*
Y123583D03*
X252189Y130670D03*
X257413Y137756D03*
X252184D03*
X259457Y210478D03*
Y207978D03*
Y215478D03*
Y212978D03*
Y228726D03*
Y231226D03*
Y226226D03*
Y223726D03*
X262786Y264180D03*
X262711Y258880D03*
X263003Y293796D03*
X257226Y312081D03*
X257993Y307994D03*
X256475Y422088D03*
X255000Y427017D03*
X254692Y431029D03*
X253758Y435029D03*
X254512Y438323D03*
X254678Y449873D03*
X250336Y456386D03*
X254678Y445873D03*
X263301Y444232D03*
X261605Y465492D03*
Y472579D03*
X259105D03*
X254305D03*
X249125Y465874D03*
X261605Y486752D03*
X254305D03*
X259105Y479666D03*
X261605D03*
X254305D03*
X259105Y486752D03*
X254305Y493839D03*
X259105D03*
X261605Y516713D03*
X259105D03*
Y523800D03*
X261605D03*
X254305D03*
Y516713D03*
X261605Y509626D03*
Y530886D03*
X259105D03*
Y537973D03*
X254305Y530886D03*
Y537973D03*
Y566752D03*
X261605Y559665D03*
Y566752D03*
X259105D03*
X261605Y588012D03*
X259105Y588013D03*
X254305Y573839D03*
X261605D03*
X259105D03*
X261605Y580926D03*
X259105D03*
X254305D03*
Y588013D03*
X259105Y602186D03*
X254305D03*
Y595099D03*
X259105D03*
X261605D03*
Y602185D03*
X254305Y609272D03*
X259105D03*
X261605D03*
X259105Y616359D03*
X254305D03*
X248984Y638125D03*
X258867Y680499D03*
X248690Y678519D03*
X248090Y691114D03*
X254634Y698241D03*
X248506Y812042D03*
X251802Y824128D03*
X250700Y819900D03*
X254058Y819851D03*
X252100Y836800D03*
X248042Y1532900D03*
X279156Y5374D03*
X278469Y24773D03*
Y44773D03*
X269509Y77393D03*
Y74793D03*
Y85193D03*
Y82593D03*
Y79993D03*
X274105Y94017D03*
X278105D03*
X277834Y101701D03*
Y98551D03*
X268822Y116496D03*
Y109410D03*
X278233Y115401D03*
Y110445D03*
X268822Y102323D03*
X271580Y107649D03*
Y104249D03*
X268822Y130670D03*
Y123583D03*
X278233Y129574D03*
Y124618D03*
X268822Y137756D03*
X276146Y147540D03*
X279918Y141247D03*
X276146Y151540D03*
X268602Y162368D03*
X271202D03*
X278302Y162793D03*
Y165393D03*
Y167993D03*
Y170493D03*
X277299Y181426D03*
X279796Y191941D03*
X280124Y184012D03*
X277507Y184221D03*
X269913Y210713D03*
X273985Y208695D03*
Y211695D03*
X276485D03*
X269913Y208213D03*
Y213213D03*
Y228961D03*
Y226461D03*
X277882Y229286D03*
X273620Y226141D03*
X269913Y231461D03*
Y215713D03*
X276363Y236611D03*
X278863D03*
X277882Y231786D03*
X273863Y236611D03*
X276065Y248891D03*
X273565D03*
X278565D03*
X265286Y264180D03*
X276980Y267526D03*
Y270026D03*
X271680Y267526D03*
X274480D03*
Y270026D03*
X271680D03*
X276317Y288190D03*
X273517Y285690D03*
X271017Y288190D03*
X273517D03*
X271017Y285690D03*
X265503Y293796D03*
X276317Y285690D03*
X274425Y390500D03*
Y381500D03*
X265011Y410394D03*
X265945Y440098D03*
Y437598D03*
Y435098D03*
Y432598D03*
Y430098D03*
X274949Y442606D03*
X266405Y451319D03*
Y458406D03*
X278827Y444841D03*
X265011Y453881D03*
X280220Y448493D03*
X274866Y446606D03*
X265011Y446595D03*
X274205Y466027D03*
X266405Y465492D03*
X266229Y462264D03*
X274347Y475262D03*
X266405Y472579D03*
X275873Y463479D03*
X276344Y467367D03*
X274347Y489435D03*
Y482666D03*
X266405Y479665D03*
Y486752D03*
Y493839D03*
X274163Y495088D03*
X266405Y523799D03*
Y516713D03*
Y509626D03*
X274205D03*
X274820Y522134D03*
X274898Y514608D03*
X266405Y530886D03*
Y537973D03*
X275463Y529136D03*
X275302Y535677D03*
X266405Y566752D03*
Y559665D03*
X274586Y565574D03*
X274205Y559665D03*
X266405Y580926D03*
Y588012D03*
Y573839D03*
X274233Y574338D03*
X266405Y602185D03*
Y595099D03*
Y609272D03*
Y616358D03*
X274332D03*
X274096Y820725D03*
X274697Y830951D03*
X269700Y853100D03*
X275400Y864400D03*
X269700Y884600D03*
X278400Y890839D03*
X275400Y899400D03*
X269900Y914200D03*
X279261Y926339D03*
X278739Y936439D03*
X270100Y946500D03*
X281594Y1211712D03*
X270374Y1215452D03*
X272000Y1644980D03*
X294959Y11097D03*
X289797Y36735D03*
X284666Y34068D03*
X286129Y36971D03*
X291182Y84140D03*
Y80140D03*
Y76140D03*
X293930Y76587D03*
Y72615D03*
X282105Y94017D03*
X286114D03*
X288635Y117557D03*
X283225Y115401D03*
Y110445D03*
X285384Y103783D03*
X296551Y103621D03*
X293627Y117557D03*
X281384Y103783D03*
X288319Y106186D03*
X288635Y131731D03*
Y122513D03*
X283225Y129574D03*
Y124618D03*
X293627Y122513D03*
Y131731D03*
X291726Y146461D03*
X293627Y136687D03*
X288635D03*
X295948Y141247D03*
X290628Y152367D03*
X292328Y180572D03*
X280510Y181366D03*
X283305Y181009D03*
X288480Y168697D03*
X292328Y185165D03*
X286296Y184619D03*
X289568Y191941D03*
X288276Y206760D03*
X291577Y206767D03*
X294077D03*
X296577D03*
X285246Y213132D03*
X281543Y211359D03*
Y213859D03*
X281575Y224712D03*
Y222212D03*
X296707Y221708D03*
X292822Y228221D03*
Y231021D03*
X294207Y221708D03*
X291122Y224421D03*
X291707Y221708D03*
X285246Y215632D03*
X293373Y236189D03*
X295873D03*
X281490Y256535D03*
X289490D03*
X293314Y248765D03*
X295814D03*
X285490Y256303D03*
X290520Y279208D03*
X296011Y270695D03*
X293511D03*
Y268195D03*
X296011D03*
X296614Y293645D03*
Y290845D03*
Y288345D03*
X284543Y290755D03*
X280543D03*
X286940Y315039D03*
X284075Y381500D03*
X292520Y384410D03*
X292500Y410394D03*
Y403307D03*
X284295Y430760D03*
X284316Y433570D03*
X284132Y437072D03*
X284173Y439963D03*
X295253Y440869D03*
Y438269D03*
X292453D03*
Y440869D03*
Y435669D03*
Y430469D03*
Y433069D03*
X295253D03*
Y430469D03*
Y435669D03*
X284417Y443180D03*
X284437Y454744D03*
X284379Y452018D03*
X292316Y458406D03*
X293307Y451677D03*
X295807D03*
X293307Y454177D03*
X295807D03*
X284482Y460250D03*
X284516Y465492D03*
X282247Y470136D03*
X292316Y465492D03*
X284516Y472579D03*
X292316D03*
X295011Y460218D03*
Y463618D03*
X284516Y479665D03*
Y486752D03*
X292316Y479665D03*
Y486752D03*
Y493839D03*
X284516D03*
X292316Y523799D03*
Y516713D03*
Y509626D03*
X284516Y516713D03*
Y509626D03*
X292316Y537973D03*
Y530886D03*
X283377Y532756D03*
X283456Y525483D03*
X280976Y537973D03*
X284516Y559665D03*
Y566752D03*
X292316Y559665D03*
Y566752D03*
X284366Y579978D03*
X292316Y573839D03*
Y588012D03*
Y580925D03*
X284516Y573839D03*
X292316Y595099D03*
Y602185D03*
X284580Y608117D03*
X292316Y616358D03*
Y609272D03*
X281980Y953926D03*
X280897Y1465913D03*
X289558Y1465513D03*
X280897Y1461182D03*
X289558Y1460782D03*
X280897Y1456451D03*
X289558Y1480867D03*
X280897Y1476536D03*
X289558Y1476136D03*
Y1470244D03*
X280897Y1471805D03*
Y1481267D03*
Y1491890D03*
X289558Y1491490D03*
Y1485598D03*
X280897Y1487159D03*
Y1496621D03*
X289558Y1496221D03*
X280897Y1507245D03*
X289558Y1506845D03*
Y1500952D03*
X280897Y1502514D03*
X289558Y1511576D03*
X280897Y1511976D03*
X289558Y1516307D03*
X280897Y1563544D03*
X289558Y1563144D03*
X280897Y1558813D03*
Y1574167D03*
Y1568275D03*
X289558Y1567875D03*
X280897Y1578898D03*
X289558Y1578498D03*
Y1572606D03*
Y1593853D03*
Y1587960D03*
X280897Y1589522D03*
Y1583629D03*
X289558Y1583229D03*
X280897Y1594253D03*
Y1609607D03*
X289558Y1609207D03*
X280897Y1598984D03*
X289558Y1598584D03*
Y1603315D03*
X280897Y1604876D03*
Y1614338D03*
X289558Y1613938D03*
Y1618669D03*
X292000Y1644980D03*
X298059Y3000D03*
X309106Y37543D03*
X312256D03*
X308760Y55513D03*
X305610D03*
X301835Y68581D03*
X310817Y60393D03*
X301848Y80581D03*
X310882Y96613D03*
X305953Y91951D03*
X305978Y88801D03*
X308895Y94351D03*
X308338Y85731D03*
X311892Y86046D03*
X312088Y113394D03*
X304557Y117261D03*
X312088Y116594D03*
X299742Y112083D03*
X304031Y103621D03*
X312088Y119594D03*
X310929Y161306D03*
X302685Y152562D03*
X308180Y157370D03*
X297011Y180527D03*
X312264Y172665D03*
Y180665D03*
Y176665D03*
Y168665D03*
X299759Y190285D03*
X296966Y185121D03*
X304363Y186629D03*
X312264Y196665D03*
Y192665D03*
X312377Y186778D03*
X300814Y192859D03*
X312296Y212864D03*
Y200864D03*
Y204864D03*
Y221864D03*
Y216864D03*
X301057Y221642D03*
X307937Y219379D03*
X298373Y236189D03*
X298314Y248765D03*
X302471Y265897D03*
X304971D03*
X298811Y270695D03*
Y268195D03*
X299114Y290845D03*
Y288345D03*
Y293645D03*
X302966Y324139D03*
X310013Y316731D03*
X301943Y328867D03*
X306812Y342319D03*
X301943Y332017D03*
X308952Y356875D03*
X312316Y356747D03*
X301158Y380307D03*
X309258Y389912D03*
Y393924D03*
Y385912D03*
X301308Y395346D03*
X301393Y400039D03*
X309258Y409924D03*
Y405924D03*
Y401924D03*
X306673Y418838D03*
X298507Y445908D03*
X302457Y445787D03*
X298220Y1465913D03*
Y1456451D03*
Y1461182D03*
X306881Y1465513D03*
Y1460782D03*
Y1470244D03*
Y1480867D03*
X298220Y1471805D03*
Y1476536D03*
Y1481267D03*
X306881Y1476136D03*
X298220Y1487159D03*
Y1491890D03*
Y1496621D03*
X306881Y1491490D03*
Y1485598D03*
Y1496221D03*
X298220Y1507245D03*
Y1502514D03*
X306881Y1506845D03*
Y1500952D03*
Y1511576D03*
X298220Y1511976D03*
X306881Y1516307D03*
X298220Y1558813D03*
Y1563544D03*
X306881Y1563144D03*
X298220Y1568275D03*
X306881Y1567875D03*
X298220Y1574167D03*
Y1578898D03*
X306881Y1578498D03*
Y1572606D03*
X298220Y1583629D03*
X306881Y1583229D03*
X298220Y1589522D03*
Y1594253D03*
X306881Y1593853D03*
Y1587960D03*
Y1598584D03*
Y1603315D03*
X298220Y1609607D03*
Y1604876D03*
Y1598984D03*
X306881Y1609207D03*
X298220Y1614338D03*
X306881Y1613938D03*
Y1618669D03*
X312000Y1644980D03*
X318059Y3000D03*
X313624Y60922D03*
X316751Y94374D03*
X320306Y102249D03*
X327323Y109172D03*
X316306Y102249D03*
X314737Y110784D03*
X324057Y116594D03*
X314854Y130898D03*
X322331Y133298D03*
X324057Y119594D03*
X329064Y146012D03*
X316478Y134579D03*
X329064Y142862D03*
X322225Y198883D03*
X322606Y195176D03*
X320106D03*
X317606D03*
X323654Y206838D03*
X319966Y203393D03*
X317466D03*
X326154Y206838D03*
X317345Y218085D03*
X320145D03*
X323945Y216385D03*
X326658Y216970D03*
Y219470D03*
X326724Y226320D03*
X326658Y221970D03*
X325650Y238589D03*
X328616Y236121D03*
X328642Y232971D03*
X328535Y253198D03*
X314053Y252371D03*
Y248371D03*
X323882Y303839D03*
X327032Y303962D03*
X314855Y311740D03*
X319857Y321649D03*
X315904Y336324D03*
X320483Y353506D03*
X317333Y353470D03*
X315310Y356712D03*
X321549Y445315D03*
Y448115D03*
X323489Y471484D03*
X318497Y466528D03*
X323489D03*
X318497Y471484D03*
X328899Y473640D03*
Y487813D03*
X323489Y480701D03*
X328899Y478596D03*
X318497Y480701D03*
Y485657D03*
X323489D03*
X328899Y492769D03*
X323489Y515617D03*
X328899Y517774D03*
X318497Y510661D03*
X323489D03*
X318497Y515617D03*
X328899Y522730D03*
X318497Y524835D03*
X328899Y536903D03*
Y531947D03*
X323489Y529791D03*
Y524835D03*
X318497Y529791D03*
X318660Y539315D03*
X320785Y553287D03*
X324291Y556775D03*
X328899Y572769D03*
X318497Y565657D03*
Y560701D03*
X328899Y567813D03*
X323489Y565657D03*
Y560701D03*
X318497Y579830D03*
X323489Y574874D03*
X318497D03*
X323489Y579830D03*
X328899Y581987D03*
X323489Y589047D03*
X318497D03*
X328899Y586943D03*
X318497Y594003D03*
X328899Y596160D03*
X323489Y594003D03*
Y603221D03*
X318497D03*
X328899Y601116D03*
Y610333D03*
X323489Y608177D03*
X318497D03*
X328899Y615289D03*
X321119Y622912D03*
X315543Y1465913D03*
Y1456451D03*
Y1461182D03*
X324204Y1465513D03*
Y1460782D03*
Y1480867D03*
X315543Y1471805D03*
Y1476536D03*
Y1481267D03*
X324204Y1476136D03*
Y1470244D03*
X315543Y1487159D03*
Y1491890D03*
Y1496621D03*
X324204Y1491490D03*
Y1485598D03*
Y1496221D03*
Y1500952D03*
Y1511576D03*
X315543Y1507245D03*
Y1502514D03*
Y1511976D03*
X324204Y1506845D03*
Y1516307D03*
X315543Y1558813D03*
Y1563544D03*
X324204Y1563144D03*
X315543Y1574167D03*
Y1578898D03*
X324204Y1567875D03*
Y1578498D03*
Y1572606D03*
X315543Y1568275D03*
Y1583629D03*
Y1589522D03*
Y1594253D03*
X324204Y1583229D03*
Y1593853D03*
Y1587960D03*
X315543Y1609607D03*
Y1604876D03*
Y1598984D03*
X324204Y1609207D03*
Y1598584D03*
Y1603315D03*
X315543Y1614338D03*
X324204Y1613938D03*
Y1618669D03*
X334043Y4469D03*
X330905Y11806D03*
Y15806D03*
Y19806D03*
X335404Y24773D03*
X330905Y23806D03*
Y31806D03*
Y27806D03*
X335404Y44773D03*
X342725Y53597D03*
X337924Y95111D03*
X329330Y106495D03*
X345074Y116496D03*
X337874Y116497D03*
X340374D03*
X345074Y109410D03*
Y102323D03*
X340374Y109410D03*
X333074Y116497D03*
X330323Y109172D03*
X329330Y102495D03*
X342293Y106561D03*
X337874Y130670D03*
X345074D03*
Y123583D03*
X340374D03*
X337874Y123584D03*
X333074D03*
Y130670D03*
X340374D03*
X333074Y137757D03*
X337874D03*
X330970Y141228D03*
X345074Y137756D03*
X333858Y150847D03*
X335153Y195176D03*
X332653D03*
X336671Y199248D03*
X337653Y195176D03*
X340153D03*
X341606Y213539D03*
X336671Y201748D03*
X334507Y206806D03*
X337007D03*
X335234Y210509D03*
X332734D03*
X339671Y202048D03*
X335052Y238689D03*
X335826Y247292D03*
X343287Y238714D03*
X339287D03*
X333411Y242078D03*
X338768Y246874D03*
X339072Y416888D03*
Y419488D03*
Y422088D03*
X345050Y458334D03*
Y454334D03*
X333891Y473640D03*
Y487813D03*
Y478596D03*
Y492769D03*
Y522730D03*
Y517774D03*
Y531947D03*
Y536903D03*
X338358Y554861D03*
X337078Y551381D03*
X335399Y544718D03*
X333891Y572769D03*
Y567813D03*
Y586943D03*
Y581987D03*
Y596160D03*
Y601116D03*
Y610333D03*
Y615289D03*
X337564Y1018294D03*
X339251Y1138130D03*
X336755Y1143489D03*
X341266Y1171956D03*
X337629Y1186071D03*
X330800Y1174500D03*
X343121Y1188412D03*
X335502Y1188222D03*
X336901Y1196407D03*
X339540Y1196894D03*
X341527Y1460782D03*
X332865Y1465913D03*
Y1456451D03*
Y1461182D03*
X341527Y1465513D03*
Y1476136D03*
Y1470244D03*
Y1480867D03*
X332865Y1471805D03*
Y1476536D03*
Y1481267D03*
X341527Y1491490D03*
Y1485598D03*
Y1496221D03*
X332865Y1487159D03*
Y1491890D03*
Y1496621D03*
Y1511976D03*
X341527Y1506845D03*
Y1500952D03*
Y1511576D03*
X332865Y1507245D03*
Y1502514D03*
X341527Y1516307D03*
X332865Y1558813D03*
Y1563544D03*
X341527Y1563144D03*
X332865Y1578898D03*
X341527Y1567875D03*
Y1578498D03*
Y1572606D03*
X332865Y1568275D03*
Y1574167D03*
Y1583629D03*
Y1589522D03*
Y1594253D03*
X341527Y1583229D03*
Y1593853D03*
Y1587960D03*
X332865Y1598984D03*
X341527Y1609207D03*
Y1598584D03*
Y1603315D03*
X332865Y1609607D03*
Y1604876D03*
X341527Y1613938D03*
Y1618669D03*
X332865Y1614338D03*
X332000Y1644980D03*
X353536Y82984D03*
Y80384D03*
Y77784D03*
Y75184D03*
X356090Y92849D03*
X353536Y85584D03*
X353074Y95236D03*
Y102323D03*
X353326Y109410D03*
Y116496D03*
X353498Y124576D03*
X354551Y130670D03*
X359525Y137756D03*
X354546D03*
X359376Y290592D03*
X356423Y301288D03*
X348375Y322284D03*
X348351Y319372D03*
X348806Y315427D03*
X351132Y322202D03*
X348968Y333138D03*
X349120Y336100D03*
X348737Y375386D03*
X354486Y377173D03*
X351136Y372334D03*
X350486Y377173D03*
X358491D03*
X357173Y392183D03*
X347591Y391533D03*
X357218Y396866D03*
X361234Y402867D03*
X357655Y405889D03*
Y408489D03*
X358248Y403300D03*
X354155Y421489D03*
Y418889D03*
Y416289D03*
X350163Y412106D03*
X357655Y413689D03*
Y416289D03*
Y421489D03*
Y418889D03*
Y424089D03*
Y411089D03*
X358042Y442518D03*
Y439718D03*
Y432718D03*
X357655Y426689D03*
X358042Y435518D03*
X347450Y447486D03*
X358754Y450091D03*
X356241Y447001D03*
X359241D03*
X353670Y473571D03*
Y488618D03*
Y491118D03*
Y481071D03*
Y478571D03*
Y476071D03*
X360242Y477053D03*
X357742D03*
X353670Y493618D03*
X359278Y491870D03*
X356778D03*
X353670Y496118D03*
X358096Y867459D03*
X358086Y884616D03*
X357962Y898800D03*
X358024Y912085D03*
X358085Y923327D03*
X355929Y1132042D03*
X351563Y1132410D03*
X346366Y1134729D03*
X361621D03*
X349748D03*
X357748D03*
X353748D03*
X349700Y1148000D03*
X357947Y1159455D03*
X352536Y1160168D03*
X357057Y1179542D03*
X357796Y1188058D03*
X357297Y1192709D03*
X358368Y1201043D03*
X354398D03*
X350402D03*
X346387Y1199256D03*
X360523Y1192282D03*
X349276Y1217228D03*
X351940Y1219895D03*
X355215Y1223170D03*
X360273Y1228226D03*
X358062Y1226016D03*
X350188Y1491891D03*
Y1487160D03*
Y1496622D03*
Y1507246D03*
Y1502515D03*
Y1511977D03*
X358850Y1511576D03*
Y1506845D03*
Y1516307D03*
X350188Y1563544D03*
Y1558813D03*
Y1568275D03*
Y1578898D03*
Y1574167D03*
Y1583629D03*
Y1594253D03*
Y1589522D03*
Y1604876D03*
Y1609607D03*
Y1598984D03*
Y1614338D03*
X352000Y1644980D03*
X362725Y53597D03*
X371871Y85193D03*
Y82593D03*
Y79993D03*
Y77393D03*
Y74793D03*
X376467Y94017D03*
X363007Y95236D03*
X363050Y103037D03*
X363184Y116496D03*
Y109410D03*
X371184Y116496D03*
Y109410D03*
Y102323D03*
X373942Y104249D03*
Y107649D03*
X363184Y130670D03*
Y123583D03*
X371184Y130670D03*
Y123583D03*
Y137756D03*
X370964Y162368D03*
X373564D03*
X372275Y208213D03*
X376347Y208695D03*
Y211695D03*
X372275Y210713D03*
Y213213D03*
X361819Y207978D03*
Y212978D03*
Y215478D03*
Y210478D03*
X372275Y226461D03*
X375982Y226141D03*
X361819Y231226D03*
Y228726D03*
Y223726D03*
Y226226D03*
X372275Y228961D03*
Y231461D03*
Y215713D03*
X376225Y236611D03*
X375927Y248891D03*
X367648Y264180D03*
X365148D03*
X365073Y258880D03*
X374042Y270026D03*
X376842D03*
X374042Y267526D03*
X376842D03*
X365365Y293796D03*
X367865D03*
X373379Y288190D03*
X375879Y285690D03*
X373379D03*
X375879Y288190D03*
X368057Y354184D03*
X371417Y353820D03*
X365559Y354300D03*
X364933Y374232D03*
X373264Y370010D03*
X377237Y371060D03*
X366526Y377173D03*
X370486D03*
X361767Y392228D03*
X362486Y385123D03*
X376992Y395248D03*
X364551Y409032D03*
X361811Y396866D03*
X368587Y401066D03*
X367919Y439318D03*
X375919Y442118D03*
Y439318D03*
X367919Y442118D03*
X375919Y449118D03*
Y446318D03*
X364954Y450091D03*
X367919Y449118D03*
Y446318D03*
X376099Y458309D03*
Y454309D03*
X367564Y452740D03*
X361754Y450091D03*
X376099Y462309D03*
X369282Y468088D03*
Y465288D03*
X366443Y472189D03*
X373546Y470001D03*
X376046D03*
X361754Y462060D03*
X365332Y490070D03*
Y487570D03*
X373971Y489036D03*
X371832Y485580D03*
X374332D03*
X376832D03*
X366420Y479986D03*
Y477486D03*
X363686Y478668D03*
Y476168D03*
X361887Y493758D03*
Y496258D03*
X376207Y492836D03*
Y495636D03*
X373504Y517954D03*
X376881Y518564D03*
X363015Y710365D03*
X365887Y710329D03*
X372400Y746300D03*
X372300Y750000D03*
X373500Y767300D03*
X376300D03*
X370415Y766108D03*
X377020Y782535D03*
X373101Y779608D03*
X376300Y779800D03*
X365850Y773950D03*
X371436Y791188D03*
X368491Y815092D03*
X362042Y814772D03*
X368273Y928100D03*
X368067Y925136D03*
X375040Y932959D03*
X371424Y937185D03*
X367944Y946082D03*
X368626Y931346D03*
X368964Y937738D03*
X372858Y935136D03*
X366761Y934550D03*
X370214Y959812D03*
X363893Y946863D03*
X370214Y947812D03*
X370101Y953699D03*
X370214Y967812D03*
Y963812D03*
Y971812D03*
X372501Y1123695D03*
X365748Y1134325D03*
X368657Y1146937D03*
Y1150087D03*
X366133Y1162817D03*
Y1170767D03*
X368661Y1182649D03*
X368917Y1195419D03*
X362402Y1201039D03*
X366402Y1200969D03*
X365029Y1214158D03*
X362735Y1211864D03*
X369839Y1218940D03*
X366521Y1208993D03*
X367816Y1310586D03*
Y1315542D03*
X370202Y1314764D03*
Y1311364D03*
X372000Y1644980D03*
X388059Y3000D03*
X381518Y5374D03*
X388487Y24069D03*
X380831Y24773D03*
X383612Y30618D03*
Y33768D03*
X388612Y31168D03*
X380831Y44773D03*
X393544Y76140D03*
Y84140D03*
Y80140D03*
X384467Y94017D03*
X388476D03*
X380467D03*
X380196Y101701D03*
Y98551D03*
X390997Y117557D03*
X385587Y115401D03*
X380595D03*
X385587Y110445D03*
X380595D03*
X387746Y103783D03*
X383746D03*
X390681Y106186D03*
X390997Y131731D03*
Y122513D03*
X385587Y129574D03*
X380595D03*
X385587Y124618D03*
X380595D03*
X390997Y136687D03*
X380664Y165393D03*
Y162793D03*
Y167993D03*
Y170493D03*
X382872Y181366D03*
X379661Y181426D03*
X385667Y181009D03*
X390842Y168697D03*
X382158Y191941D03*
X388658Y184619D03*
X391930Y191941D03*
X382486Y184012D03*
X379869Y184221D03*
X390638Y206760D03*
X393939Y206767D03*
X383905Y211359D03*
X387608Y213132D03*
X378847Y211695D03*
X383905Y213859D03*
X380244Y229286D03*
X383937Y222212D03*
Y224712D03*
X394069Y221708D03*
X393484Y224421D03*
X387608Y215632D03*
X381225Y236611D03*
X378725D03*
X380244Y231786D03*
X378427Y248891D03*
X380927D03*
X391852Y256535D03*
X383852D03*
X387852Y256303D03*
X392882Y279208D03*
X379342Y270026D03*
Y267526D03*
X378679Y285690D03*
Y288190D03*
X386905Y290755D03*
X382905D03*
X392387Y337599D03*
Y342555D03*
X389237Y371070D03*
X385237Y370976D03*
X391737Y377581D03*
X391940Y383817D03*
Y388817D03*
Y386317D03*
X392444Y401949D03*
X385864Y398278D03*
X383364D03*
X378927Y409539D03*
X381927D03*
Y407039D03*
X381591Y401981D03*
X384091D03*
X378210Y424067D03*
X380710D03*
X385710D03*
X383210D03*
X378445Y413611D03*
X380945D03*
X385945D03*
X383445D03*
X385584Y438293D03*
Y441093D03*
Y450041D03*
Y452841D03*
Y455641D03*
Y443893D03*
X393837Y466409D03*
X393662Y470382D03*
X393823Y487382D03*
X393652Y482382D03*
X393746Y478382D03*
X387141Y484882D03*
X388593Y664232D03*
X386350Y693559D03*
X391478Y690675D03*
X391470Y732865D03*
X380963Y731000D03*
X379800Y778000D03*
Y769200D03*
X387692Y790056D03*
X393547D03*
X380607Y786932D03*
X387958Y813700D03*
X381631Y814147D03*
X384666Y814103D03*
X383391Y804000D03*
X386589Y864408D03*
X383462Y860535D03*
X386614Y868286D03*
X382675Y870151D03*
X391614Y938651D03*
Y930676D03*
X385512Y955356D03*
X390150Y955312D03*
Y959905D03*
X385467Y959950D03*
X378119Y953696D03*
X392910Y948536D03*
X393998Y971780D03*
X381377Y1003008D03*
X381045Y1009444D03*
X378790Y1001083D03*
X380280Y1006071D03*
X378410Y1131573D03*
X380261Y1129692D03*
X387587Y1296675D03*
X387644Y1302089D03*
X385091Y1297453D03*
Y1300853D03*
X391284Y1307238D03*
X386415Y1321645D03*
X391691Y1326715D03*
X389458Y1365466D03*
X389188Y1369033D03*
X391757Y1383480D03*
X388600Y1395500D03*
X391852Y1389931D03*
X389985Y1405762D03*
X393951Y1447455D03*
X394000Y1508100D03*
X381900Y1544800D03*
X389700Y1536900D03*
X382017Y1555700D03*
Y1547700D03*
Y1551700D03*
Y1559700D03*
X392000Y1644980D03*
X408059Y3000D03*
X408680Y37530D03*
X396680Y37543D03*
X400714Y45448D03*
X404686D03*
X408493Y117577D03*
X395989Y117557D03*
X398913Y103621D03*
X402104Y112083D03*
X406393Y103621D03*
X395989Y131731D03*
Y122513D03*
Y136687D03*
X399373Y180527D03*
X394690Y180572D03*
X403096Y192421D03*
X394690Y185165D03*
X399328Y185121D03*
X406725Y186629D03*
X395942Y192300D03*
X398939Y206767D03*
X396439D03*
X395184Y228221D03*
X399069Y221708D03*
X396569D03*
X403419Y221642D03*
X395184Y231021D03*
X410299Y219379D03*
X400735Y236189D03*
X398235D03*
X395735D03*
X400676Y248765D03*
X398176D03*
X395676D03*
X407333Y265897D03*
X404833D03*
X401173Y268195D03*
Y270695D03*
X398373Y268195D03*
X395873D03*
Y270695D03*
X398373D03*
X398976Y293645D03*
X401476D03*
Y288345D03*
Y290845D03*
X398976Y288345D03*
Y290845D03*
X409484Y314921D03*
X405843Y315158D03*
X403343D03*
X398951Y333711D03*
X397374Y344439D03*
X394883Y341777D03*
Y338377D03*
X400993Y331589D03*
Y335589D03*
X407493Y354142D03*
X400728Y353152D03*
X394237Y370899D03*
X406421Y387151D03*
Y382151D03*
Y384651D03*
X398453Y387702D03*
X401253D03*
X394653Y389402D03*
X396373Y409904D03*
X409268Y408240D03*
X406843Y399161D03*
Y401661D03*
Y396661D03*
X394944Y398949D03*
X399518Y402642D03*
X402018D03*
X396633Y423944D03*
X409386Y420393D03*
X396693Y413611D03*
X399193D03*
X401693D03*
X401633Y423944D03*
X399133D03*
X395577Y438293D03*
Y441093D03*
Y455641D03*
Y450041D03*
Y452841D03*
Y443893D03*
X397315Y471560D03*
Y479560D03*
Y475560D03*
X405603Y668060D03*
X408103D03*
X403103D03*
X400603D03*
Y678060D03*
X405603D03*
X408103D03*
X403103D03*
X409284Y741316D03*
X406200Y741300D03*
X400900Y755400D03*
X400914Y762675D03*
X408300Y755487D03*
X400900Y770100D03*
X407965Y770196D03*
X408400Y795200D03*
Y792200D03*
X406600Y789000D03*
X397223Y796792D03*
X400023D03*
X397900Y789000D03*
X407000Y784700D03*
X402376Y842677D03*
X399876D03*
X402376Y850677D03*
X399876D03*
X396306Y864409D03*
X406967Y878764D03*
X406415Y874840D03*
X407193Y883566D03*
X401121Y929686D03*
X409121D03*
X401121Y936686D03*
X409121Y939186D03*
X401121D03*
X409121Y936686D03*
X401121Y932186D03*
X409121D03*
X396182Y955858D03*
X402682Y948536D03*
X402815Y951750D03*
X404971Y956256D03*
X402354Y956465D03*
X401968Y959111D03*
X399173Y959468D03*
X404176Y977684D03*
Y975084D03*
Y969984D03*
Y972484D03*
X406954Y982970D03*
X409554D03*
X404354D03*
X407547Y1058097D03*
X410047D03*
X405047D03*
X407547Y1060697D03*
X410047D03*
X405047D03*
X399285Y1081599D03*
X408989Y1082501D03*
X409015Y1087705D03*
Y1085205D03*
X408847Y1090956D03*
X398915Y1097278D03*
X396415D03*
X408847Y1093956D03*
X406895Y1107997D03*
X402695D03*
X409231Y1123101D03*
X402695Y1110897D03*
X407780Y1113648D03*
X409231Y1118801D03*
X406995Y1110597D03*
X404895Y1112397D03*
X404795Y1109397D03*
X402695Y1113797D03*
X406105Y1139435D03*
X410131Y1129301D03*
X407631D03*
X409231Y1125801D03*
X406105Y1131935D03*
Y1134435D03*
Y1136935D03*
Y1141935D03*
Y1146935D03*
Y1144435D03*
X403263Y1152684D03*
X408961Y1162384D03*
Y1164884D03*
Y1167384D03*
Y1169884D03*
Y1172384D03*
X403263Y1160834D03*
X408961Y1174884D03*
X406319Y1186709D03*
Y1184209D03*
Y1181709D03*
Y1179209D03*
Y1204405D03*
X404004Y1198321D03*
Y1200821D03*
Y1192621D03*
Y1190121D03*
X406319Y1206905D03*
Y1211905D03*
Y1209405D03*
X397063Y1221428D03*
X401063D03*
X405063D03*
X409063D03*
X397063Y1233428D03*
Y1229428D03*
Y1225428D03*
X401063Y1237428D03*
Y1229428D03*
Y1225428D03*
X405063Y1237428D03*
Y1233428D03*
Y1229428D03*
X409063Y1237428D03*
Y1229428D03*
Y1225428D03*
X401063Y1241428D03*
X405063Y1245428D03*
Y1241428D03*
X409063Y1245428D03*
Y1241428D03*
X397695Y1287071D03*
X404324Y1275889D03*
X399716Y1295198D03*
X407767Y1292198D03*
X403678Y1295426D03*
X398584Y1313443D03*
X401011Y1307258D03*
X402967Y1319815D03*
X409220Y1315516D03*
X404583Y1316131D03*
X404921Y1321819D03*
X408787Y1321795D03*
X408937Y1351568D03*
X395959Y1352153D03*
X403981Y1351568D03*
X399959Y1352153D03*
X408159Y1349072D03*
X404759D03*
X403029Y1379716D03*
X403111Y1384920D03*
X408212Y1379695D03*
X394657Y1377875D03*
X403111Y1390103D03*
X408212Y1390083D03*
X395112Y1395690D03*
X398340Y1399779D03*
X395770Y1389817D03*
X410152Y1410928D03*
X398112Y1403741D03*
X410172Y1402446D03*
X402489Y1417275D03*
X405889D03*
X401711Y1419771D03*
X406667D03*
X401990Y1446807D03*
X399731Y1442755D03*
X407970Y1449751D03*
X404500Y1452500D03*
X395888Y1450022D03*
X395199Y1482223D03*
X407469Y1495035D03*
X407854Y1492118D03*
X395380Y1485778D03*
X406377Y1499142D03*
X397245Y1511640D03*
X404053Y1513673D03*
X397266Y1514647D03*
X398747Y1500959D03*
X395370Y1501022D03*
X397220Y1521207D03*
X397266Y1518047D03*
X408964Y1531149D03*
X400911Y1537902D03*
X407048D03*
X400911Y1544424D03*
X394391Y1537786D03*
Y1535286D03*
X407048Y1549936D03*
X400911D03*
X409461Y1569560D03*
X405461D03*
X397461D03*
X401461D03*
X420050Y33425D03*
X416900Y33400D03*
X422473Y22627D03*
X422378Y26534D03*
X426147Y147540D03*
Y151540D03*
X414626Y180665D03*
Y172665D03*
Y176665D03*
Y168665D03*
Y196665D03*
Y192665D03*
X414658Y212864D03*
Y200864D03*
Y204864D03*
Y216864D03*
Y221864D03*
X422873Y309966D03*
X419955Y306966D03*
X414999D03*
X423651Y307470D03*
X419177Y304470D03*
X415777D03*
X411984Y314921D03*
X415129Y325181D03*
X421231Y338523D03*
Y331255D03*
X412671Y333418D03*
X412812Y330617D03*
X421231Y345776D03*
X413432Y346797D03*
X426138Y355079D03*
X416318Y367903D03*
X424479Y367859D03*
X412318Y367903D03*
X420422Y367859D03*
X418997Y382210D03*
Y384710D03*
Y387210D03*
X418876Y401661D03*
Y396661D03*
X411768Y408240D03*
X414268D03*
X418876Y399161D03*
X411847Y424240D03*
X414386Y420393D03*
X411886D03*
X422215Y424939D03*
X411847Y426740D03*
X422215Y427439D03*
X414924Y435321D03*
Y438121D03*
X412124Y435321D03*
Y438121D03*
X414924Y440921D03*
X412124D03*
X415453Y455039D03*
X414924Y443721D03*
X412124D03*
X418754Y468607D03*
X411754Y474513D03*
X415433Y459170D03*
X425673Y461607D03*
X424876Y471334D03*
X414275Y492469D03*
X424731Y492704D03*
X414275Y497469D03*
Y499969D03*
X424731Y497704D03*
Y495204D03*
Y500204D03*
X414275Y494969D03*
X424731Y513452D03*
Y515952D03*
X414275Y508217D03*
Y510717D03*
Y515717D03*
Y513217D03*
X424731Y510952D03*
X419040Y533690D03*
Y528390D03*
Y530990D03*
Y536290D03*
Y538890D03*
X419340Y549990D03*
X419140Y547390D03*
Y544790D03*
X419340Y552590D03*
Y555190D03*
X423266Y631438D03*
X420266D03*
X417666D03*
X420266Y637038D03*
Y634238D03*
X417666Y637038D03*
Y634238D03*
X423266Y637038D03*
Y634238D03*
X423963Y625778D03*
X418226Y653288D03*
X423266Y642638D03*
X420266D03*
X417666D03*
X423266Y639838D03*
X420266D03*
X418226Y646480D03*
Y648980D03*
X417666Y639838D03*
X418226Y655788D03*
X410603Y668060D03*
Y678060D03*
X426607Y712360D03*
Y709760D03*
X415700Y755400D03*
X415696Y762466D03*
X415700Y770200D03*
X423700Y795500D03*
X426300Y797400D03*
X421200Y786400D03*
X411267Y829193D03*
Y831693D03*
X416267D03*
X413767D03*
Y829193D03*
X416267D03*
X424649Y842644D03*
X422149D03*
Y850644D03*
X424649D03*
X422149Y858644D03*
X424649D03*
X425759Y869921D03*
Y872721D03*
Y875521D03*
Y867121D03*
X422379Y867229D03*
X425759Y878321D03*
X411214Y892109D03*
X417121Y929686D03*
X425121D03*
Y936686D03*
Y939186D03*
X417121Y936686D03*
Y939186D03*
Y932186D03*
X425121D03*
X411960Y962261D03*
X414560D03*
X417160D03*
X411276Y978109D03*
X416476D03*
X413876D03*
X417677Y1052215D03*
X415047Y1058097D03*
X412547D03*
X415047Y1060697D03*
X412547D03*
X411989Y1082501D03*
X412015Y1085205D03*
X414989Y1082501D03*
X415015Y1085205D03*
Y1088205D03*
X412015D03*
X412297Y1091227D03*
X425175Y1098767D03*
X417171Y1098887D03*
X425060Y1101917D03*
X420782Y1105552D03*
X424995Y1106897D03*
X416988Y1104792D03*
X418495Y1106867D03*
X419731Y1123101D03*
X417231D03*
X414580Y1113648D03*
X412080D03*
X422631Y1125801D03*
X425131Y1129301D03*
X422631D03*
X420131D03*
X417631D03*
X415131D03*
X412631D03*
X420131Y1125801D03*
X417631D03*
X425131D03*
X422495Y1152713D03*
Y1155213D03*
X412095Y1152713D03*
Y1155213D03*
X411461Y1162384D03*
Y1164884D03*
Y1167384D03*
Y1169884D03*
Y1172384D03*
X420619Y1179421D03*
Y1181921D03*
Y1184421D03*
Y1186921D03*
X411461Y1174884D03*
X422934Y1200821D03*
Y1198321D03*
X420619Y1204617D03*
X417469Y1200821D03*
Y1198321D03*
X422934Y1192621D03*
Y1190121D03*
X417469Y1192621D03*
Y1190121D03*
X420619Y1207117D03*
Y1209617D03*
Y1212117D03*
X413063Y1221428D03*
X417063D03*
X421063D03*
X425063D03*
X413063Y1237428D03*
Y1233428D03*
Y1229428D03*
Y1225428D03*
X417063Y1237428D03*
Y1233428D03*
Y1229428D03*
X421063Y1237428D03*
Y1233428D03*
Y1229428D03*
Y1225428D03*
X425063Y1233428D03*
Y1229428D03*
Y1225428D03*
X413063Y1245428D03*
Y1241428D03*
X417063Y1245428D03*
Y1241428D03*
X421063Y1245428D03*
Y1241428D03*
X425063Y1245428D03*
Y1241428D03*
X425702Y1257160D03*
X422702Y1260160D03*
Y1257160D03*
X425702Y1260160D03*
X419702Y1257160D03*
Y1260160D03*
X411174Y1282776D03*
X418537Y1300197D03*
X423741Y1300115D03*
X413354Y1300197D03*
X425582Y1291743D03*
X413526Y1288938D03*
X419977Y1288843D03*
X413640Y1292856D03*
X423762Y1305298D03*
X413374D03*
X418558Y1310523D03*
X413395Y1310481D03*
X423721Y1310523D03*
X419545Y1317722D03*
X413127Y1318011D03*
X422665Y1325323D03*
X426665D03*
X414280Y1362561D03*
X425283Y1364023D03*
X417305Y1359169D03*
X425855Y1360495D03*
X425912Y1357141D03*
X413437Y1379736D03*
Y1384899D03*
X425283Y1373958D03*
X416029Y1371572D03*
X420636Y1383912D03*
X418610Y1371590D03*
X413395Y1390062D03*
X423400Y1394500D03*
X423200Y1397500D03*
X418430Y1394237D03*
X422729Y1400490D03*
X420925Y1390330D03*
X419045Y1398874D03*
X421300Y1415400D03*
X419100Y1402200D03*
X421200Y1417900D03*
X411000Y1463500D03*
Y1460500D03*
Y1457500D03*
Y1454500D03*
Y1451000D03*
X411147Y1474993D03*
X419818Y1474945D03*
X413934Y1477101D03*
X417334D03*
X415241Y1492990D03*
X415202Y1496118D03*
X415095Y1502750D03*
X415202Y1499518D03*
X411353Y1519440D03*
X419467Y1519706D03*
X420279Y1525978D03*
X410626Y1525991D03*
X417153Y1516886D03*
X413753D03*
X413012Y1537902D03*
Y1544098D03*
X426196Y1534087D03*
X419619Y1539978D03*
X413012Y1549936D03*
X421616Y1549885D03*
X418151Y1552470D03*
X413461Y1569560D03*
X417461Y1569584D03*
X412000Y1644980D03*
X428059Y3000D03*
X441727Y146461D03*
X429919Y141247D03*
X440629Y152367D03*
X435703Y306966D03*
X430747D03*
X427829Y309966D03*
X431525Y304470D03*
X434925D03*
X427051Y307470D03*
X441296Y325061D03*
X427713Y321965D03*
X430361Y323187D03*
X428459Y331255D03*
X435793D03*
X428500Y345776D03*
X435793Y345738D03*
X430439Y358115D03*
X428420Y353578D03*
X435886Y353867D03*
X435702Y367813D03*
X430746D03*
X431524Y370309D03*
X434924D03*
X428637Y408104D03*
X431437D03*
X434237D03*
X428354Y420375D03*
X431154D03*
X433954D03*
X433724Y433975D03*
X432310Y436164D03*
X427782Y464026D03*
X433673Y461607D03*
X429673D03*
X442704Y506427D03*
X427693Y506520D03*
X435789Y501525D03*
X427568Y502003D03*
X435831Y498923D03*
X438644Y500461D03*
X438353Y508685D03*
X427693Y509020D03*
X432700Y516277D03*
X435834Y509580D03*
X428740Y533690D03*
X442704Y533790D03*
X428740Y528390D03*
Y530990D03*
X442704Y528490D03*
Y531090D03*
X428740Y536290D03*
X431804Y536682D03*
X428740Y538890D03*
X431804Y539182D03*
X442704Y536390D03*
X439804Y536682D03*
X442704Y538990D03*
X439804Y539182D03*
X428740Y549990D03*
X442804Y546990D03*
Y544390D03*
X428740Y546990D03*
Y544390D03*
Y555190D03*
Y552590D03*
X431384D03*
Y555190D03*
Y544390D03*
Y546990D03*
Y549990D03*
X436369Y622883D03*
X441832Y626193D03*
X441612Y631011D03*
X439290Y712399D03*
X436790D03*
X439290Y709799D03*
X436790D03*
X434290Y712399D03*
Y709799D03*
X429290D03*
X431790Y712399D03*
X429290D03*
X431790Y709799D03*
X429253Y759847D03*
X429210Y784833D03*
X432303Y785067D03*
X434100Y797400D03*
X430600D03*
X428759Y869921D03*
Y867121D03*
Y872721D03*
Y875521D03*
Y878321D03*
X432332Y892049D03*
Y897649D03*
Y894849D03*
Y900449D03*
X432678Y1016186D03*
X429878D03*
X427078D03*
X427052Y1019384D03*
X429852D03*
X432652D03*
X433206Y1055498D03*
X430706D03*
Y1057998D03*
X433206D03*
Y1060498D03*
Y1062998D03*
X430706D03*
Y1060498D03*
X433378Y1091816D03*
Y1089316D03*
X430878Y1084316D03*
Y1086816D03*
X433378D03*
Y1084316D03*
X436244Y1090288D03*
X433378Y1081816D03*
X430878D03*
X429677Y1106955D03*
X439023Y1107997D03*
X436244Y1093088D03*
X434823Y1107997D03*
X441359Y1123101D03*
X431476Y1115896D03*
X427810Y1110092D03*
X439908Y1113648D03*
X441359Y1116101D03*
Y1118801D03*
X439123Y1110597D03*
X434823Y1113797D03*
Y1110897D03*
X437023Y1112397D03*
X436923Y1109397D03*
X431476Y1118396D03*
X438233Y1139435D03*
X441359Y1125801D03*
X439759Y1129301D03*
X442259D03*
X429331Y1136935D03*
Y1134435D03*
Y1139435D03*
Y1131935D03*
X435733D03*
Y1134435D03*
Y1136935D03*
Y1139435D03*
X438233Y1131935D03*
Y1134435D03*
Y1136935D03*
X429348Y1129092D03*
X432838Y1128821D03*
X429331Y1141935D03*
X435733D03*
Y1146935D03*
Y1144435D03*
X438233Y1141935D03*
Y1146935D03*
Y1144435D03*
X437231Y1154902D03*
Y1152402D03*
X429331Y1146935D03*
Y1144435D03*
X436789Y1167384D03*
Y1164884D03*
Y1162384D03*
Y1172384D03*
Y1169884D03*
X439289Y1167384D03*
Y1164884D03*
Y1162384D03*
X427231D03*
X429731D03*
Y1164884D03*
Y1167384D03*
Y1169884D03*
Y1172384D03*
X427231D03*
Y1169884D03*
Y1167384D03*
Y1164884D03*
X439289Y1172384D03*
Y1169884D03*
X437132Y1158266D03*
X433249Y1186709D03*
Y1184209D03*
Y1181709D03*
Y1179209D03*
X429731Y1174884D03*
X427231D03*
X436789D03*
X439289D03*
X433249Y1204405D03*
X430934Y1200821D03*
Y1198321D03*
Y1190121D03*
Y1192621D03*
X433249Y1209405D03*
Y1211905D03*
Y1206905D03*
X429063Y1221428D03*
X433063D03*
X429063Y1237428D03*
Y1233428D03*
Y1229428D03*
X433063Y1237428D03*
Y1233428D03*
Y1229428D03*
Y1225428D03*
X429063Y1245428D03*
Y1241428D03*
X433063Y1245428D03*
Y1241428D03*
X440702Y1260160D03*
Y1257160D03*
X437702Y1260160D03*
Y1257160D03*
X428702D03*
X431702Y1260160D03*
Y1257160D03*
X434702Y1260160D03*
Y1257160D03*
X428702Y1260160D03*
X431114Y1272701D03*
X437991Y1286544D03*
X434424Y1286274D03*
X430527Y1289198D03*
X440906D03*
X440896Y1311366D03*
X431867Y1315696D03*
X431885Y1313115D03*
X432485Y1325784D03*
X439434Y1322369D03*
X429530Y1325051D03*
X436002Y1382252D03*
X437675Y1550158D03*
X430657Y1563562D03*
X429784Y1548222D03*
X432000Y1644980D03*
X448059Y3000D03*
X445949Y141247D03*
X452686Y152562D03*
X458181Y157370D03*
X458454Y328963D03*
Y324007D03*
Y339755D03*
Y344711D03*
X443508Y337713D03*
X443480Y344014D03*
X453463Y370694D03*
X448092Y375770D03*
X455885Y367702D03*
X448391Y382641D03*
X448323Y379643D03*
X446179Y447101D03*
X453544Y461961D03*
X451144Y472809D03*
Y468809D03*
X443094Y491251D03*
X450942Y506449D03*
X448442D03*
X445942D03*
X446025Y511512D03*
X448525D03*
X446025Y519699D03*
X448525D03*
X452404Y533690D03*
Y528390D03*
Y530990D03*
X455104Y536582D03*
X452404Y536290D03*
X455104Y539082D03*
X452404Y538890D03*
Y549790D03*
X443004Y549890D03*
X452404Y546990D03*
Y544390D03*
X443004Y555090D03*
X452404Y552390D03*
Y554990D03*
X443004Y552490D03*
X455009Y554912D03*
Y552312D03*
Y544312D03*
Y546912D03*
Y549712D03*
X447279Y633881D03*
X448726Y653288D03*
Y646480D03*
Y648980D03*
X446987Y643360D03*
X456469Y638302D03*
X448726Y655788D03*
X447836Y711199D03*
X454815Y974622D03*
X458120Y974701D03*
X451460Y974695D03*
X448999Y994483D03*
X456210Y1004680D03*
X452319Y1000828D03*
X449731Y1000855D03*
X450591Y1004766D03*
X453270Y1003763D03*
X453710Y1018825D03*
X443091Y1022766D03*
X443591Y1019766D03*
X447091D03*
X443091Y1030266D03*
X450063Y1043140D03*
X443091Y1034266D03*
X449767Y1047047D03*
X450244Y1090268D03*
X457303Y1098767D03*
X446863Y1098428D03*
X450244Y1093068D03*
X457188Y1101917D03*
X452910Y1105552D03*
X457123Y1106897D03*
X449116Y1104792D03*
X450623Y1106867D03*
X449359Y1123101D03*
X451859D03*
X444208Y1113648D03*
X446708D03*
X457259Y1129301D03*
X449759Y1125801D03*
X452259D03*
X444759Y1129301D03*
X447259D03*
X449759D03*
X452259D03*
X454759Y1125801D03*
X457259D03*
X454759Y1129301D03*
X443223Y1155213D03*
Y1152713D03*
X452623D03*
Y1155213D03*
X457559Y1169884D03*
Y1167384D03*
Y1164884D03*
Y1162384D03*
X455059D03*
Y1164884D03*
Y1167384D03*
Y1169884D03*
Y1172384D03*
X457559D03*
X455059Y1174884D03*
X457559D03*
X447549Y1179421D03*
Y1181921D03*
Y1184421D03*
Y1186921D03*
Y1204617D03*
X449864Y1198321D03*
Y1200821D03*
Y1190121D03*
Y1192621D03*
X447549Y1209617D03*
Y1207117D03*
Y1212117D03*
X454120Y1269498D03*
X449702Y1260160D03*
Y1257160D03*
X443702Y1260160D03*
X446702D03*
Y1257160D03*
X443702D03*
X456213Y1286776D03*
X451889Y1301067D03*
X451304Y1293045D03*
X456832Y1299121D03*
X451304Y1297045D03*
X454385Y1301845D03*
X451889Y1306023D03*
X454385Y1305245D03*
X444288Y1314391D03*
X454125Y1471805D03*
Y1487159D03*
Y1502514D03*
Y1558813D03*
Y1574167D03*
Y1589522D03*
Y1604876D03*
X452000Y1644980D03*
X468059Y3000D03*
X464738Y110784D03*
X462089Y113394D03*
X470307Y102249D03*
X466307D03*
X462089Y116594D03*
X472332Y133298D03*
X464332D03*
X462089Y119594D03*
X474058D03*
X466479Y134579D03*
X460930Y161306D03*
X470107Y195176D03*
X467607D03*
X472607D03*
X472226Y198883D03*
X473655Y206838D03*
X467467Y203393D03*
X469967D03*
X467346Y218085D03*
X470146D03*
X473946Y216385D03*
X464054Y252371D03*
Y248371D03*
X460950Y328185D03*
Y324785D03*
X461454Y336837D03*
Y331881D03*
X463950Y332659D03*
Y336059D03*
X460950Y343933D03*
Y340533D03*
X461454Y347629D03*
Y352585D03*
X472810Y347995D03*
X472913Y360089D03*
X472608Y352495D03*
X463950Y351807D03*
Y348407D03*
X466375Y366365D03*
X472913Y369089D03*
Y373589D03*
X470389Y389553D03*
X472913Y387089D03*
Y391589D03*
Y382589D03*
Y378089D03*
X470796Y394592D03*
X473658Y467215D03*
X471048Y464566D03*
X464848D03*
X467848D03*
X465126Y460435D03*
X462126D03*
X467848Y476535D03*
X464848D03*
X468558Y503669D03*
Y507669D03*
Y495669D03*
Y499669D03*
Y512669D03*
Y516609D03*
X464199Y510184D03*
X463104Y536582D03*
X468850Y537507D03*
X463104Y539082D03*
X461849Y668016D03*
X459349D03*
X466849D03*
X469349D03*
X464349D03*
X469349Y678016D03*
X466849D03*
X459349D03*
X461849D03*
X464349D03*
X469300Y799500D03*
X462242Y809792D03*
X459245Y807152D03*
X473654Y821234D03*
X475032Y843252D03*
X472399Y839566D03*
X463404Y846870D03*
X474678Y857919D03*
X463134Y859203D03*
X465492Y861970D03*
X460455Y867050D03*
X475046Y885952D03*
X471726Y883705D03*
X467494Y924532D03*
X471110Y921577D03*
X471876Y937236D03*
X471068Y930235D03*
X473992Y952546D03*
X469495Y1011303D03*
X459360Y1004680D03*
X464795Y1000647D03*
X469495Y1023303D03*
Y1017303D03*
X462185Y1016825D03*
X459860Y1015825D03*
X462427Y1030218D03*
X471558Y1029482D03*
X473639Y1030952D03*
X459700Y1035716D03*
X460277Y1090268D03*
X474348Y1090171D03*
X460277Y1093068D03*
X462913Y1106365D03*
X474277Y1093048D03*
X472482Y1107997D03*
X468282D03*
X474818Y1123101D03*
X459938Y1110092D03*
X463604Y1115896D03*
X473367Y1113648D03*
X474818Y1116101D03*
Y1118801D03*
X472582Y1110597D03*
X470482Y1112397D03*
X468282Y1110897D03*
Y1113797D03*
X470382Y1109397D03*
X463604Y1118396D03*
X469192Y1131935D03*
X474818Y1125801D03*
X473218Y1129301D03*
X461459Y1136935D03*
Y1134435D03*
Y1139435D03*
Y1131935D03*
X471692Y1139435D03*
Y1136935D03*
Y1134435D03*
Y1131935D03*
X469192Y1139435D03*
Y1136935D03*
Y1134435D03*
X471692Y1146935D03*
Y1141935D03*
X469192Y1144435D03*
Y1146935D03*
Y1141935D03*
X471692Y1144435D03*
X461459D03*
X462687Y1152684D03*
X468850D03*
X461459Y1141935D03*
Y1146935D03*
X462687Y1160834D03*
X474548Y1172384D03*
Y1169884D03*
Y1167384D03*
Y1164884D03*
Y1162384D03*
X468850Y1160834D03*
X474548Y1174884D03*
X465785Y1197471D03*
X461285Y1193471D03*
Y1197471D03*
X465785Y1193471D03*
X463216Y1254164D03*
Y1250760D03*
Y1244055D03*
X474647Y1260160D03*
Y1257160D03*
X471647D03*
Y1260160D03*
X461613Y1286776D03*
X459290Y1297035D03*
X462786Y1460782D03*
X471448Y1471805D03*
X462786Y1476136D03*
Y1491490D03*
X471448Y1487159D03*
Y1502514D03*
X462786Y1506845D03*
Y1563144D03*
X471448Y1558813D03*
X462786Y1578498D03*
X471448Y1574167D03*
X462786Y1593853D03*
X471448Y1589522D03*
X462786Y1609207D03*
X471448Y1604876D03*
X472000Y1644980D03*
X484043Y4469D03*
X485404Y24773D03*
Y44773D03*
X487925Y95111D03*
X480324Y109172D03*
X477324D03*
X479331Y106495D03*
X483075Y116497D03*
X487875D03*
X490375Y109410D03*
Y116497D03*
X479331Y102495D03*
X483075Y130670D03*
X487875Y123584D03*
Y130670D03*
X490375Y123583D03*
Y130670D03*
X483075Y123584D03*
X479065Y146012D03*
X480971Y141228D03*
X483075Y137757D03*
X487875D03*
X479065Y142862D03*
X483859Y150847D03*
X487654Y195176D03*
X485154D03*
X482654D03*
X486672Y199248D03*
X490154Y195176D03*
X476155Y206838D03*
X491607Y213539D03*
X485235Y210509D03*
X482735D03*
X489672Y202048D03*
X486672Y201748D03*
X484508Y206806D03*
X487008D03*
X476659Y216970D03*
Y219470D03*
X476725Y226320D03*
X476659Y221970D03*
X485827Y247292D03*
X478617Y236121D03*
X475651Y238589D03*
X485053Y238689D03*
X483412Y242078D03*
X478643Y232971D03*
X488769Y246874D03*
X489288Y238714D03*
X478536Y253198D03*
X483242Y366481D03*
X483584Y375840D03*
X483736Y371266D03*
X481724Y373589D03*
Y369089D03*
X483541Y380306D03*
X481724Y391589D03*
Y387089D03*
Y382589D03*
Y378089D03*
X488438Y425464D03*
X482532Y418464D03*
X490985Y412342D03*
X485485Y439903D03*
X489485D03*
X482484Y444517D03*
X482193Y472784D03*
Y468784D03*
Y476784D03*
X482905Y531726D03*
X482737Y537215D03*
X482836Y534249D03*
X482905Y527726D03*
Y552726D03*
Y540726D03*
Y548726D03*
X486738Y581222D03*
X489538D03*
Y591215D03*
X486738D03*
X491340Y611091D03*
X487209Y611071D03*
X484772Y621311D03*
Y629311D03*
Y625311D03*
X481165Y646036D03*
X485005Y659771D03*
X491324Y667293D03*
X488765Y667224D03*
X485303Y681841D03*
X484341Y700528D03*
X486837Y701306D03*
X484341Y705484D03*
X486837Y704706D03*
X489406Y797558D03*
X486246Y804497D03*
X485824Y819787D03*
X481593Y826387D03*
X489572Y822805D03*
X479448Y828594D03*
X491453Y834546D03*
X491527Y843206D03*
X479700Y847600D03*
X488469Y857013D03*
X477574Y860815D03*
X481943Y924633D03*
X488388Y938903D03*
X483636Y952152D03*
X476475Y952249D03*
X489163Y977163D03*
X490143Y989521D03*
X487091Y989550D03*
X481495Y1011303D03*
X475495D03*
X481495Y1023303D03*
Y1017303D03*
X475495Y1023303D03*
X488041Y1020440D03*
X485678Y1039880D03*
X476148Y1057998D03*
Y1055498D03*
X478648D03*
Y1057998D03*
X476148Y1060498D03*
Y1062998D03*
X478648D03*
Y1060498D03*
X477607Y1089942D03*
X491503Y1086796D03*
Y1084296D03*
X478517Y1086724D03*
Y1084224D03*
Y1081724D03*
X476017D03*
Y1084224D03*
Y1086724D03*
X490762Y1098767D03*
X480322Y1098428D03*
X486369Y1105552D03*
X490647Y1101917D03*
X490582Y1106897D03*
X482575Y1104792D03*
X484082Y1106867D03*
X485318Y1123101D03*
X482818D03*
X480167Y1113648D03*
X477667D03*
X490718Y1129301D03*
X483218Y1125801D03*
X485718D03*
X475718Y1129301D03*
X478218D03*
X480718D03*
X483218D03*
X485718D03*
X488218Y1125801D03*
X490718D03*
X488218Y1129301D03*
X477682Y1152713D03*
Y1155213D03*
X488082D03*
Y1152713D03*
X477048Y1172384D03*
Y1169884D03*
Y1167384D03*
Y1164884D03*
Y1162384D03*
X479521Y1179209D03*
Y1181709D03*
Y1184209D03*
Y1186709D03*
X477048Y1174884D03*
X477206Y1198321D03*
X490671D03*
Y1200821D03*
X479521Y1204405D03*
X477206Y1200821D03*
X490671Y1192621D03*
Y1190121D03*
X477206Y1192621D03*
Y1190121D03*
X479521Y1206905D03*
Y1211905D03*
Y1209405D03*
X489647Y1260160D03*
Y1257160D03*
X486647D03*
Y1260160D03*
X480647Y1257160D03*
X477647D03*
Y1260160D03*
X480647D03*
X483647Y1257160D03*
Y1260160D03*
X484800Y1302000D03*
X490100Y1302100D03*
X487600D03*
X480109Y1460782D03*
Y1476136D03*
X488771Y1471805D03*
Y1487159D03*
X480109Y1491490D03*
Y1506845D03*
X488771Y1502514D03*
Y1558813D03*
X480109Y1563144D03*
Y1578498D03*
X488771Y1574167D03*
Y1589522D03*
X480109Y1593853D03*
X488771Y1604876D03*
X480109Y1609207D03*
X492725Y53597D03*
X503537Y77784D03*
Y75184D03*
Y80384D03*
Y82984D03*
X506091Y92849D03*
X503537Y85584D03*
X503075Y95236D03*
Y102323D03*
X503327Y109410D03*
Y116496D03*
X495075D03*
Y102323D03*
Y109410D03*
X492294Y106561D03*
X495075Y130670D03*
Y123583D03*
X506653Y121652D03*
X504552Y130670D03*
X504547Y137756D03*
X495075D03*
X493288Y238714D03*
X497424Y354559D03*
X492317Y376252D03*
X493485Y439903D03*
X503729Y439919D03*
X503682Y455466D03*
X497776Y448466D03*
X500729Y469905D03*
X496729Y470419D03*
X492736Y487982D03*
Y483982D03*
X505476Y485128D03*
X497095Y481467D03*
X492736Y499982D03*
X501887Y504825D03*
X499387D03*
X496887D03*
X492736Y495982D03*
X501828Y517401D03*
X499328D03*
X496828D03*
X502379Y522569D03*
X495444Y531948D03*
X503494Y531882D03*
X502379Y525369D03*
X500994Y531882D03*
X498494D03*
X504079Y529169D03*
X493929Y555194D03*
X496729D03*
X503729D03*
X500929D03*
X493929Y563194D03*
X496729D03*
X493929Y571194D03*
X496729D03*
X500929D03*
X503729D03*
Y563194D03*
X500929D03*
X492338Y581222D03*
X505286D03*
X502486D03*
X492338Y591215D03*
X505286D03*
X502486D03*
X505458Y610562D03*
X502658D03*
Y607762D03*
X505458D03*
X493778Y641817D03*
X494632Y654622D03*
X494465Y657772D03*
X502755Y657694D03*
X496070Y665976D03*
X504966Y678098D03*
X498284Y681453D03*
Y678953D03*
X501618Y698355D03*
X499012Y699819D03*
X503311Y715652D03*
X500705Y705524D03*
X500714Y708755D03*
X502832Y720491D03*
X507546Y738539D03*
X505673Y767961D03*
X500717D03*
X504895Y770457D03*
X501495D03*
X506166Y793224D03*
X504341Y812040D03*
X491655Y829173D03*
X506246Y824689D03*
X494677Y830468D03*
X492799Y846488D03*
X503741Y846830D03*
X497467Y833027D03*
X495073Y835586D03*
X495470Y844271D03*
X499640Y861538D03*
X495700Y849389D03*
X494315Y941212D03*
X503144Y957934D03*
X499595Y963963D03*
X493050Y976078D03*
X504088Y985171D03*
X506888D03*
X506702Y978947D03*
X493091Y989550D03*
X503933Y981392D03*
X506566Y1000766D03*
Y1004766D03*
Y1008766D03*
Y996766D03*
Y1016266D03*
Y1012266D03*
Y1030766D03*
X505981Y1052487D03*
X503177Y1058097D03*
X495677D03*
X493177D03*
X498177D03*
X500677D03*
X503177Y1060697D03*
X495677D03*
X493177D03*
X498177D03*
X500677D03*
X494003Y1086796D03*
X496503D03*
X499003D03*
X501503D03*
Y1084296D03*
X499003D03*
X496503D03*
X494003D03*
X501831Y1090288D03*
X496372Y1106298D03*
X504610Y1107997D03*
X501831Y1093088D03*
X500410Y1107997D03*
X506946Y1123101D03*
X497063Y1115896D03*
X505495Y1113648D03*
X506946Y1116101D03*
Y1118801D03*
X504710Y1110597D03*
X500410Y1113797D03*
X502610Y1112397D03*
X500410Y1110897D03*
X502510Y1109397D03*
X493397Y1110092D03*
X497063Y1118396D03*
X506946Y1125801D03*
X505346Y1129301D03*
X507846D03*
X503820Y1139435D03*
Y1136935D03*
Y1134435D03*
Y1131935D03*
X501320Y1139435D03*
Y1136935D03*
Y1134435D03*
Y1131935D03*
X494918Y1136935D03*
Y1134435D03*
Y1139435D03*
Y1131935D03*
X498727Y1128759D03*
X495236Y1129094D03*
X503820Y1144435D03*
Y1146935D03*
Y1141935D03*
X501320Y1144435D03*
Y1146935D03*
Y1141935D03*
X494918Y1146935D03*
Y1144435D03*
Y1141935D03*
X502562Y1152713D03*
Y1155213D03*
X502376Y1172384D03*
Y1169884D03*
Y1167384D03*
Y1164884D03*
Y1162384D03*
X504876Y1172384D03*
Y1169884D03*
Y1167384D03*
Y1164884D03*
Y1162384D03*
X492818D03*
Y1164884D03*
Y1167384D03*
Y1169884D03*
Y1172384D03*
X495318D03*
Y1169884D03*
Y1167384D03*
Y1164884D03*
Y1162384D03*
X502562Y1158200D03*
X506451Y1179209D03*
Y1181709D03*
Y1184209D03*
Y1186709D03*
X504876Y1174884D03*
X493821Y1186921D03*
Y1184421D03*
Y1181921D03*
Y1179421D03*
X492818Y1174884D03*
X495318D03*
X502376D03*
X506451Y1204405D03*
X504136Y1198321D03*
Y1200821D03*
X493821Y1204617D03*
X496136Y1200821D03*
Y1198321D03*
X504136Y1190121D03*
Y1192621D03*
X496136Y1190121D03*
Y1192621D03*
X506451Y1206905D03*
Y1211905D03*
Y1209405D03*
X493821Y1207117D03*
Y1209617D03*
Y1212117D03*
X506562Y1222194D03*
X502562D03*
X498562D03*
X494562D03*
X506562Y1226194D03*
Y1230194D03*
Y1234194D03*
X502562Y1226194D03*
Y1230194D03*
Y1234194D03*
Y1238194D03*
X498562Y1230194D03*
Y1234194D03*
Y1238194D03*
X494562Y1226194D03*
Y1230194D03*
Y1234194D03*
Y1238194D03*
Y1246194D03*
Y1242194D03*
X506562D03*
Y1246194D03*
X502562Y1242194D03*
Y1246194D03*
X498562D03*
X504647Y1257160D03*
X507347D03*
X501647D03*
Y1260160D03*
X495647D03*
X492647D03*
Y1257160D03*
X495647D03*
X498647D03*
Y1260160D03*
X507347D03*
X504647D03*
X497432Y1460782D03*
Y1476136D03*
X506093Y1471805D03*
X497432Y1491490D03*
X506093Y1487159D03*
X497432Y1506845D03*
X506093Y1502514D03*
X497432Y1563144D03*
X506093Y1558813D03*
X497432Y1578498D03*
X506093Y1574167D03*
Y1589522D03*
X497432Y1593853D03*
X506093Y1604876D03*
X497432Y1609207D03*
X492000Y1644980D03*
X512725Y53597D03*
X521872Y82593D03*
Y85193D03*
Y74793D03*
Y77393D03*
Y79993D03*
X513008Y95236D03*
X513051Y103037D03*
X513185Y116496D03*
Y109410D03*
X521185Y116496D03*
Y109410D03*
Y102323D03*
X523943Y107649D03*
Y104249D03*
X513185Y130670D03*
Y123583D03*
X521185Y130670D03*
Y123583D03*
X509251Y137756D03*
X521185D03*
X520965Y162368D03*
X523565D03*
X511820Y207978D03*
Y210478D03*
Y215478D03*
Y212978D03*
X522276Y208213D03*
Y213213D03*
Y210713D03*
Y226461D03*
Y228961D03*
Y231461D03*
X511820Y231226D03*
Y228726D03*
Y223726D03*
Y226226D03*
X522276Y215713D03*
X515149Y264180D03*
X517649D03*
X515074Y258880D03*
X524043Y270026D03*
Y267526D03*
X517866Y293796D03*
X515366D03*
X523380Y285690D03*
Y288190D03*
X511342Y311124D03*
X514769Y312953D03*
X511790Y313804D03*
X520845Y434508D03*
X516845D03*
X512845D03*
X514608Y445874D03*
X510022Y446352D03*
X523705Y444269D03*
X523583Y447201D03*
X511753Y454339D03*
Y456839D03*
X509253D03*
Y454339D03*
X508729Y469905D03*
X521310Y470045D03*
X513310D03*
X509253Y459339D03*
X511753D03*
X517310Y470045D03*
X523457Y482134D03*
Y484634D03*
X508325Y485138D03*
X512210Y478625D03*
X513910Y482425D03*
X513325Y485138D03*
X510825D03*
X519786Y491214D03*
X521636Y504699D03*
X516636D03*
X519136D03*
X516756Y500086D03*
X523489Y492987D03*
X519786Y493714D03*
X523489Y495487D03*
X517319Y521804D03*
X516338Y516979D03*
X521338D03*
X518838D03*
X513626Y531378D03*
X518781Y527449D03*
X517319Y524304D03*
X521581Y527449D03*
X509955Y537958D03*
X513658Y539731D03*
X518716Y541895D03*
X521216Y544895D03*
Y541895D03*
X513658Y542231D03*
X509955Y540458D03*
X521494Y572975D03*
Y582747D03*
X508086Y581222D03*
Y591215D03*
X519875Y608311D03*
X518940Y620653D03*
Y617853D03*
X511058Y610562D03*
Y607762D03*
X508258Y610562D03*
Y607762D03*
X520770Y605443D03*
X516770D03*
X512404Y629362D03*
X510215Y627948D03*
X523616Y625013D03*
X521778Y642184D03*
X518812Y665867D03*
X521868Y666577D03*
X518812Y662874D03*
X511990Y686365D03*
X510425Y683246D03*
X522200Y677613D03*
X521540Y686319D03*
X518001Y694940D03*
X522410Y694881D03*
X518067Y699378D03*
X513324Y693892D03*
X515357Y698253D03*
X511359Y698494D03*
X510654Y703806D03*
X518530Y703584D03*
X522628Y703884D03*
X523299Y709313D03*
X519072Y709183D03*
X512530Y718301D03*
X514531Y716398D03*
X508237Y723585D03*
X512502Y738539D03*
X516953Y738575D03*
X521909D03*
X521131Y741071D03*
X517731D03*
X511724Y741035D03*
X508324D03*
X520159Y758832D03*
X520549Y761982D03*
X509096Y753072D03*
X515422Y753455D03*
X509063Y782867D03*
X517194Y773232D03*
X520833Y773389D03*
X513551Y773203D03*
X522316Y793574D03*
X509316Y793224D03*
X508130Y787488D03*
X522697Y797102D03*
X521178Y814001D03*
X518157Y803973D03*
X518565Y811973D03*
X521565Y820931D03*
X522481Y824661D03*
X517702Y826600D03*
X520720Y846133D03*
X517832Y834558D03*
X514682Y834590D03*
X511741Y846649D03*
X508049Y877789D03*
X523272Y880067D03*
X509428Y888390D03*
X521115Y897500D03*
X509673Y900295D03*
X521572Y901500D03*
X516256Y939157D03*
X520146Y939241D03*
X523289Y939195D03*
X514886Y952189D03*
X521353Y952266D03*
X509471Y981608D03*
X514566Y1000766D03*
X514690Y996766D03*
Y1004766D03*
X514566Y1016266D03*
X514649Y1020266D03*
X519792Y1031271D03*
X514843Y1030766D03*
X519500Y1028377D03*
X515831Y1090568D03*
X517702Y1098518D03*
X512450Y1098428D03*
X515831Y1093068D03*
X522890Y1098767D03*
X518497Y1105552D03*
X522775Y1101917D03*
X514703Y1104792D03*
X522710Y1106897D03*
X516210Y1106867D03*
X514946Y1123101D03*
X517446D03*
X509795Y1113648D03*
X512295D03*
X522846Y1129301D03*
X515346Y1125801D03*
X517846D03*
X510346Y1129301D03*
X512846D03*
X515346D03*
X517846D03*
X520346Y1125801D03*
X522846D03*
X520346Y1129301D03*
X518210Y1155213D03*
Y1152713D03*
X508810D03*
Y1155213D03*
X520646Y1169884D03*
Y1167384D03*
Y1164884D03*
Y1162384D03*
X523146D03*
Y1164884D03*
Y1167384D03*
Y1169884D03*
Y1172384D03*
X520646D03*
X520751Y1186921D03*
Y1184421D03*
Y1181921D03*
Y1179421D03*
X523146Y1174884D03*
X520646D03*
X520751Y1204617D03*
X523066Y1200821D03*
Y1198321D03*
Y1190121D03*
Y1192621D03*
X520751Y1207117D03*
Y1209617D03*
Y1212117D03*
X522562Y1222194D03*
X518562D03*
X514562D03*
X510562D03*
X522562Y1226194D03*
X518562D03*
Y1230194D03*
Y1234194D03*
X514562Y1226194D03*
Y1234194D03*
Y1238194D03*
X510562Y1226194D03*
Y1230194D03*
Y1234194D03*
Y1238194D03*
X514562Y1242194D03*
Y1246194D03*
X510562Y1242194D03*
Y1246194D03*
X518576Y1273004D03*
X525712Y1272992D03*
X517374Y1287222D03*
X514363Y1287370D03*
X520548Y1287181D03*
X514755Y1460782D03*
Y1476136D03*
Y1491490D03*
Y1506845D03*
Y1563144D03*
Y1578498D03*
Y1593853D03*
Y1609207D03*
X512000Y1644980D03*
X531518Y5374D03*
X530831Y24773D03*
Y44773D03*
X526468Y94017D03*
X530197Y101701D03*
X534468Y94017D03*
X538477D03*
X530468D03*
X530197Y98551D03*
X530596Y115401D03*
X535588Y110445D03*
Y115401D03*
X530596Y110445D03*
X537747Y103783D03*
X533747D03*
X530596Y124618D03*
Y129574D03*
X535588Y124618D03*
Y129574D03*
X532281Y141247D03*
X528509Y147540D03*
Y151540D03*
X530665Y162793D03*
Y165393D03*
Y170493D03*
Y167993D03*
X535668Y181009D03*
X529662Y181426D03*
X532873Y181366D03*
X538659Y184619D03*
X532159Y191941D03*
X529870Y184221D03*
X532487Y184012D03*
X533906Y211359D03*
Y213859D03*
X528848Y211695D03*
X537609Y213132D03*
X526348Y208695D03*
Y211695D03*
X530245Y229286D03*
X525983Y226141D03*
X533938Y222212D03*
Y224712D03*
X537609Y215632D03*
X526226Y236611D03*
X531226D03*
X528726D03*
X530245Y231786D03*
X528428Y248891D03*
X530928D03*
X533853Y256535D03*
X525928Y248891D03*
X537853Y256303D03*
X526843Y270026D03*
X529343D03*
X526843Y267526D03*
X529343D03*
X525880Y285690D03*
X528680D03*
X525880Y288190D03*
X528680D03*
X532906Y290755D03*
X536906D03*
X524206Y354119D03*
X533027Y351836D03*
X530215Y364422D03*
X535142Y397552D03*
X531992D03*
X526216Y456652D03*
X528716D03*
X526216Y459152D03*
Y461652D03*
X528716Y459152D03*
Y461652D03*
X535119Y481086D03*
Y478586D03*
X526902Y478446D03*
Y475946D03*
X531412Y480705D03*
X535119Y476086D03*
X528612Y480705D03*
X535119Y491133D03*
X531047Y498151D03*
X535119Y493633D03*
Y496133D03*
Y498633D03*
X531047Y495151D03*
X528547D03*
X528247Y498151D03*
X532936Y519544D03*
X525288Y522129D03*
X527936Y519544D03*
X525436D03*
X530436D03*
X525288Y524629D03*
Y527129D03*
Y529929D03*
X529481Y532849D03*
X532281D03*
X525288Y537877D03*
X535219Y555897D03*
Y553297D03*
X533488Y548344D03*
X525288Y540377D03*
Y545377D03*
Y542877D03*
X528488Y548344D03*
X525988D03*
X530988D03*
X524708Y572842D03*
X535219Y561097D03*
Y563697D03*
Y558497D03*
X532009Y570478D03*
X529214Y570686D03*
X532863Y585507D03*
X528270D03*
X528816Y579475D03*
X529423Y573303D03*
X532069Y573689D03*
X532426Y576484D03*
X532908Y590190D03*
X528314Y590145D03*
X524770Y597232D03*
X532770Y605443D03*
X526756Y613913D03*
Y616713D03*
Y619513D03*
X538826Y614158D03*
Y616958D03*
Y619758D03*
X536770Y605443D03*
X538826Y633450D03*
X526756Y636005D03*
Y633205D03*
X538826Y636250D03*
Y639050D03*
X526756Y638805D03*
X524653Y643595D03*
X533486Y664052D03*
X538442D03*
X524941Y661387D03*
X530796D03*
X537664Y661556D03*
X534264D03*
X529664Y664056D03*
X526264D03*
X534940Y684489D03*
X539111Y681459D03*
X526956Y694959D03*
X526951Y699443D03*
X538316Y687357D03*
X535738Y687489D03*
X535387Y712617D03*
X526933Y703820D03*
X532628Y720776D03*
X526276Y721339D03*
X539763Y734097D03*
X534807D03*
X531763Y739097D03*
X526807D03*
X535585Y736593D03*
X538985D03*
X530985Y741593D03*
X527585D03*
X532450Y767474D03*
X532278Y762736D03*
X524598Y753387D03*
X532449Y782389D03*
X534672Y785037D03*
X531501Y792331D03*
X531260Y794934D03*
X531666Y815724D03*
X532304Y806649D03*
X531313Y812850D03*
Y822693D03*
Y826630D03*
X527733Y847026D03*
X536641Y838649D03*
X532316Y833649D03*
X534000Y843000D03*
X537300Y842900D03*
X534632Y849830D03*
X528868Y873683D03*
X525718Y873821D03*
X533468Y878533D03*
X538468Y888033D03*
X530968Y888283D03*
X527346Y911458D03*
X528975Y898346D03*
X537279Y897943D03*
X533143Y897910D03*
X527879Y952189D03*
X530473Y961728D03*
X528674Y964851D03*
X528500Y1106365D03*
X529191Y1115896D03*
X525525Y1110092D03*
X529191Y1118396D03*
X527046Y1131935D03*
Y1139435D03*
Y1134435D03*
Y1136935D03*
X528274Y1152684D03*
X527046Y1146935D03*
Y1144435D03*
Y1141935D03*
X528274Y1160834D03*
X532000Y1644980D03*
X550421Y3000D03*
X554198Y68581D03*
X543545Y84140D03*
Y80140D03*
Y76140D03*
X554211Y80581D03*
X546293Y76587D03*
Y72615D03*
X540998Y117557D03*
X545990D03*
X548914Y103621D03*
X540682Y106186D03*
X552105Y112083D03*
X556394Y103621D03*
X545990Y122513D03*
Y131731D03*
X540998Y122513D03*
Y131731D03*
X544089Y146461D03*
X545990Y136687D03*
X540998D03*
X548311Y141247D03*
X542991Y152367D03*
X555048Y152562D03*
X549374Y180527D03*
X544691Y180572D03*
X540843Y168697D03*
X553097Y192421D03*
X549329Y185121D03*
X544691Y185165D03*
X541931Y191941D03*
X540639Y206760D03*
X548940Y206767D03*
X546440D03*
X543940D03*
X549070Y221708D03*
X546570D03*
X553420Y221642D03*
X545185Y231021D03*
Y228221D03*
X544070Y221708D03*
X543485Y224421D03*
X550736Y236189D03*
X548236D03*
X545736D03*
X541853Y256535D03*
X550677Y248765D03*
X548177D03*
X545677D03*
X542883Y279208D03*
X545874Y268195D03*
X548374D03*
X551174Y270695D03*
X554834Y265897D03*
X551174Y268195D03*
X548374Y270695D03*
X545874D03*
X551477Y288345D03*
Y290845D03*
X548977Y288345D03*
Y290845D03*
Y293645D03*
X551477D03*
X551536Y359223D03*
Y354723D03*
Y350223D03*
Y345723D03*
Y377223D03*
Y372723D03*
Y368223D03*
Y363723D03*
X541644Y389047D03*
X553731Y388487D03*
X541706Y381723D03*
X551536D03*
X552905Y430829D03*
X544738Y581659D03*
X540770Y605443D03*
X544770D03*
X550274Y658676D03*
X551475Y661504D03*
X556574Y684031D03*
X547227Y678299D03*
X547276Y675521D03*
X556574Y700031D03*
Y688987D03*
X543101Y698772D03*
X556574Y716031D03*
Y704987D03*
Y720987D03*
X540379Y719785D03*
X552384Y762892D03*
X552188Y766577D03*
X542599Y782389D03*
X542546Y784911D03*
X554357Y784889D03*
X551524D03*
X550420Y793743D03*
X556326D03*
X540578Y793889D03*
X553871Y811298D03*
X545741Y804149D03*
X548464Y823156D03*
X540807Y816556D03*
X541129Y828335D03*
X546855Y829949D03*
X550087Y829836D03*
X556326Y829989D03*
X541129Y838865D03*
X545981Y846389D03*
X549241Y841388D03*
X546241Y843149D03*
X545237Y850319D03*
X548665Y850399D03*
X548521Y877859D03*
Y874859D03*
X540968Y878360D03*
X545144Y909025D03*
X544793Y899220D03*
X552238Y959102D03*
X548215Y1006560D03*
X552923Y997860D03*
X542793Y998507D03*
X541766Y1018368D03*
X551673Y1023900D03*
X556493Y1118351D03*
X552000Y1644980D03*
X570421Y3000D03*
X566287Y60922D03*
X561123Y55513D03*
X563433Y60438D03*
X557973Y55513D03*
X563224Y96813D03*
X558316Y91951D03*
X558341Y88801D03*
X569114Y94374D03*
X561258Y94351D03*
X560701Y85731D03*
X564255Y86046D03*
X556920Y117261D03*
X567100Y110784D03*
X564451Y113394D03*
X572669Y102249D03*
X568669D03*
X564451Y116594D03*
X567290Y130898D03*
X564451Y119594D03*
X568841Y134579D03*
X563292Y161306D03*
X560543Y157370D03*
X564627Y180665D03*
Y172665D03*
Y176665D03*
Y168665D03*
X569969Y195176D03*
X572469D03*
X556726Y186629D03*
X564627Y196665D03*
Y192665D03*
X564740Y186778D03*
X572329Y203393D03*
X564659Y212864D03*
Y200864D03*
X569829Y203393D03*
X564659Y204864D03*
Y221864D03*
Y216864D03*
X569708Y218085D03*
X572508D03*
X560300Y219379D03*
X566416Y252371D03*
Y248371D03*
X557334Y265897D03*
X570634Y375453D03*
X569938Y378317D03*
X559070Y684809D03*
X559074Y696987D03*
Y692031D03*
X559070Y700809D03*
Y688209D03*
X561570Y696209D03*
Y692809D03*
X559074Y712987D03*
Y708031D03*
X559070Y716809D03*
X561570Y708809D03*
Y712209D03*
X559070Y704209D03*
X561886Y728138D03*
X559070Y720209D03*
X558616Y732530D03*
X562001Y732834D03*
X562374Y721593D03*
X559625Y739609D03*
X557813Y747814D03*
X570578Y749800D03*
X567428Y750145D03*
X557847Y744599D03*
X570695Y767052D03*
X570038Y752339D03*
X564276Y776701D03*
X558241Y796389D03*
X562231Y784911D03*
X558294D03*
X569186Y787332D03*
X561401Y811242D03*
X567559Y812850D03*
X567316Y806224D03*
X561061Y803606D03*
X561001Y806889D03*
X567559Y803008D03*
X563099Y829943D03*
X560263Y829989D03*
X567316Y827724D03*
X559741Y822149D03*
X567559Y824661D03*
X562400Y818900D03*
X572171Y842346D03*
X559196Y846296D03*
X560813Y840574D03*
X568990Y844721D03*
X572476Y845535D03*
X559295Y874267D03*
X559887Y877196D03*
X569577Y886913D03*
X559260Y891043D03*
X564165Y894411D03*
X560814Y901022D03*
X568503Y936807D03*
X562328Y957307D03*
X566303Y951807D03*
X569403D03*
X563103D03*
X560923Y980443D03*
X556923Y980523D03*
X564923Y988813D03*
X556923D03*
X564923Y997860D03*
X560923D03*
X568923D03*
X556923D03*
X568362Y1008262D03*
X571857Y1009354D03*
X558112Y1009655D03*
X560912D03*
X568362Y1011762D03*
X571857Y1016827D03*
X565451Y1035102D03*
X559057Y1030563D03*
X562057D03*
X568057Y1030672D03*
X565057D03*
X571857Y1029427D03*
X569520Y1102091D03*
X560211D03*
X566020D03*
X569520Y1114691D03*
X566020D03*
X560211D03*
Y1109564D03*
X566058Y1122164D03*
X560211D03*
X569520Y1139891D03*
X566020D03*
X560211D03*
X566020Y1127291D03*
X560211D03*
X569520D03*
X566058Y1134764D03*
X566020Y1152491D03*
X560211D03*
X569520D03*
X566058Y1147364D03*
X560211D03*
X566020Y1165091D03*
X569520D03*
X566058Y1159964D03*
X560211D03*
X566058Y1172564D03*
X560211D03*
Y1177691D03*
X566020D03*
X569520D03*
X566058Y1185164D03*
X560211D03*
X563673Y1204932D03*
X568532Y1200001D03*
X569882Y1223749D03*
X565600Y1530800D03*
X567324Y1528151D03*
X572432Y1521462D03*
X569349Y1541947D03*
X560635Y1543531D03*
X566800Y1541800D03*
X565400Y1535100D03*
X586405Y4469D03*
X587766Y24773D03*
Y44773D03*
X582686Y109172D03*
X579686D03*
X581693Y106495D03*
X585437Y116497D03*
X581693Y102495D03*
X576420Y116594D03*
X574694Y133298D03*
X585437Y123584D03*
Y130670D03*
X576420Y119594D03*
X581427Y146012D03*
X583333Y141228D03*
X585437Y137757D03*
X581427Y142862D03*
X588568Y143762D03*
X586221Y150847D03*
X574969Y195176D03*
X574588Y198883D03*
X587516Y195176D03*
X585016D03*
X589034Y199248D03*
X578517Y206838D03*
X576017D03*
X587597Y210509D03*
X585097D03*
X589034Y201748D03*
X586870Y206806D03*
X576308Y216385D03*
X579021Y216970D03*
Y219470D03*
X579087Y226320D03*
X579021Y221970D03*
X587415Y238689D03*
X588189Y247292D03*
X580979Y236121D03*
X578013Y238589D03*
X585774Y242078D03*
X581005Y232971D03*
X580898Y253198D03*
X581487Y336676D03*
X573805Y728301D03*
X576556Y728219D03*
X575979Y732517D03*
X573778Y747437D03*
X574620Y772724D03*
X584624Y781850D03*
X588345Y798030D03*
X582100Y787600D03*
X586060Y793145D03*
X581001Y814123D03*
X583501Y800831D03*
X581001Y810973D03*
X588377Y807536D03*
X588272Y804601D03*
X588231Y801520D03*
X579758Y817753D03*
X577501Y829069D03*
X588001Y829624D03*
X581158Y823473D03*
X573300Y829600D03*
X579827Y884000D03*
Y888000D03*
X579251Y903364D03*
X582706Y908959D03*
X583065Y903294D03*
X577903Y940907D03*
X581703D03*
X576003Y935107D03*
X573103Y941307D03*
X585703D03*
X581903Y954507D03*
X577303D03*
X577249Y965445D03*
X573895Y965319D03*
X580923Y988813D03*
X588923D03*
X572923D03*
X580923Y997860D03*
X576923D03*
X588923D03*
X577666Y1009354D03*
X581166D03*
X572923Y997860D03*
X584923D03*
X577666Y1021954D03*
X577704Y1016827D03*
X581967Y1105091D03*
Y1117691D03*
Y1130291D03*
Y1155491D03*
Y1142891D03*
Y1168091D03*
Y1180691D03*
X578298Y1215195D03*
X584024Y1209607D03*
X586502Y1227300D03*
X587689Y1505724D03*
X583661Y1529142D03*
X573784Y1530646D03*
X575332Y1523740D03*
X583800Y1518000D03*
X583740Y1520640D03*
X587858Y1517942D03*
X572849Y1518702D03*
X577645Y1540982D03*
X580700Y1544100D03*
X595087Y53597D03*
X590287Y95111D03*
X592737Y109410D03*
X590237Y116497D03*
X592737D03*
X597437Y102323D03*
Y109410D03*
Y116496D03*
X594656Y106561D03*
X597437Y123583D03*
Y130670D03*
X592737Y123583D03*
X590237Y123584D03*
Y130670D03*
X592737D03*
X597437Y137756D03*
X590237Y137757D03*
X590016Y195176D03*
X592516D03*
X593969Y213539D03*
X592034Y202048D03*
X589370Y206806D03*
X595650Y238714D03*
X591131Y246874D03*
X591650Y238714D03*
X590178Y309760D03*
X592900Y309871D03*
X603282Y390223D03*
X605147Y382600D03*
X600272Y397335D03*
X603282Y395179D03*
Y404396D03*
Y409352D03*
X595280Y402291D03*
X600272D03*
X595280Y397335D03*
X592880Y416465D03*
Y411509D03*
X603282Y418569D03*
Y423525D03*
X597872Y425682D03*
X592880D03*
X597872Y416465D03*
Y411509D03*
X603282Y432743D03*
Y437699D03*
X597872Y439855D03*
X592880D03*
X597872Y430638D03*
X592880D03*
X597872Y444811D03*
X592880D03*
X593690Y450750D03*
X605262Y458711D03*
X592880Y468609D03*
X597872D03*
X592880Y473565D03*
X597872D03*
X604606Y463600D03*
X603282Y489895D03*
X592880Y487738D03*
X597872D03*
X603282Y480677D03*
Y475721D03*
X592880Y482782D03*
X597872D03*
X603282Y494851D03*
X598462Y504684D03*
X592880Y517699D03*
X597872D03*
X603282Y519855D03*
X597872Y512743D03*
X592880D03*
Y526916D03*
X597872Y531872D03*
X592880D03*
X603282Y524811D03*
Y538984D03*
Y534028D03*
X597872Y526916D03*
X597789Y536382D03*
X599110Y552466D03*
X602756Y597580D03*
X604979Y599588D03*
X604241Y589556D03*
X604180Y592354D03*
X602695Y594668D03*
X604982Y596095D03*
X605011Y603600D03*
X604979Y607588D03*
X605011Y619600D03*
Y623600D03*
X592238Y880612D03*
X592272Y877262D03*
X592110Y895611D03*
X597129Y913386D03*
X601084Y913544D03*
X602385Y940920D03*
X589203Y941407D03*
X591403Y938807D03*
Y936007D03*
X589603Y952907D03*
X602484Y965764D03*
X604923Y988813D03*
X596923D03*
Y997860D03*
X592923D03*
X604923D03*
X600923D03*
X602603Y1012354D03*
Y1024954D03*
X593613Y1012354D03*
Y1024954D03*
X604405Y1034870D03*
X591898Y1035011D03*
X603682Y1053457D03*
X590957Y1105091D03*
Y1117691D03*
Y1130291D03*
Y1155491D03*
Y1142891D03*
Y1168091D03*
Y1180691D03*
X593519Y1224472D03*
X592978Y1514812D03*
X591858Y1523542D03*
X591872Y1518071D03*
X598800Y1546400D03*
X615087Y53597D03*
X605899Y80384D03*
Y82984D03*
Y77784D03*
Y75184D03*
X608453Y92849D03*
X605899Y85584D03*
X615370Y95236D03*
X605437D03*
X615413Y103037D03*
X605437Y102323D03*
X605689Y109410D03*
Y116496D03*
X615547D03*
Y109410D03*
X605861Y124576D03*
X615547Y130670D03*
Y123583D03*
X606914Y130670D03*
X606909Y137756D03*
X612138D03*
X620727Y162368D03*
X614182Y210478D03*
Y215478D03*
Y212978D03*
Y207978D03*
Y223726D03*
Y226226D03*
Y231226D03*
Y228726D03*
X617511Y264180D03*
X620011D03*
X617436Y258880D03*
X617728Y293796D03*
X620228D03*
X608274Y390223D03*
Y395179D03*
Y404396D03*
Y409352D03*
Y418569D03*
Y423525D03*
Y432743D03*
Y437699D03*
X607789Y453682D03*
X606026Y455921D03*
X608274Y489895D03*
Y480677D03*
Y475721D03*
Y494851D03*
Y519855D03*
Y538984D03*
Y534028D03*
Y524811D03*
X614461Y555234D03*
X614176Y562003D03*
X609472Y634946D03*
X612489Y941024D03*
X609133Y941137D03*
X605733D03*
X608965Y966414D03*
X616923Y997860D03*
X608923D03*
X618878Y1011914D03*
X620151Y1040363D03*
X621479Y1030482D03*
X619086Y1056453D03*
X620715Y1046785D03*
X617634Y1049283D03*
X617894Y1043955D03*
X612955Y1062941D03*
X612000Y1644980D03*
X633248Y44884D03*
X624234Y74793D03*
Y82593D03*
Y85193D03*
Y77393D03*
Y79993D03*
X636830Y94017D03*
X628830D03*
X632830D03*
X632559Y101701D03*
Y98551D03*
X632958Y110445D03*
X623547Y109410D03*
Y116496D03*
X632958Y115401D03*
X623547Y102323D03*
X636109Y103783D03*
X626305Y104249D03*
Y107649D03*
X632958Y124618D03*
X623547Y123583D03*
Y130670D03*
X632958Y129574D03*
X623547Y137756D03*
X630871Y147540D03*
X634643Y141247D03*
X630871Y151540D03*
X625927Y162368D03*
X623327D03*
X633027Y165393D03*
Y162793D03*
Y170493D03*
Y167993D03*
X632024Y181426D03*
X635235Y181366D03*
X634521Y191941D03*
X632232Y184221D03*
X634849Y184012D03*
X628710Y211695D03*
Y208695D03*
X624638Y208213D03*
X636268Y211359D03*
Y213859D03*
X631210Y211695D03*
X624638Y213213D03*
Y210713D03*
Y231461D03*
X636300Y222212D03*
Y224712D03*
X632607Y229286D03*
X624638Y226461D03*
X628345Y226141D03*
X624638Y228961D03*
Y215713D03*
X633588Y236611D03*
X631088D03*
X632607Y231786D03*
X628588Y236611D03*
X630790Y248891D03*
X633290D03*
X628290D03*
X636215Y256535D03*
X629205Y267526D03*
X626405D03*
X631705D03*
X629205Y270026D03*
X626405D03*
X631705D03*
X631042Y288190D03*
Y285690D03*
X625742Y288190D03*
X628242Y285690D03*
X625742D03*
X628242Y288190D03*
X635268Y290755D03*
X634455Y389154D03*
Y396240D03*
Y403327D03*
Y410413D03*
Y417500D03*
Y424587D03*
Y431673D03*
Y438760D03*
Y445847D03*
Y467539D03*
Y474626D03*
Y488799D03*
Y481713D03*
Y495886D03*
Y511673D03*
Y518760D03*
Y525847D03*
Y532933D03*
Y540020D03*
Y547106D03*
X632009Y541863D03*
Y545263D03*
X630201Y553407D03*
X632701D03*
X630201Y550907D03*
X632701D03*
X634185Y569426D03*
X634471Y566929D03*
X628425Y572070D03*
X629772Y569928D03*
X632119Y570962D03*
X631862Y568475D03*
X633736Y602197D03*
X634200Y595108D03*
X622270Y864781D03*
X621592Y1033862D03*
X636015Y1460782D03*
X627354Y1461182D03*
X636015Y1465513D03*
X627354Y1465913D03*
Y1456451D03*
X636015Y1476136D03*
X627354Y1476536D03*
X636015Y1480867D03*
X627354Y1481267D03*
Y1471805D03*
X636015Y1470244D03*
X627354Y1487159D03*
X636015Y1485598D03*
Y1491490D03*
X627354Y1491890D03*
X636015Y1496221D03*
X627354Y1496621D03*
Y1507245D03*
Y1511976D03*
X636015Y1511576D03*
X627354Y1502514D03*
X636015Y1500952D03*
Y1506845D03*
Y1516307D03*
X627354Y1558813D03*
X636015Y1563144D03*
X627354Y1563544D03*
X621727Y1556800D03*
X636015Y1567875D03*
X627354Y1568275D03*
Y1574167D03*
X636015Y1572606D03*
Y1578498D03*
X627354Y1578898D03*
X636015Y1593853D03*
X627354Y1594253D03*
X636015Y1583229D03*
X627354Y1583629D03*
Y1589522D03*
X636015Y1587960D03*
X627354Y1604876D03*
X636015Y1603315D03*
Y1598584D03*
X627354Y1598984D03*
X636015Y1609207D03*
X627354Y1609607D03*
X636015Y1618669D03*
Y1613938D03*
X627354Y1614338D03*
X632000Y1644980D03*
X645907Y76140D03*
Y84140D03*
Y80140D03*
X648655Y76587D03*
Y72615D03*
X640839Y94017D03*
X643360Y117557D03*
X637950Y110445D03*
Y115401D03*
X648352Y117557D03*
X651276Y103621D03*
X640109Y103783D03*
X643044Y106186D03*
X643360Y122513D03*
Y131731D03*
X637950Y124618D03*
Y129574D03*
X648352Y122513D03*
Y131731D03*
X646451Y146461D03*
X643360Y136687D03*
X648352D03*
X650673Y141247D03*
X645353Y152367D03*
X647053Y180572D03*
X651736Y180527D03*
X638030Y181009D03*
X643205Y168697D03*
X651691Y185121D03*
X647053Y185165D03*
X641021Y184619D03*
X644293Y191941D03*
X643001Y206760D03*
X646302Y206767D03*
X651302D03*
X648802D03*
X639971Y213132D03*
X648932Y221708D03*
X647547Y228221D03*
X645847Y224421D03*
X646432Y221708D03*
X651432D03*
X639971Y215632D03*
X650598Y236189D03*
X648098D03*
X653098D03*
X644215Y256535D03*
X653039Y248765D03*
X650539D03*
X648039D03*
X640215Y256303D03*
X645245Y279208D03*
X650736Y268195D03*
X653536Y270695D03*
Y268195D03*
X650736Y270695D03*
X648236D03*
Y268195D03*
X651339Y290845D03*
Y293645D03*
X653839D03*
X639268Y290755D03*
X653839Y288345D03*
Y290845D03*
X651339Y288345D03*
X642255Y389154D03*
X649074D03*
X642255Y396240D03*
X643534Y404911D03*
X647604Y396240D03*
X642488Y412571D03*
X652381Y414823D03*
X651689Y422864D03*
X643675Y426299D03*
X651759Y429832D03*
X651364Y436447D03*
X653399Y447953D03*
X643986Y445847D03*
X642255Y467539D03*
X652566D03*
X642255Y474626D03*
X651308Y472772D03*
X652042Y487711D03*
X652155Y479104D03*
X642516Y480828D03*
X644466Y498834D03*
X652566Y495886D03*
X647915Y516841D03*
X651166Y510565D03*
X642255Y518760D03*
Y511673D03*
Y525847D03*
X642862Y550123D03*
X642740Y552872D03*
X644494Y572334D03*
X642185Y562443D03*
X643953Y560675D03*
X642726Y574102D03*
X651149Y577716D03*
X648211Y602400D03*
Y598400D03*
Y594400D03*
Y606400D03*
Y614400D03*
Y610400D03*
X647361Y653161D03*
X648352Y645467D03*
X650958Y677843D03*
X653338Y1465513D03*
X644677Y1461182D03*
Y1456451D03*
Y1465913D03*
X653338Y1460782D03*
X644677Y1476536D03*
Y1471805D03*
X653338Y1480867D03*
Y1470244D03*
Y1476136D03*
X644677Y1481267D03*
X653338Y1491490D03*
X644677Y1496621D03*
Y1491890D03*
Y1487159D03*
X653338Y1496221D03*
Y1485598D03*
X644677Y1511976D03*
X653338Y1511576D03*
Y1500952D03*
Y1506845D03*
X644677Y1502514D03*
Y1507245D03*
X653338Y1516307D03*
X644677Y1558813D03*
X653338Y1563144D03*
X644677Y1563544D03*
X653338Y1572606D03*
Y1578498D03*
X644677Y1578898D03*
Y1574167D03*
X653338Y1567875D03*
X644677Y1568275D03*
X653338Y1587960D03*
Y1593853D03*
X644677Y1594253D03*
Y1589522D03*
X653338Y1583229D03*
X644677Y1583629D03*
X653338Y1609207D03*
X644677Y1598984D03*
Y1604876D03*
Y1609607D03*
X653338Y1603315D03*
Y1598584D03*
Y1613938D03*
X644677Y1614338D03*
X653338Y1618669D03*
X652000Y1644980D03*
X668649Y60922D03*
X666209Y57297D03*
X665795Y60438D03*
X657507Y58013D03*
X656560Y68581D03*
X656573Y80581D03*
X665423Y96853D03*
X660678Y91951D03*
X660703Y88801D03*
X663620Y94351D03*
X663063Y85731D03*
X666617Y86046D03*
X659282Y117261D03*
X666813Y113394D03*
X669462Y110784D03*
X666813Y116594D03*
X654467Y112083D03*
X669056Y133298D03*
X666813Y119594D03*
X665654Y161306D03*
X657410Y152562D03*
X662905Y157370D03*
X666989Y172665D03*
Y180665D03*
Y176665D03*
Y168665D03*
X655459Y192421D03*
X659088Y186629D03*
X666989Y196665D03*
Y192665D03*
X667102Y186778D03*
X667021Y200864D03*
Y212864D03*
Y204864D03*
Y221864D03*
Y216864D03*
X655782Y221642D03*
X662662Y219379D03*
X668778Y252371D03*
X668886Y248371D03*
X657196Y265897D03*
X659696D03*
X660366Y389154D03*
X667666Y389153D03*
X660366Y403327D03*
Y410413D03*
X665166Y396240D03*
X667666D03*
X665166Y403327D03*
X667666Y403326D03*
X665166Y410413D03*
X667666D03*
X660366Y396240D03*
X667666Y417499D03*
X665166Y424586D03*
X667666D03*
X660366Y417500D03*
Y424586D03*
X665166Y417500D03*
Y431673D03*
Y438760D03*
X667666D03*
Y431673D03*
X660366D03*
Y438760D03*
X665166Y445847D03*
X660366D03*
X667666Y467539D03*
X660366D03*
X665166Y474626D03*
X667666D03*
X660366D03*
Y488799D03*
X665166D03*
X667666D03*
Y481712D03*
X665166D03*
X660366Y481713D03*
X665166Y495886D03*
X660366D03*
X667666Y518760D03*
X665166D03*
X667666Y511673D03*
X660366D03*
Y518760D03*
X667666Y532933D03*
X665166D03*
Y540020D03*
Y525846D03*
X667666D03*
X660366Y525847D03*
Y532933D03*
Y540020D03*
Y554193D03*
Y547106D03*
X660826Y570414D03*
Y567914D03*
Y565414D03*
X669546Y560500D03*
X661760Y561420D03*
Y558917D03*
X660826Y575414D03*
Y572914D03*
X657581Y577937D03*
X660366Y602205D03*
Y595118D03*
X658233Y646449D03*
X655752Y668885D03*
X661776Y662981D03*
X657967D03*
X662092Y666275D03*
X656157Y691851D03*
X659209D03*
X661768Y705043D03*
X661018Y707592D03*
X662000Y1456451D03*
Y1465913D03*
Y1461182D03*
Y1481267D03*
Y1476536D03*
Y1471805D03*
Y1496621D03*
Y1491890D03*
Y1487159D03*
Y1511976D03*
Y1502514D03*
Y1507245D03*
Y1563544D03*
Y1558813D03*
Y1568275D03*
Y1578898D03*
Y1574167D03*
Y1594253D03*
Y1589522D03*
Y1583629D03*
Y1598984D03*
Y1604876D03*
Y1609607D03*
Y1614338D03*
X671476Y94374D03*
X682048Y109172D03*
X685048D03*
X684055Y106495D03*
X678782Y116594D03*
X684055Y102495D03*
X677056Y133298D03*
X678782Y119594D03*
X671203Y134579D03*
X683789Y146012D03*
X685695Y141228D03*
X683789Y142862D03*
X672331Y195176D03*
X674831D03*
X677331D03*
X676950Y198883D03*
X672191Y203393D03*
X674691D03*
X678379Y206838D03*
X680879D03*
X674870Y218085D03*
X681383Y219470D03*
Y216970D03*
X678670Y216385D03*
X681383Y221970D03*
X681449Y226320D03*
X672070Y218085D03*
X680375Y238589D03*
X683341Y236121D03*
X683367Y232971D03*
X683260Y253198D03*
X686012Y339795D03*
X685353Y392718D03*
X672466Y389153D03*
Y410413D03*
X685353Y408718D03*
Y400718D03*
X672466Y396240D03*
Y403326D03*
X685353Y396718D03*
X672466Y424586D03*
Y417499D03*
Y438760D03*
Y431673D03*
X678461Y455981D03*
X672466Y467539D03*
Y474626D03*
X675237Y465611D03*
X672466Y488799D03*
Y481712D03*
Y518760D03*
Y511673D03*
Y525846D03*
Y532933D03*
X682586Y530000D03*
X681586Y555000D03*
X681011Y543925D03*
X682086Y540500D03*
X681086Y547075D03*
X681286Y549800D03*
X681126Y558800D03*
X681190Y562800D03*
X679322Y1461182D03*
Y1456451D03*
Y1465913D03*
X670661Y1460782D03*
Y1465513D03*
Y1470244D03*
Y1476136D03*
X679322Y1481267D03*
Y1476536D03*
Y1471805D03*
X670661Y1480867D03*
X679322Y1487159D03*
X670661Y1496221D03*
Y1485598D03*
Y1491490D03*
X679322Y1496621D03*
Y1491890D03*
X670661Y1500952D03*
Y1506845D03*
X679322Y1511976D03*
Y1502514D03*
Y1507245D03*
X670661Y1511576D03*
Y1516307D03*
X679322Y1558813D03*
X670661Y1563144D03*
X679322Y1563544D03*
Y1578898D03*
Y1574167D03*
Y1568275D03*
X670661Y1572606D03*
Y1578498D03*
Y1567875D03*
X679322Y1583629D03*
X670661Y1587960D03*
Y1593853D03*
Y1583229D03*
X679322Y1594253D03*
Y1589522D03*
Y1604876D03*
Y1609607D03*
X670661Y1603315D03*
Y1598584D03*
Y1609207D03*
X679322Y1598984D03*
Y1614338D03*
X670661Y1618669D03*
Y1613938D03*
X672000Y1644980D03*
X690073Y44662D03*
X697387Y53619D03*
X692649Y95111D03*
X695099Y109410D03*
X687799Y116497D03*
X692599D03*
X695099D03*
X699799Y116496D03*
Y109410D03*
Y102323D03*
X697018Y106561D03*
X687799Y123584D03*
X695099Y123583D03*
X692599Y123584D03*
X687799Y130670D03*
X692599D03*
X695099D03*
X699799Y123583D03*
Y130670D03*
X687799Y137757D03*
X692599D03*
X699799Y137756D03*
X688583Y150847D03*
X691396Y199248D03*
X687378Y195176D03*
X689878D03*
X694878D03*
X692378D03*
X696331Y213539D03*
X691396Y201748D03*
X689232Y206806D03*
X687459Y210509D03*
X689959D03*
X694396Y202048D03*
X691732Y206806D03*
X698012Y238714D03*
X689777Y238689D03*
X690551Y247292D03*
X694012Y238714D03*
X688136Y242078D03*
X693493Y246874D03*
X702448Y546712D03*
Y542712D03*
X700164Y636842D03*
X699188Y656321D03*
X698936Y678462D03*
X702086D03*
X692478Y730641D03*
X702691Y766471D03*
Y753471D03*
Y762971D03*
Y756971D03*
X702677Y771159D03*
Y780659D03*
Y775159D03*
Y784659D03*
X690449Y814406D03*
X696645Y1461183D03*
Y1456452D03*
Y1465914D03*
X687984Y1460782D03*
Y1465513D03*
Y1470244D03*
Y1476136D03*
X696645Y1481268D03*
Y1471806D03*
Y1476537D03*
X687984Y1480867D03*
X696645Y1491891D03*
X687984Y1496221D03*
Y1485598D03*
Y1491490D03*
X696645Y1496622D03*
Y1487160D03*
Y1511977D03*
Y1502515D03*
Y1507246D03*
X687984Y1511576D03*
Y1500952D03*
Y1506845D03*
Y1516307D03*
X696645Y1558813D03*
Y1563544D03*
X687984Y1563144D03*
X696645Y1574167D03*
Y1578898D03*
X687984Y1572606D03*
Y1578498D03*
X696645Y1568275D03*
X687984Y1567875D03*
Y1583229D03*
X696645Y1589522D03*
Y1594253D03*
X687984Y1587960D03*
Y1593853D03*
X696645Y1583629D03*
Y1598984D03*
Y1609607D03*
X687984Y1603315D03*
Y1598584D03*
Y1609207D03*
X696645Y1604876D03*
X687984Y1613938D03*
X696645Y1614338D03*
X687984Y1618669D03*
X692000Y1644980D03*
X718503Y-38525D03*
X718500Y-33320D03*
Y-30420D03*
X718488Y-36010D03*
Y-27642D03*
X718503Y-25127D03*
X717387Y53619D03*
X708261Y82984D03*
Y80384D03*
Y77784D03*
Y75184D03*
X710815Y92849D03*
X708261Y85584D03*
X717732Y95236D03*
X707799D03*
X717775Y103037D03*
X707799Y102323D03*
X708051Y109410D03*
Y116496D03*
X717909D03*
Y109410D03*
X708223Y124576D03*
X717909Y130670D03*
Y123583D03*
X709276Y130670D03*
X714500Y137756D03*
X709271D03*
X716544Y215478D03*
Y210478D03*
Y207978D03*
Y212978D03*
Y228726D03*
Y231226D03*
Y226226D03*
Y223726D03*
X718338Y305272D03*
X713162Y434493D03*
X711598Y438323D03*
X711764Y449873D03*
X710643Y456335D03*
X711764Y445873D03*
X718691Y465492D03*
Y472579D03*
X716191D03*
X711391D03*
X716191Y479666D03*
X718691D03*
X711391D03*
Y486752D03*
X716191D03*
X718691D03*
X711391Y493839D03*
X716191D03*
Y516713D03*
Y523800D03*
X718691D03*
X711391D03*
Y516713D03*
X718691D03*
Y509626D03*
Y530886D03*
X716191D03*
Y537973D03*
X711391Y530886D03*
Y537973D03*
Y566752D03*
X718691Y559665D03*
Y566752D03*
X716191D03*
X711391Y573839D03*
X718691D03*
X716191D03*
X711391Y588013D03*
X718691Y588012D03*
X716191Y588013D03*
X718691Y580926D03*
X716191D03*
X711391D03*
X716191Y602186D03*
X711391D03*
X718691Y602185D03*
Y595099D03*
X711391D03*
X716191D03*
X711391Y609272D03*
X716191D03*
X718691D03*
X716191Y616359D03*
X711391D03*
X704364Y618288D03*
X706070Y638125D03*
X716656Y646429D03*
X711328Y653821D03*
X703669Y665140D03*
X705390Y655789D03*
X705776Y678519D03*
X716350Y699477D03*
X703604Y699653D03*
X713200Y699676D03*
X716623Y702463D03*
X703600Y702212D03*
X703680Y697094D03*
X715802Y706446D03*
X710196Y707562D03*
X704446Y760611D03*
X717434Y782500D03*
X710275Y786131D03*
X713222Y793312D03*
Y790812D03*
X712901Y821600D03*
X712000Y1644980D03*
X721756Y-38539D03*
X724781Y-37219D03*
X721741Y-36024D03*
Y-27628D03*
X721756Y-25113D03*
X724781Y-26433D03*
X726596Y74793D03*
Y77393D03*
Y79993D03*
Y85193D03*
Y82593D03*
X735192Y94017D03*
X731192D03*
X734921Y101701D03*
Y98551D03*
X725909Y102323D03*
Y116496D03*
Y109410D03*
X728667Y104249D03*
Y107649D03*
X725909Y130670D03*
Y123583D03*
Y137756D03*
X733233Y147540D03*
Y151540D03*
X728289Y162368D03*
X725689D03*
X734386Y181426D03*
X734594Y184221D03*
X727000Y213213D03*
Y208213D03*
X731072Y208695D03*
X733572Y211695D03*
X731072D03*
X727000Y210713D03*
Y228961D03*
X730707Y226141D03*
X727000Y226461D03*
X734969Y229286D03*
X727000Y231461D03*
Y215713D03*
X733450Y236611D03*
X730950D03*
X734969Y231786D03*
X733152Y248891D03*
X730652D03*
X722373Y264180D03*
X719873D03*
X719798Y258880D03*
X731567Y267526D03*
X728767D03*
X734067D03*
Y270026D03*
X731567D03*
X728767D03*
X733404Y285690D03*
X720090Y293796D03*
X722590D03*
X728104Y288190D03*
X730604Y285690D03*
X728104D03*
X730604Y288190D03*
X733404D03*
X731511Y390500D03*
X734606Y379562D03*
X731511Y381113D03*
X722097Y410394D03*
Y403307D03*
X723031Y440098D03*
Y437598D03*
Y435098D03*
Y432598D03*
Y430098D03*
X732035Y442606D03*
X723491Y458406D03*
Y451319D03*
X722097Y453881D03*
X731952Y446606D03*
X722097Y446595D03*
X723491Y465492D03*
X731291Y466027D03*
X723315Y462264D03*
X723491Y472579D03*
X731433Y475262D03*
X732959Y463479D03*
X733430Y467367D03*
X731433Y489435D03*
Y482666D03*
X723491Y479665D03*
Y486752D03*
Y493839D03*
X731249Y495088D03*
X724362Y504731D03*
X723491Y523799D03*
Y516713D03*
Y509626D03*
X731984Y514608D03*
X731906Y522134D03*
X731291Y509626D03*
X723491Y530886D03*
Y537973D03*
X732549Y529136D03*
X732388Y535677D03*
X723491Y566752D03*
Y559665D03*
X731291D03*
X731672Y565574D03*
X723491Y573839D03*
Y588012D03*
Y580926D03*
X731319Y574338D03*
X723491Y595099D03*
Y602185D03*
Y609272D03*
Y616358D03*
X731418D03*
X734819Y646429D03*
X722473Y693718D03*
X723656Y705858D03*
X720985Y711658D03*
X725667Y732161D03*
X723177Y728219D03*
X721218Y742131D03*
X721163Y738981D03*
X720271Y782481D03*
X733000Y816000D03*
X730880Y828924D03*
X733680Y828977D03*
X732713Y853890D03*
X722600Y869600D03*
X725318Y890354D03*
X724707Y893143D03*
X719661Y904900D03*
X722789Y927095D03*
X720373Y940310D03*
X722400Y942500D03*
X720271Y931730D03*
X732306Y942682D03*
X724547Y958287D03*
X728846Y948331D03*
X727116Y959326D03*
X732825Y1604100D03*
X732000Y1644980D03*
X736242Y5374D03*
X735555Y24773D03*
Y44773D03*
X748269Y84140D03*
Y76140D03*
Y80140D03*
X751017Y76587D03*
Y72615D03*
X743201Y94017D03*
X739192D03*
X750714Y117557D03*
X745722D03*
X740312Y115401D03*
Y110445D03*
X735320D03*
Y115401D03*
X742471Y103783D03*
X745406Y106186D03*
X738471Y103783D03*
X745722Y131731D03*
Y122513D03*
X740312Y129574D03*
Y124618D03*
X735320D03*
Y129574D03*
X750714Y131731D03*
Y122513D03*
Y136687D03*
X745722D03*
X748813Y146461D03*
X737005Y141247D03*
X747715Y152367D03*
X735389Y165393D03*
Y162793D03*
X749415Y180572D03*
X735389Y170493D03*
Y167993D03*
X740392Y181009D03*
X737597Y181366D03*
X745567Y168697D03*
X749415Y185165D03*
X743383Y184619D03*
X736883Y191941D03*
X746655D03*
X737211Y184012D03*
X750667Y192300D03*
X745363Y206760D03*
X751164Y206767D03*
X748664D03*
X738630Y213859D03*
Y211359D03*
X742333Y213132D03*
X738662Y224712D03*
Y222212D03*
X749909Y228221D03*
Y231021D03*
X751294Y221708D03*
X748209Y224421D03*
X748794Y221708D03*
X742333Y215632D03*
X735950Y236611D03*
X750460Y236189D03*
X735652Y248891D03*
X738577Y256535D03*
X746577D03*
X750401Y248765D03*
X742577Y256303D03*
X747607Y279208D03*
X750598Y268195D03*
Y270695D03*
X741630Y290755D03*
X737630D03*
X741051Y316389D03*
X741161Y381500D03*
X749606Y384410D03*
X749586Y410394D03*
Y403307D03*
X741259Y439963D03*
X741381Y430760D03*
X741402Y433570D03*
X741218Y437072D03*
X749539Y438269D03*
Y440869D03*
Y435669D03*
Y430469D03*
Y433069D03*
X741503Y443180D03*
X741523Y454744D03*
X741465Y452018D03*
X749402Y458406D03*
X735599Y449961D03*
X750393Y451677D03*
Y454177D03*
X741602Y465492D03*
X741568Y460250D03*
X739333Y470136D03*
X749402Y465492D03*
X741602Y472579D03*
X749402D03*
X741072Y478958D03*
X741602Y486752D03*
X749402Y479665D03*
Y486752D03*
Y493839D03*
X741602D03*
X749402Y523799D03*
Y516713D03*
Y509626D03*
X741602D03*
Y516713D03*
X749402Y537973D03*
Y530886D03*
X738062Y537973D03*
X740542Y525483D03*
X740463Y532756D03*
X749402Y559665D03*
Y566752D03*
X741602Y559665D03*
Y566752D03*
X749402Y573839D03*
Y588012D03*
Y580925D03*
X741452Y579978D03*
X741602Y573839D03*
X749402Y602185D03*
Y595099D03*
Y609272D03*
Y616358D03*
X741666Y608117D03*
X741992Y763480D03*
X741000Y771100D03*
X743428Y772418D03*
X741993Y775909D03*
X735576Y861780D03*
X736000Y864266D03*
X742407Y988452D03*
X743062Y1004460D03*
X742655Y1445733D03*
X749439Y1458777D03*
X740530Y1524113D03*
X751140Y1581335D03*
X740640Y1586885D03*
X747140Y1581335D03*
X737892Y1602340D03*
X748924Y1617709D03*
X735878Y1617010D03*
X747590Y1627871D03*
X744924Y1617709D03*
X743331Y1627871D03*
X741705Y1622015D03*
X738325Y1634485D03*
X755145Y3000D03*
X765847Y55513D03*
X762697D03*
X758922Y68581D03*
X758935Y80581D03*
X763040Y91951D03*
X763065Y88801D03*
X765982Y94351D03*
X765425Y85731D03*
X762065Y117040D03*
X753638Y103621D03*
X756829Y112083D03*
X761118Y103621D03*
X753035Y141247D03*
X759772Y152562D03*
X765267Y157370D03*
X754098Y180527D03*
X757821Y192421D03*
X754053Y185121D03*
X761450Y186629D03*
X753182Y198671D03*
X753664Y206767D03*
X753794Y221708D03*
X758144Y221642D03*
X765024Y219379D03*
X763653Y224536D03*
X752960Y236189D03*
X755460D03*
X755401Y248765D03*
X752901D03*
X753098Y268195D03*
X755898D03*
X753098Y270695D03*
X755898D03*
X759558Y265897D03*
X762058D03*
X756201Y288345D03*
Y290845D03*
X753701Y288345D03*
Y290845D03*
Y293645D03*
X756201D03*
X760407Y324494D03*
X767099Y316731D03*
X759029Y328867D03*
X763898Y342319D03*
X759029Y332017D03*
X766344Y377912D03*
Y393924D03*
Y389912D03*
Y385912D03*
X758038Y381143D03*
X766344Y381912D03*
Y409924D03*
Y405924D03*
Y401924D03*
X752341Y407148D03*
X756800Y403824D03*
X758381Y395391D03*
X766344Y397912D03*
X752339Y438269D03*
Y433069D03*
Y430469D03*
Y435669D03*
Y440869D03*
X759543Y445787D03*
X755593Y445908D03*
X752893Y451677D03*
Y454177D03*
X752097Y460218D03*
Y463618D03*
X755035Y1443524D03*
X765713Y1437365D03*
X766433Y1583713D03*
X755187Y1580821D03*
X759802Y1590864D03*
X752150Y1627871D03*
X762671Y1619367D03*
X756358Y1613767D03*
X762776Y1629415D03*
X752000Y1644980D03*
X775145Y3000D03*
X771011Y60922D03*
X768157Y60438D03*
X767929Y96890D03*
X773838Y94374D03*
X768979Y86046D03*
X771824Y110784D03*
X777393Y102249D03*
X773393D03*
X769175Y113394D03*
X781144Y116594D03*
X769175D03*
X779418Y133298D03*
X771960Y130898D03*
X781144Y119594D03*
X769175D03*
X773565Y134579D03*
X768016Y161306D03*
X769351Y172665D03*
Y180665D03*
Y176665D03*
Y168665D03*
X779693Y195176D03*
X779312Y198883D03*
X777193Y195176D03*
X774693D03*
X769351Y192665D03*
X769464Y186778D03*
X780741Y206838D03*
X783241D03*
X777053Y203393D03*
X774553D03*
X769383Y200864D03*
Y212864D03*
Y204864D03*
Y221864D03*
Y216864D03*
X777232Y218085D03*
X783745Y216970D03*
X781032Y216385D03*
X783745Y221970D03*
X783811Y226320D03*
X783745Y219470D03*
X782737Y238589D03*
X771140Y252371D03*
Y248371D03*
X780968Y303839D03*
X771941Y311740D03*
X776943Y321649D03*
X772990Y336324D03*
X777569Y353506D03*
X774419Y353470D03*
X778985Y442498D03*
X778881Y446510D03*
X779029Y450510D03*
X780575Y471484D03*
X775584Y466528D03*
X780575D03*
X775583Y471484D03*
X780575Y480701D03*
X775583D03*
Y485657D03*
X780575D03*
Y510661D03*
X775583Y515617D03*
X780575D03*
X775583Y510661D03*
X780575Y524835D03*
Y529791D03*
X775583Y524835D03*
Y529791D03*
X775746Y539315D03*
X777708Y553287D03*
X781429Y545017D03*
X780575Y560701D03*
Y565657D03*
X775583Y560701D03*
Y565657D03*
Y579830D03*
X780575D03*
X775583Y574874D03*
X780575D03*
X775583Y589047D03*
X780575D03*
Y594003D03*
X775583D03*
Y603221D03*
X780575D03*
X775583Y608177D03*
X780575D03*
X778860Y626912D03*
X778205Y622912D03*
X783694Y1410977D03*
X778685Y1416198D03*
X780162Y1412848D03*
X777749Y1431432D03*
X783469Y1424655D03*
X777114Y1442270D03*
X771557Y1446818D03*
X768910Y1437741D03*
X777749Y1435432D03*
Y1439432D03*
X777260Y1446237D03*
X778428Y1455156D03*
X777725Y1450193D03*
X768812Y1453306D03*
X777033Y1595215D03*
X781124Y1583553D03*
X781545Y1602835D03*
X774658Y1601012D03*
X778045Y1622545D03*
X782289Y1620109D03*
X773822Y1627418D03*
X778045Y1619395D03*
X778358Y1627418D03*
X771383Y1616917D03*
X772000Y1644980D03*
X791129Y4469D03*
X792490Y24773D03*
Y44773D03*
X799811Y53597D03*
X795011Y95111D03*
X784410Y109172D03*
X787410D03*
X794961Y116497D03*
X797461D03*
X790161D03*
X786417Y106495D03*
X797461Y109410D03*
X786417Y102495D03*
X799380Y106561D03*
X797461Y123583D03*
X794961Y123584D03*
X790161D03*
X794961Y130670D03*
X797461D03*
X790161D03*
X794961Y137757D03*
X790161D03*
X788057Y141228D03*
X786151Y146012D03*
X793221Y140296D03*
X786151Y142862D03*
X790945Y150847D03*
X797240Y195176D03*
X794740D03*
X789740D03*
X792240D03*
X793758Y199248D03*
X798693Y213539D03*
X794094Y206806D03*
X791594D03*
X789821Y210509D03*
X792321D03*
X793758Y201748D03*
X796758Y202048D03*
X792913Y247292D03*
X792139Y238689D03*
X785703Y236121D03*
X796374Y238714D03*
X790498Y242078D03*
X785729Y232971D03*
X795855Y246874D03*
X785622Y253198D03*
X788522Y290304D03*
X800155Y337368D03*
X800029Y333368D03*
X799937Y347340D03*
X797141Y350368D03*
X792564Y406410D03*
X784586Y421000D03*
Y418500D03*
Y413500D03*
Y416000D03*
X784804Y425371D03*
X794173Y450510D03*
X785985Y473640D03*
X790977D03*
X785985Y487813D03*
X790977D03*
X785985Y478596D03*
X790977D03*
X785985Y492769D03*
X790977D03*
Y517774D03*
Y522730D03*
X785985Y517774D03*
Y522730D03*
Y531947D03*
Y536903D03*
X790977Y531947D03*
Y536903D03*
X796000Y553101D03*
X784665Y564843D03*
X790977Y567813D03*
X785985Y572769D03*
X790977D03*
X785985Y567813D03*
X790977Y581987D03*
Y586943D03*
X785985Y581987D03*
Y586943D03*
X790977Y601116D03*
X785985D03*
Y596160D03*
X790977D03*
Y615289D03*
Y610333D03*
X785985Y615289D03*
Y610333D03*
X788600Y1006923D03*
X791686Y1025440D03*
X799631D03*
X795631D03*
X789050Y1026150D03*
X793842Y1143384D03*
X798353Y1172011D03*
X794716Y1186071D03*
X787887Y1174500D03*
X798542Y1188345D03*
X794533Y1195766D03*
X792183Y1334030D03*
Y1331230D03*
X789383Y1334030D03*
Y1331230D03*
X794983Y1334030D03*
Y1331230D03*
X794506Y1411307D03*
X795296Y1416995D03*
X792848Y1414718D03*
X793459Y1429165D03*
X788648Y1422044D03*
X785820Y1425993D03*
X793744Y1437159D03*
X786787Y1433800D03*
X790361Y1447895D03*
X790754Y1441399D03*
X799057Y1449158D03*
Y1456016D03*
X790296Y1463459D03*
X787038Y1460533D03*
X790989Y1455695D03*
X793723Y1468071D03*
X799314Y1475693D03*
X797318Y1471242D03*
X787447Y1593586D03*
X791610Y1593708D03*
X793564Y1642682D03*
X810623Y77784D03*
Y82984D03*
Y80384D03*
Y75184D03*
X813177Y92849D03*
X810623Y85584D03*
X810161Y95236D03*
Y102323D03*
X810413Y109410D03*
Y116496D03*
X802161D03*
Y109410D03*
Y102323D03*
X810585Y124576D03*
X811638Y130670D03*
X802161D03*
Y123583D03*
X811633Y137756D03*
X802161D03*
X800374Y238714D03*
X805952Y301675D03*
X801097Y325858D03*
X809489Y313830D03*
X809490Y321368D03*
Y333368D03*
X804536Y441486D03*
X816177Y441442D03*
X813456Y441474D03*
X802136Y452334D03*
X815840Y444091D03*
Y456060D03*
X810756Y471071D03*
Y468571D03*
X814580Y468806D03*
X814828Y472053D03*
X810756Y473571D03*
Y491118D03*
Y488618D03*
Y483618D03*
X816364Y486870D03*
X810756Y486118D03*
X813864Y486870D03*
X810756Y476071D03*
X815492Y732917D03*
X813902Y730738D03*
X813566Y744187D03*
X813653Y746856D03*
X813635Y762000D03*
X812661Y810032D03*
X813000Y805000D03*
X813548Y814000D03*
X812980Y824166D03*
X813009Y819734D03*
X815500Y824000D03*
X816016Y838036D03*
X813182Y852800D03*
X812440Y862306D03*
X814080Y864464D03*
X812575Y880834D03*
X814731Y889365D03*
X812219Y883586D03*
X812811Y908162D03*
X803673Y1025440D03*
X809682Y1133284D03*
X803453Y1134729D03*
X814835D03*
X806835D03*
X806787Y1148000D03*
X815034Y1159455D03*
X809623Y1160168D03*
X809393Y1187252D03*
X814160Y1178240D03*
X807487Y1193019D03*
X815487D03*
X811487D03*
X815455Y1201043D03*
X811485D03*
X807489D03*
X804452Y1199814D03*
X809027Y1219895D03*
X807020Y1217900D03*
X812302Y1223170D03*
X815149Y1226016D03*
X810148Y1374884D03*
X800627Y1392748D03*
X806318Y1401661D03*
X800703Y1426779D03*
X812901Y1432804D03*
X815901D03*
X810059Y1432778D03*
X812104Y1426483D03*
X809986Y1438785D03*
X812986D03*
X815986D03*
X809986Y1441485D03*
X812986D03*
X815986D03*
X812901Y1435504D03*
X815901D03*
X810001D03*
X806874Y1447457D03*
X812474D03*
X803057Y1449158D03*
X801057Y1447158D03*
X806874Y1452587D03*
Y1457717D03*
X812474D03*
X815096Y1464387D03*
X803057Y1456016D03*
X801057Y1458016D03*
X812009Y1473432D03*
Y1470432D03*
X815096Y1467387D03*
X812096Y1479587D03*
Y1476587D03*
X815096Y1473387D03*
Y1479587D03*
Y1476587D03*
Y1470387D03*
X801354Y1478681D03*
X804919Y1489247D03*
X811457Y1639797D03*
X819811Y53597D03*
X828958Y79993D03*
Y77393D03*
Y74793D03*
Y85193D03*
Y82593D03*
X820094Y95236D03*
X820137Y103037D03*
X820271Y116496D03*
Y109410D03*
X828271Y116496D03*
Y109410D03*
Y102323D03*
X831029Y104249D03*
Y107649D03*
X820271Y130670D03*
Y123583D03*
X828271Y130670D03*
Y123583D03*
X816637Y137756D03*
X828271D03*
X830651Y162368D03*
X828051D03*
X829362Y213213D03*
X818906Y207978D03*
Y212978D03*
Y215478D03*
Y210478D03*
X829362Y208213D03*
Y210713D03*
Y231461D03*
Y228961D03*
Y226461D03*
X818906Y228726D03*
Y231226D03*
Y226226D03*
Y223726D03*
X829362Y215713D03*
X822235Y264180D03*
X824735D03*
X831129Y267526D03*
Y270026D03*
X824952Y293796D03*
X822452D03*
X830466Y285690D03*
Y288190D03*
X825792Y305225D03*
X825971Y345101D03*
X829381Y348036D03*
X825103Y430358D03*
Y435558D03*
Y432958D03*
X831378Y433086D03*
Y435686D03*
Y430486D03*
X824650Y446740D03*
X822040Y444091D03*
X818840Y456060D03*
X826262Y462326D03*
Y459326D03*
X823529Y467189D03*
X817328Y472053D03*
X820810Y471243D03*
X817380Y468806D03*
X823544Y475061D03*
Y472561D03*
X820810Y473743D03*
X818973Y491258D03*
Y488758D03*
X822418Y485070D03*
Y482570D03*
X828918Y480580D03*
X831418D03*
X831057Y484036D03*
X834282Y536085D03*
X828272Y535462D03*
X827291Y533100D03*
X830318Y674164D03*
X829496Y676793D03*
X823790Y713375D03*
X829784Y713939D03*
Y716589D03*
Y705489D03*
X823890Y703415D03*
X823670Y710542D03*
X823843Y732109D03*
X824387Y726246D03*
X818307Y724144D03*
X830484Y746701D03*
X819890Y736924D03*
X826484Y747127D03*
X827500Y750000D03*
X819788Y739634D03*
X819993Y754109D03*
X817500Y760000D03*
X824500Y760500D03*
X822151Y752283D03*
X817365Y756827D03*
X820547Y780314D03*
X826925Y769000D03*
X820500Y777500D03*
X824500Y778500D03*
X826925Y787000D03*
X820500Y792000D03*
X824500Y796500D03*
X818500Y814000D03*
X820432Y800529D03*
X826925Y805000D03*
X824500Y814500D03*
X826925Y823000D03*
X829946Y829788D03*
X829791Y839020D03*
X825721Y836666D03*
Y839816D03*
X830014Y833046D03*
X822608Y848526D03*
X826165Y863000D03*
X819134Y863607D03*
X829000Y852000D03*
X831583Y853454D03*
X825686Y869496D03*
X823234Y867680D03*
X826209Y866052D03*
X823234Y870830D03*
X826797Y883756D03*
X825774Y895553D03*
X826070Y893014D03*
X817152Y896380D03*
X817139Y890330D03*
X823900Y882083D03*
X834465Y884538D03*
X825508Y913869D03*
X818031Y907747D03*
X822462Y915095D03*
X831057Y916745D03*
X818347Y939610D03*
X823552Y930700D03*
X829617Y939583D03*
X816519Y931147D03*
X828193Y949324D03*
X824168Y949538D03*
X828423Y964731D03*
X825670Y964671D03*
X832423Y964669D03*
X828964Y977780D03*
X832711Y993268D03*
X828385Y1120599D03*
X830356Y1116251D03*
X827856D03*
X817006Y1133027D03*
X822006Y1130208D03*
X825335Y1137129D03*
X819449Y1134534D03*
X819026Y1128137D03*
X825744Y1150087D03*
X823220Y1162817D03*
Y1170767D03*
X823487Y1193019D03*
X819487D03*
X819489Y1201039D03*
X823489Y1200969D03*
X826612Y1219254D03*
X819522Y1212164D03*
X821816Y1214458D03*
X823608Y1208993D03*
X817360Y1228226D03*
X816648Y1377608D03*
Y1380758D03*
X824901Y1427404D03*
X827901D03*
X821901D03*
X818901Y1430104D03*
X821901D03*
X830901D03*
X827901D03*
X824901D03*
Y1432804D03*
X827901D03*
X830901D03*
X821901D03*
X818901D03*
X824901Y1435504D03*
X827901D03*
X821901D03*
X818901D03*
X821986Y1441485D03*
X818986D03*
Y1438785D03*
X821986D03*
X817974Y1447457D03*
X826204Y1444689D03*
X832084Y1461072D03*
X817974Y1452587D03*
Y1457717D03*
X818096Y1464387D03*
X821096D03*
X826219Y1455244D03*
X818096Y1473387D03*
X821096D03*
X824096D03*
X818096Y1479587D03*
X821096D03*
X824096D03*
X818096Y1476587D03*
X821096D03*
X824096D03*
X818096Y1467387D03*
Y1470387D03*
X821096D03*
Y1467387D03*
X824096D03*
Y1470387D03*
X831457Y1639797D03*
X838503Y-77705D03*
X841756Y-77719D03*
X838500Y-72500D03*
X838488Y-75190D03*
X841741Y-75204D03*
X844781Y-76399D03*
X838500Y-69600D03*
X844781Y-65613D03*
X841756Y-64293D03*
X838503Y-64307D03*
X841741Y-66808D03*
X838488Y-66822D03*
X838606Y5374D03*
X837919Y24773D03*
Y44773D03*
X841554Y94017D03*
X837554D03*
X845563D03*
X833554D03*
X837283Y101701D03*
Y98551D03*
X837682Y110445D03*
Y115401D03*
X848084Y117557D03*
X842674Y115401D03*
Y110445D03*
X844833Y103783D03*
X840833D03*
X847768Y106186D03*
X842674Y129574D03*
Y124618D03*
X837682D03*
Y129574D03*
X848084Y131731D03*
Y122513D03*
Y136687D03*
X837751Y165393D03*
Y162793D03*
Y170493D03*
Y167993D03*
X842754Y181009D03*
X839959Y181366D03*
X836748Y181426D03*
X847929Y168697D03*
X839245Y191941D03*
X845745Y184619D03*
X839573Y184012D03*
X836956Y184221D03*
X847725Y206760D03*
X833434Y208695D03*
X835934Y211695D03*
X840992Y213859D03*
Y211359D03*
X833434Y211695D03*
X844695Y213132D03*
X837331Y229286D03*
X841024Y224712D03*
Y222212D03*
X833069Y226141D03*
X844695Y215632D03*
X835812Y236611D03*
X838312D03*
X833312D03*
X837331Y231786D03*
X833014Y248891D03*
X848939Y256535D03*
X840939D03*
X838014Y248891D03*
X835514D03*
X844939Y256303D03*
X836429Y267526D03*
X833929D03*
Y270026D03*
X836429D03*
X832966Y288190D03*
Y285690D03*
X835766Y288190D03*
Y285690D03*
X843992Y290755D03*
X839992D03*
X839573Y325327D03*
X842240Y324854D03*
X848879Y360849D03*
X846098Y408715D03*
X833185Y456309D03*
Y452309D03*
Y448309D03*
X833293Y490636D03*
Y487836D03*
X833918Y480580D03*
X834215Y484138D03*
X844227Y479882D03*
X842476Y482382D03*
X833269Y506683D03*
X835236Y533174D03*
X833953Y530621D03*
X845729Y661263D03*
X836503Y667845D03*
X839636Y666533D03*
X842640Y662814D03*
X838152Y700215D03*
X845784Y713939D03*
Y705489D03*
Y716589D03*
Y708089D03*
X835987Y713745D03*
X846484Y746701D03*
X838484D03*
X841500Y758161D03*
Y776161D03*
X842661Y769521D03*
X846000Y772079D03*
X841500Y794161D03*
Y812161D03*
X840136Y830903D03*
X836839Y831301D03*
X836894Y824401D03*
X848224Y823502D03*
X838685Y832987D03*
X835626Y843629D03*
X838189Y843459D03*
Y847490D03*
X848384Y843459D03*
X846239Y847490D03*
X835553Y835119D03*
X848384Y839459D03*
Y835459D03*
X838194Y836962D03*
X848739Y847459D03*
X837183Y855459D03*
X840234Y851459D03*
X847138Y859459D03*
X839530Y859408D03*
X848384Y863459D03*
X846336Y855459D03*
X845820Y863413D03*
X848384Y851459D03*
X843574Y859423D03*
X837434Y851459D03*
X833327Y855560D03*
X837383Y879530D03*
X837396Y871459D03*
X840234Y875459D03*
X836999Y867413D03*
X845876Y879459D03*
X848384Y867459D03*
X845820Y867413D03*
X848384Y879459D03*
Y871459D03*
Y875459D03*
X845654Y895437D03*
X833870Y881860D03*
X837290Y887490D03*
X842827Y895443D03*
X848322Y888421D03*
X848792Y896472D03*
X836066Y894955D03*
X847098Y891213D03*
X845633Y883492D03*
X845964Y887490D03*
X837276Y883459D03*
X848200Y883400D03*
X839381Y915839D03*
X841329Y926602D03*
X841274Y914060D03*
X843315Y916612D03*
X836909Y916618D03*
Y914018D03*
X839122Y939655D03*
X833683Y939579D03*
X836243D03*
X833683Y949105D03*
X836243D03*
X836423Y964669D03*
X835431Y977775D03*
X848520Y1016855D03*
X840935Y1011499D03*
X844058Y1011738D03*
X848045Y1019310D03*
X848070Y1022190D03*
X839744Y1444959D03*
Y1440859D03*
Y1448959D03*
X836704Y1448849D03*
Y1440849D03*
X836744Y1444849D03*
X845306Y1438269D03*
X846844Y1454334D03*
X837685Y1453196D03*
X839744Y1457959D03*
X846044Y1451459D03*
X839744Y1461959D03*
X834475Y1460059D03*
X850145Y3000D03*
X865059Y55513D03*
X861284Y68581D03*
X850631Y84140D03*
Y80140D03*
Y76140D03*
X861297Y80581D03*
X853379Y76587D03*
Y72615D03*
X864006Y117261D03*
X853076Y117557D03*
X856000Y103621D03*
X859191Y112083D03*
X863480Y103621D03*
X853076Y131731D03*
Y122513D03*
Y136687D03*
X851777Y180572D03*
X856460Y180527D03*
X860183Y192421D03*
X851777Y185165D03*
X856415Y185121D03*
X849017Y191941D03*
X863812Y186629D03*
X853029Y192300D03*
X853526Y206767D03*
X856026D03*
X851026D03*
X860506Y221642D03*
X852271Y228221D03*
X853656Y221708D03*
X856156D03*
X850571Y224421D03*
X851156Y221708D03*
X852822Y236189D03*
X855322D03*
X857822D03*
X852763Y248765D03*
X855263D03*
X857763D03*
X849969Y279208D03*
X852960Y268195D03*
Y270695D03*
X855460D03*
X864420Y265897D03*
X858260Y268195D03*
Y270695D03*
X861920Y265897D03*
X855460Y268195D03*
X858563Y293645D03*
Y290845D03*
X856063Y293645D03*
Y290845D03*
X858563Y288345D03*
X856063D03*
X864920Y343168D03*
X861770Y343006D03*
X854622Y359004D03*
X852569Y356712D03*
X856069Y356426D03*
X854086Y374500D03*
X858586D03*
X863086D03*
X854086Y385000D03*
X858586D03*
X864086Y384000D03*
X857973Y404867D03*
X862522Y400229D03*
X862566Y404867D03*
X857928Y400184D03*
X862020Y410899D03*
X861413Y417071D03*
X858827Y419896D03*
X858410Y413890D03*
X858767Y416685D03*
X861622Y419688D03*
X862882Y458991D03*
X854882D03*
X862882Y468791D03*
Y465991D03*
X854882D03*
Y468791D03*
X850733Y461382D03*
X850832Y473382D03*
X862882Y461791D03*
X854882D03*
X850748Y465382D03*
X861468Y491303D03*
X850738Y477382D03*
X850909Y482382D03*
X861468Y483303D03*
Y487303D03*
X858169Y495032D03*
X853900Y627700D03*
X853989Y630453D03*
Y632953D03*
X858202Y646330D03*
X851111Y656635D03*
X856145Y677887D03*
X855646Y685230D03*
X849680Y694789D03*
X858186Y701170D03*
X855646Y692710D03*
X857986Y722670D03*
X854484Y746701D03*
X849500Y761000D03*
Y758500D03*
Y763500D03*
X863443Y753254D03*
X859000Y764000D03*
Y760000D03*
X864575Y770500D03*
X849500Y779000D03*
Y776500D03*
Y781500D03*
X861425Y770500D03*
X859000Y781000D03*
Y778000D03*
X864575Y788500D03*
X849500Y797000D03*
X853282Y789887D03*
X857632Y789385D03*
X849500Y794500D03*
Y799500D03*
X861425Y788500D03*
X859000Y800000D03*
Y796000D03*
X849500Y815000D03*
X864575Y806500D03*
X861425D03*
X849500Y812500D03*
X859000Y814000D03*
X865004Y831273D03*
X864464Y828503D03*
X864575Y824500D03*
X851782Y823720D03*
X850496Y831469D03*
X861425Y824500D03*
X849500Y817500D03*
X859000Y818000D03*
X851184Y839459D03*
Y835459D03*
X859165Y848728D03*
X851239Y847459D03*
X851184Y843459D03*
X851161Y855205D03*
X851184Y863459D03*
X862114Y859479D03*
X851184Y851459D03*
X859603Y863570D03*
X859461Y859459D03*
X851184Y867459D03*
Y871459D03*
Y875459D03*
X859234Y879600D03*
X859463Y866125D03*
X851184Y879459D03*
X849267Y892567D03*
X859614Y883800D03*
Y887846D03*
X850900Y888359D03*
X850800Y883500D03*
X855524Y898505D03*
X856628Y915242D03*
X864253D03*
X849600Y915266D03*
X864253Y918042D03*
X856628D03*
X849600Y918028D03*
X849205Y924129D03*
X855867Y935540D03*
X849088Y951081D03*
X852247Y1009529D03*
X850686Y1006923D03*
X853449Y1007048D03*
X863334Y1009393D03*
X861047Y1018909D03*
X860887Y1026762D03*
X863956Y1020763D03*
X863689Y1024974D03*
X849996Y1091073D03*
X850023Y1095179D03*
X863342Y1120636D03*
X855542D03*
X858142D03*
X860842D03*
X863442Y1130336D03*
X858242D03*
X855642D03*
X860942D03*
Y1139336D03*
X863442D03*
X861119Y1148080D03*
X863619D03*
X863944Y1432359D03*
Y1429359D03*
X860944Y1432359D03*
X857944Y1429359D03*
X860944D03*
Y1426359D03*
X857944D03*
X863944D03*
X857944Y1432359D03*
X863944Y1435359D03*
Y1441359D03*
Y1438359D03*
X860944Y1441359D03*
X857944Y1435359D03*
X860944D03*
X857944Y1441359D03*
Y1438359D03*
X860944D03*
X859071Y1447459D03*
X864671D03*
X850544Y1447559D03*
X859071Y1452589D03*
Y1457719D03*
X864671D03*
X864644Y1464759D03*
X861644D03*
X855644D03*
X858644D03*
X853514Y1457510D03*
X850644Y1457359D03*
X858644Y1467759D03*
X855644Y1470759D03*
X858644D03*
X864644Y1467759D03*
Y1470759D03*
X861644Y1467759D03*
Y1470759D03*
X855644Y1467759D03*
Y1473759D03*
X858644D03*
X864644D03*
X861644D03*
X855644Y1476759D03*
X858644D03*
X864644D03*
X861644D03*
X851457Y1639797D03*
X873373Y60922D03*
X868209Y55513D03*
X870519Y60438D03*
X870395Y96738D03*
X865402Y91951D03*
X865427Y88801D03*
X876200Y94374D03*
X868344Y94351D03*
X871341Y86046D03*
X871713Y172665D03*
Y180665D03*
Y168665D03*
Y176665D03*
Y196665D03*
Y192665D03*
X871826Y186778D03*
X871745Y200864D03*
Y212864D03*
Y204864D03*
Y208864D03*
Y216864D03*
Y221864D03*
X867386Y219379D03*
X876622Y293721D03*
X876246Y302754D03*
X872050Y302644D03*
X879112Y302369D03*
X877977Y305368D03*
Y309368D03*
Y313368D03*
Y325368D03*
Y317368D03*
Y321368D03*
X873885Y340892D03*
X877977Y333368D03*
Y329368D03*
X873733Y357844D03*
X872158Y359962D03*
X871382Y373971D03*
X868086Y373750D03*
X872736Y383125D03*
X876736D03*
X880736D03*
X867586Y385000D03*
X872318Y408589D03*
X869342Y407627D03*
X866128Y417532D03*
X869342Y417399D03*
X877253Y420380D03*
X876917Y415322D03*
X879417D03*
X881190Y411619D03*
X878690D03*
X874253Y422880D03*
X877253D03*
X881271Y426952D03*
X878771D03*
X873536Y437408D03*
X876036D03*
X881036D03*
X878536D03*
X873771Y426952D03*
X876271D03*
X870882Y458991D03*
X880910Y454634D03*
Y457434D03*
Y471982D03*
Y469182D03*
Y466382D03*
X870882Y465991D03*
Y468791D03*
X880910Y460234D03*
X870882Y461791D03*
X875907Y486256D03*
X867093Y554703D03*
X866938Y549771D03*
X874649Y545296D03*
X867093Y558703D03*
Y562703D03*
Y566703D03*
Y578703D03*
Y586828D03*
Y574703D03*
X876351Y605023D03*
Y608523D03*
X879135Y632552D03*
X870137Y669461D03*
X872862Y666859D03*
X869313Y688486D03*
X872069Y700894D03*
X876286Y686970D03*
Y690970D03*
X868919Y700894D03*
X876286Y694970D03*
Y698970D03*
X877616Y749484D03*
X878610Y747171D03*
X873318Y744597D03*
X881157Y749148D03*
X874142Y748914D03*
X875473Y742056D03*
X878670Y742841D03*
X869325Y761259D03*
X871294Y771809D03*
X867000Y774000D03*
X873250Y798750D03*
X867000Y792000D03*
X875916Y808965D03*
X874925Y800746D03*
X870035Y801032D03*
X867000Y810000D03*
X879916Y808965D03*
X872700Y816615D03*
X877407Y828017D03*
X877818Y824214D03*
X876475Y830372D03*
X872628Y915242D03*
X880628D03*
X872628Y918042D03*
X876628Y915242D03*
X880628Y918042D03*
X876628D03*
X868908Y933640D03*
X867199Y949372D03*
X865830Y961600D03*
X869390Y978003D03*
X865973Y978187D03*
X874066Y977928D03*
X875391Y993796D03*
X872183Y993980D03*
X878976Y994020D03*
X871069Y1023114D03*
X878927Y1022387D03*
X878783Y1018751D03*
X872845Y1018988D03*
X866906Y1018751D03*
X866887Y1023208D03*
X875887D03*
X878887Y1026762D03*
X872887D03*
X866887D03*
X873824Y1071604D03*
X871224D03*
X876424D03*
Y1074104D03*
X871224D03*
X873824D03*
X868624Y1071604D03*
Y1074104D03*
X870057Y1091604D03*
X875257D03*
Y1089104D03*
X870057D03*
X872657D03*
X880115Y1084666D03*
X867457Y1091604D03*
Y1089104D03*
X872657Y1091604D03*
X875375Y1107647D03*
X872675D03*
X870075D03*
X867475D03*
X871364Y1120636D03*
X873964D03*
X876564D03*
X879264D03*
X875376Y1110175D03*
X872676D03*
X870076D03*
X867476D03*
X871364Y1139336D03*
X868664D03*
X879264Y1130336D03*
X876564D03*
X873964D03*
X871364D03*
X870522Y1148080D03*
X868022D03*
X871624Y1213314D03*
X874624D03*
X871624Y1221714D03*
Y1218914D03*
Y1216114D03*
X874624Y1221714D03*
Y1218914D03*
Y1216114D03*
X872440Y1230083D03*
Y1227583D03*
X871624Y1224514D03*
X874624D03*
X872440Y1234483D03*
Y1236983D03*
X878004Y1224406D03*
X872440Y1243883D03*
Y1241383D03*
Y1248283D03*
Y1250783D03*
X875700Y1299700D03*
X872600Y1300833D03*
Y1298333D03*
X872944Y1432359D03*
Y1429359D03*
Y1426359D03*
X869944Y1432359D03*
Y1429359D03*
Y1426359D03*
X866944Y1432359D03*
Y1429359D03*
Y1426359D03*
X872944Y1435359D03*
Y1441359D03*
Y1438359D03*
X869944Y1435359D03*
X866944D03*
X869944Y1441359D03*
Y1438359D03*
X866944Y1441359D03*
Y1438359D03*
X870171Y1447459D03*
X881244Y1448859D03*
Y1440859D03*
X870171Y1452589D03*
Y1457719D03*
X867644Y1464759D03*
X870644D03*
X881244Y1464859D03*
Y1453059D03*
Y1456859D03*
X875744Y1453573D03*
X867644Y1467759D03*
X870644D03*
X867644Y1470759D03*
X870644D03*
X867644Y1473759D03*
X870644D03*
X867644Y1476759D03*
X870644D03*
X881244Y1476859D03*
X871457Y1639797D03*
X883233Y147540D03*
X887005Y141247D03*
X886011Y154100D03*
X895780Y237517D03*
Y232634D03*
X893284Y233339D03*
Y236739D03*
X891383Y243203D03*
X896034Y243307D03*
X886261Y252090D03*
X885741Y261150D03*
X887148Y249670D03*
X896953Y272012D03*
X895140Y265236D03*
X885918Y289500D03*
X885989Y309368D03*
Y305368D03*
Y317368D03*
X885953Y325368D03*
X885989Y313368D03*
X885953Y329368D03*
X886026Y346584D03*
X896592Y358369D03*
Y354369D03*
X883552Y357276D03*
X896592Y362369D03*
Y366369D03*
Y370369D03*
Y374369D03*
X884736Y383125D03*
X893736D03*
X888736D03*
X891251Y387484D03*
X887266Y400158D03*
Y405158D03*
Y402658D03*
X896579Y404043D03*
X893779D03*
X889979Y405743D03*
X894844Y418983D03*
X887770Y415290D03*
X890270D03*
X891699Y423245D03*
X897344Y418983D03*
X894519Y426952D03*
X889596Y437264D03*
X896388Y437614D03*
X887096Y437264D03*
X892019Y426952D03*
X897019D03*
X890903Y454634D03*
Y457434D03*
Y469182D03*
Y471982D03*
Y466382D03*
Y460234D03*
X882907Y480350D03*
X891454Y486303D03*
X896431Y534093D03*
X882891Y536122D03*
X892931Y534093D03*
X885931D03*
X896449Y550863D03*
X893949Y550363D03*
X891449Y547363D03*
X893949D03*
X886549Y553963D03*
X892023Y570176D03*
X882949Y557363D03*
X887417Y566713D03*
X890959Y579788D03*
X890956Y588325D03*
X894015Y588253D03*
X891673Y600049D03*
X895933Y618143D03*
X887949Y608863D03*
X894449Y606363D03*
X891933Y618143D03*
X883309Y666608D03*
X892461Y666671D03*
X886304Y666650D03*
X884903Y694119D03*
Y696678D03*
X884911Y690279D03*
X889436Y715970D03*
X886836D03*
X893241Y704656D03*
X883686Y729778D03*
X889525Y722060D03*
X882098Y741565D03*
X884976Y740891D03*
X884463Y744757D03*
X881637Y744154D03*
X883126Y766124D03*
X883413Y759855D03*
X889083Y780371D03*
X888545Y785528D03*
X888514Y797602D03*
X889763Y788159D03*
X891916Y799605D03*
X884002Y797616D03*
X891916Y808965D03*
X887916Y800815D03*
X895916Y808965D03*
X883916D03*
X887916D03*
X895829Y800660D03*
X883916Y800815D03*
X897636Y839406D03*
X889178Y905619D03*
X884628Y915242D03*
Y918042D03*
X896553D03*
X892628Y915242D03*
X888628D03*
Y918042D03*
X882763Y933472D03*
X882609Y994245D03*
X888400Y994579D03*
X894660Y994330D03*
X891343Y994378D03*
X881887Y1023208D03*
X888743Y1019931D03*
X895394Y1026985D03*
X893147Y1020025D03*
X893887Y1023208D03*
X887887D03*
X890887Y1026762D03*
X884887D03*
X882779Y1074104D03*
Y1071604D03*
X887979Y1074104D03*
X885379D03*
X890579D03*
Y1071604D03*
X885379D03*
X887979D03*
X897056Y1091391D03*
X882615Y1084666D03*
X891055Y1095407D03*
X897056Y1095984D03*
X884906Y1102760D03*
X884890Y1098724D03*
X892856Y1102760D03*
X894249Y1114103D03*
X891549D03*
X888949D03*
X886349D03*
Y1123803D03*
X888949D03*
X891549D03*
X894249D03*
X895275Y1132870D03*
X892575D03*
X895547Y1145169D03*
X893190Y1208069D03*
X893328Y1212887D03*
X894887Y1227209D03*
X886888Y1263058D03*
X889388D03*
X891888D03*
X889388Y1260558D03*
X886888D03*
X891888D03*
X891003Y1292765D03*
X886926Y1298712D03*
X889729Y1295516D03*
X890738Y1311132D03*
X891107Y1314305D03*
X887342Y1314990D03*
X892244Y1449636D03*
Y1440859D03*
X889944Y1457959D03*
X889244Y1460859D03*
X895244Y1457510D03*
X889336Y1452554D03*
X893919Y1462132D03*
X889244Y1472859D03*
Y1468859D03*
X891457Y1639797D03*
X898813Y146461D03*
X903035Y141247D03*
X897715Y152367D03*
X909772Y152562D03*
X899573Y158195D03*
X898851Y231496D03*
Y238583D03*
Y245669D03*
X910977Y238583D03*
Y243307D03*
X898851Y259843D03*
X898576Y253056D03*
X910977Y252756D03*
Y257480D03*
Y248032D03*
Y262205D03*
X898851Y274016D03*
X910977Y266929D03*
X898851D03*
X898048Y269387D03*
X912786Y306697D03*
X901848Y307782D03*
Y312738D03*
X910076Y304843D03*
X905120D03*
X913057Y311046D03*
X899352Y308560D03*
Y311960D03*
X909298Y302347D03*
X905898D03*
X909417Y323302D03*
X912278Y343881D03*
X913206Y336489D03*
X912085Y332335D03*
X898533Y334498D03*
X910040Y353532D03*
X908521Y356708D03*
X908625Y359317D03*
X898869Y351114D03*
X913288Y372752D03*
X911072Y386992D03*
X897736Y383125D03*
X901747Y398492D03*
Y403492D03*
Y400992D03*
X902169Y413002D03*
Y418002D03*
Y415502D03*
X905094Y424581D03*
X902594D03*
X907594D03*
X905212Y436734D03*
X902712D03*
X907712D03*
X907173Y440581D03*
X898888Y437614D03*
X907173Y443081D03*
X910250Y457262D03*
Y454462D03*
X907450D03*
Y457262D03*
X910250Y451662D03*
X907450D03*
X910779Y471380D03*
X910250Y460062D03*
X907450D03*
X910759Y475511D03*
X903431Y534093D03*
X906996Y530707D03*
X902459Y530755D03*
X899931Y534093D03*
X899530Y530753D03*
X911630Y543998D03*
X910578Y550186D03*
X909362Y555614D03*
X898156Y554812D03*
X913853Y561487D03*
X904393Y570176D03*
X908517D03*
X898815D03*
X899407Y560019D03*
X909024Y578394D03*
X898232Y588320D03*
X909024Y586768D03*
X902635Y588305D03*
X906999Y588274D03*
X909024Y574394D03*
X898207Y599891D03*
X908730Y619120D03*
X913686D03*
X899898Y619040D03*
X904854D03*
X900676Y621536D03*
X904076D03*
X909508Y621616D03*
X912908D03*
X900753Y656925D03*
X909265Y677795D03*
X910036Y702285D03*
X912462Y687770D03*
X906886Y702285D03*
X902236Y689332D03*
Y694332D03*
X905313Y709259D03*
X910753Y715864D03*
X908699Y709387D03*
X902841Y703665D03*
X905050Y720268D03*
X910836Y721570D03*
X913858Y721289D03*
X907866Y795572D03*
X911028Y796598D03*
X913716Y800815D03*
X899916D03*
X911053Y800510D03*
X909785Y810778D03*
X903916Y810809D03*
X913716Y811954D03*
X899916Y808965D03*
X902641Y800748D03*
X907884Y829866D03*
X903817Y879770D03*
X899693Y895207D03*
X908920Y905630D03*
X904833Y915340D03*
X912628Y928101D03*
X900628Y918042D03*
X912628Y915242D03*
X908628Y918042D03*
X900628Y915242D03*
X912628Y918042D03*
X904838D03*
X908628Y915242D03*
X911355Y944909D03*
X906710Y962433D03*
X903759Y951358D03*
X913005Y969605D03*
X912690Y994350D03*
X897825Y994413D03*
X909166Y994188D03*
X909296Y1020224D03*
X909300Y1014639D03*
X897717Y1019915D03*
X899887Y1023208D03*
Y1026762D03*
X908422Y1023103D03*
X908856Y1017677D03*
X901739Y1091346D03*
X897815Y1078042D03*
X901366Y1078069D03*
X901694Y1095940D03*
X908799Y1096659D03*
X911071Y1123803D03*
X905771D03*
X903171D03*
X908371D03*
X910971Y1114103D03*
X908271D03*
X903071D03*
X905671D03*
X911699Y1129488D03*
X909041Y1126328D03*
X911641D03*
X901428Y1136426D03*
X903908Y1132870D03*
X904063Y1135946D03*
X898278Y1136426D03*
X904897Y1145169D03*
X902397D03*
X898047D03*
X913784Y1221057D03*
X901940Y1236799D03*
Y1229899D03*
Y1232399D03*
X910633Y1222799D03*
X906309Y1226647D03*
X909077Y1232724D03*
X901940Y1246199D03*
Y1243699D03*
Y1239299D03*
X899699Y1283872D03*
X904703Y1297398D03*
X910788Y1299456D03*
X906506Y1299188D03*
X902908Y1299828D03*
X911117Y1314130D03*
X902875Y1309301D03*
X905740Y1309264D03*
X908700Y1316300D03*
X911135Y1345560D03*
X904177Y1359955D03*
X899944Y1432359D03*
X908944Y1426359D03*
Y1429359D03*
Y1432359D03*
X911944Y1426359D03*
Y1429359D03*
Y1432359D03*
X905944Y1426359D03*
X899944D03*
X902944D03*
Y1429359D03*
X899944D03*
X902944Y1432359D03*
X905944Y1429359D03*
Y1432359D03*
X902944Y1438359D03*
X899944D03*
Y1441359D03*
X902944Y1435359D03*
X899944D03*
X908944Y1438359D03*
Y1441359D03*
X911944Y1438359D03*
Y1441359D03*
X902944D03*
X905944Y1438359D03*
Y1441359D03*
X908944Y1435359D03*
X911944D03*
X905944D03*
X912171Y1447459D03*
X906671D03*
X901071D03*
X912171Y1457719D03*
Y1452589D03*
X906671Y1457719D03*
X901071D03*
Y1452589D03*
X908370Y1464583D03*
X905370D03*
X899370D03*
X902370D03*
X911370D03*
X905370Y1476583D03*
X908370D03*
X902370D03*
X899370D03*
X905370Y1473583D03*
X908370D03*
X902370D03*
X899370D03*
X902370Y1467583D03*
X899370Y1470583D03*
X902370D03*
X908370Y1467583D03*
Y1470583D03*
X905370Y1467583D03*
Y1470583D03*
X899370Y1467583D03*
X911370Y1476583D03*
Y1473583D03*
Y1467583D03*
Y1470583D03*
X911457Y1639797D03*
X930145Y3000D03*
X919175Y113394D03*
X921824Y110784D03*
X923393Y102249D03*
X927393D03*
X919175Y116594D03*
X921418Y133298D03*
X929418D03*
X919175Y119594D03*
X923565Y134579D03*
X918016Y161306D03*
X915267Y157370D03*
X925359Y180347D03*
X927859D03*
X916453Y167975D03*
X925219Y188564D03*
X927719D03*
X929978Y184054D03*
X927898Y203256D03*
X925098D03*
X919606Y231000D03*
X919577Y245669D03*
Y233858D03*
X919682Y236921D03*
X919577Y240945D03*
Y259843D03*
Y255118D03*
Y250394D03*
X919729Y274580D03*
X919577Y271654D03*
X919616Y268462D03*
X919577Y264567D03*
X920142Y308501D03*
X926801Y323302D03*
X917906Y321670D03*
X922629Y336609D03*
X922198Y342051D03*
X917858Y331453D03*
X923902Y332411D03*
X916229Y336333D03*
X919629D03*
X927309Y357267D03*
X921389D03*
X915395D03*
X921847Y346622D03*
X915395Y363212D03*
X927309Y363239D03*
Y369210D03*
X921468D03*
X915395D03*
X929943Y372600D03*
X927072Y386992D03*
X919072D03*
X923072D03*
X915072D03*
X914323Y398551D03*
Y403551D03*
Y401051D03*
X914202Y418002D03*
Y413002D03*
Y415502D03*
X927563Y424445D03*
X924763D03*
X921963D03*
X927280Y436716D03*
X921680D03*
X924480D03*
X917541Y441280D03*
X927636Y452505D03*
X929050Y450316D03*
X917541Y443780D03*
X928999Y477948D03*
X920999D03*
X924999D03*
X924600Y533706D03*
X920961Y550075D03*
X915949Y563363D03*
X923453Y569578D03*
X919080Y587640D03*
X921507Y578791D03*
X919038Y579378D03*
X921217Y589216D03*
X913998Y597103D03*
X915712Y613792D03*
X925949Y612363D03*
Y608863D03*
X922626Y633772D03*
X915800Y629700D03*
X918300D03*
X915194Y666671D03*
X929690Y666593D03*
X920090Y666714D03*
X928043Y677795D03*
X917286Y679625D03*
X928353Y686342D03*
X928704Y680261D03*
X924932Y701051D03*
X921061Y715386D03*
X926961Y723797D03*
X914202Y797460D03*
X923872Y798271D03*
X916590Y800636D03*
X921790Y810965D03*
X922352Y800809D03*
X917803Y811365D03*
X927916Y800909D03*
Y817015D03*
X925228Y816934D03*
X929557Y889258D03*
X921451Y903800D03*
X920628Y928101D03*
X928628D03*
X916628D03*
X924628D03*
X920628Y918042D03*
X924628D03*
Y915242D03*
X920628D03*
X928628D03*
X916628D03*
X914193Y945318D03*
X924487Y951244D03*
X928227Y951125D03*
X921364Y951251D03*
X918648Y964717D03*
X915490Y969886D03*
X918265Y969745D03*
X923289Y965780D03*
X926796Y966297D03*
X916932Y994405D03*
X924864Y1026762D03*
X925024Y1018909D03*
X927861Y1024768D03*
X916749Y1080659D03*
Y1088659D03*
Y1084659D03*
X916992Y1076659D03*
X917110Y1101902D03*
X916875Y1098643D03*
X916749Y1104659D03*
X927598Y1120636D03*
X924898D03*
X914661Y1132612D03*
X914299Y1129488D03*
X914241Y1126328D03*
X924919Y1130336D03*
X927619D03*
X924919Y1139336D03*
X927419D03*
X925097Y1147708D03*
X927597D03*
X914637Y1210568D03*
Y1214838D03*
X927146Y1328597D03*
Y1323641D03*
X924650Y1327819D03*
Y1324419D03*
X914033Y1345613D03*
X927193Y1361547D03*
X931159Y1379427D03*
X920360Y1387039D03*
X920255Y1383264D03*
X931199Y1371951D03*
X931159Y1390827D03*
Y1406027D03*
X914944Y1426359D03*
Y1429359D03*
Y1432359D03*
Y1438359D03*
Y1441359D03*
Y1435359D03*
X921498Y1446692D03*
X914370Y1464583D03*
X925697Y1460109D03*
X917744Y1453573D03*
X920244Y1451605D03*
X919285Y1456226D03*
X914370Y1476583D03*
Y1473583D03*
Y1467583D03*
Y1470583D03*
X924803Y1474743D03*
X925435Y1478114D03*
X926044Y1545370D03*
Y1542370D03*
X929094Y1542353D03*
Y1545353D03*
X926041Y1554503D03*
Y1551503D03*
Y1548503D03*
Y1557503D03*
Y1560503D03*
X941129Y4469D03*
X942490Y24773D03*
Y44773D03*
X945011Y95111D03*
X944961Y116497D03*
X934410Y109172D03*
X936417Y106495D03*
X937410Y109172D03*
X940161Y116497D03*
X931144Y116594D03*
X936417Y102495D03*
X940161Y123584D03*
X944961D03*
X940161Y130670D03*
X944961D03*
X931144Y119594D03*
X940161Y137757D03*
X944961D03*
X936151Y146012D03*
X938057Y141228D03*
X936151Y142862D03*
X940945Y150847D03*
X930359Y180347D03*
X945406D03*
X940406D03*
X942906D03*
X931407Y192009D03*
X933907D03*
X944424Y186919D03*
X944760Y191977D03*
X942260D03*
X940487Y195680D03*
X942987D03*
X944424Y184419D03*
X934411Y202141D03*
X931698Y201556D03*
X934411Y207141D03*
X934477Y211491D03*
X934411Y204641D03*
X938125Y230891D03*
X942805Y223860D03*
X936369Y221292D03*
X936395Y218142D03*
X940158Y245707D03*
X933403Y245507D03*
X946064Y252998D03*
X941845Y278968D03*
X945018Y276051D03*
X943183Y281652D03*
X939606Y310521D03*
X930727Y302571D03*
X937000Y312284D03*
X939653Y317474D03*
X940924Y328959D03*
X936608Y326058D03*
X945120Y326441D03*
X937000Y315684D03*
X932388Y330517D03*
X930398Y342050D03*
X936453Y345336D03*
X945599Y345383D03*
X940972Y338238D03*
X932622Y336817D03*
X943663Y355674D03*
X944694Y352192D03*
X934464Y358618D03*
X944900Y363700D03*
X938499Y362202D03*
X940600Y370600D03*
X934047Y369160D03*
X931072Y386992D03*
X941872Y440942D03*
X941505Y463442D03*
X939827Y531104D03*
X939992Y536726D03*
X936653Y526836D03*
X944351Y534211D03*
X939992Y527726D03*
Y540726D03*
Y552726D03*
Y548726D03*
X931627Y561578D03*
Y565578D03*
Y557641D03*
Y569578D03*
X943825Y581222D03*
X931620Y584417D03*
X931627Y581578D03*
Y577578D03*
Y573578D03*
X933725Y585936D03*
X943825Y591215D03*
X931594Y599420D03*
X931647Y593271D03*
X931578Y590669D03*
X933741Y598087D03*
Y594687D03*
X933725Y589336D03*
X944296Y611071D03*
X941859Y621311D03*
Y629311D03*
X943181Y632536D03*
X945434Y634325D03*
X941859Y625311D03*
X946128Y666522D03*
X935281Y680945D03*
X931244Y720471D03*
X936026Y730600D03*
Y727450D03*
X933974Y719371D03*
X945626Y789761D03*
X942676Y789286D03*
X941916Y808965D03*
X944916D03*
X932000Y831000D03*
X931916Y817015D03*
X942858Y819430D03*
X945736Y819397D03*
X935124Y831382D03*
X935262Y825135D03*
X932418D03*
X940716Y840074D03*
X944297Y839975D03*
X933021Y840893D03*
X933054Y843804D03*
X937200Y841000D03*
X936450Y858327D03*
X937551Y860801D03*
X932770Y878233D03*
X935765Y878317D03*
X934928Y871727D03*
X932319Y871626D03*
X938729Y874396D03*
X942634Y886520D03*
X933700Y887508D03*
X932300Y890200D03*
X944839Y902400D03*
X938188Y900853D03*
X930800Y904840D03*
X941592Y900908D03*
X932628Y928101D03*
X936628D03*
X940497D03*
X936628Y915242D03*
X940628D03*
X932628D03*
X936628Y918042D03*
X932628D03*
X936371Y951484D03*
X940716Y951733D03*
X946363Y951179D03*
X935255Y962725D03*
X940015Y1020176D03*
X934911Y1023579D03*
X945864Y1023208D03*
X930864Y1026762D03*
X936864D03*
X942864D03*
X939864Y1023208D03*
X930864D03*
X930883Y1018751D03*
X936822Y1018988D03*
X942760Y1018751D03*
X932289Y1074182D03*
Y1071682D03*
X937489Y1074182D03*
X934889D03*
X940089D03*
Y1071682D03*
X934889D03*
X937489D03*
X944092Y1084666D03*
X931628Y1091409D03*
Y1088909D03*
X936828Y1091409D03*
X934228D03*
X939428D03*
Y1088909D03*
X934228D03*
X936828D03*
X943241Y1120636D03*
X940541D03*
X937941D03*
X935341D03*
X937941Y1130336D03*
X940541D03*
X943241D03*
X932641Y1139336D03*
X935341Y1130336D03*
Y1139336D03*
X934500Y1147708D03*
X932000D03*
X935601Y1221714D03*
Y1218914D03*
Y1216114D03*
Y1213314D03*
X938601Y1221714D03*
Y1218914D03*
Y1216114D03*
Y1213314D03*
X936417Y1234483D03*
Y1236983D03*
Y1230083D03*
Y1227583D03*
X935601Y1224514D03*
X938601D03*
X941981Y1224406D03*
X936417Y1243883D03*
Y1241383D03*
Y1248283D03*
Y1250783D03*
X933254Y1308273D03*
X940848Y1310181D03*
X943891Y1306608D03*
X931137Y1375878D03*
X931159Y1383227D03*
X939559Y1398427D03*
X931159Y1394627D03*
Y1387027D03*
Y1398427D03*
Y1402227D03*
X939559D03*
X943725Y1430744D03*
Y1427744D03*
X934725Y1430744D03*
X940725Y1427744D03*
Y1430744D03*
X934725Y1427744D03*
X937725D03*
Y1430744D03*
X943725Y1433744D03*
Y1439744D03*
Y1436744D03*
X940725Y1433744D03*
Y1439744D03*
Y1436744D03*
X934725Y1433744D03*
X937725D03*
X934725Y1439744D03*
X937725D03*
X934725Y1436744D03*
X937725D03*
X930441Y1455039D03*
Y1458039D03*
Y1464039D03*
Y1461039D03*
Y1467039D03*
X937671Y1488139D03*
X938670Y1510528D03*
X941270D03*
Y1505328D03*
X938670D03*
X940170Y1507928D03*
X943870Y1510528D03*
Y1505328D03*
X945370Y1507928D03*
X942770D03*
X935094Y1542353D03*
X932094D03*
X935094Y1545353D03*
X932094D03*
X938094Y1542353D03*
Y1545353D03*
X941094Y1542353D03*
X944094D03*
X941094Y1545353D03*
X944094D03*
X931457Y1639797D03*
X956448Y-30304D03*
Y-33204D03*
X956460Y-35982D03*
X953207Y-35996D03*
X956445Y-38497D03*
X953192Y-38511D03*
X950167Y-37191D03*
X953192Y-25085D03*
X956445Y-25099D03*
X950167Y-26405D03*
X953207Y-27600D03*
X956460Y-27614D03*
X949811Y53597D03*
X960623Y82984D03*
Y77784D03*
Y80384D03*
Y75184D03*
Y85584D03*
X960161Y95236D03*
Y102323D03*
X960413Y109410D03*
Y116496D03*
X947461Y116497D03*
X952161Y116496D03*
Y109410D03*
Y102323D03*
X947461Y109410D03*
X949380Y106561D03*
X961638Y130670D03*
X947461D03*
X952161D03*
Y123583D03*
X947461D03*
X961633Y137756D03*
X952161D03*
X947906Y180347D03*
X949359Y198710D03*
X947424Y187219D03*
X949443Y208206D03*
X951040Y223885D03*
X947040D03*
X951278Y250583D03*
X946482Y255940D03*
X949974Y291554D03*
X947733Y319680D03*
X949579Y330517D03*
X949813Y336817D03*
X956348Y356371D03*
X952170Y356131D03*
X958823Y362802D03*
X954888Y369513D03*
X948400Y370045D03*
X960376Y392807D03*
X956863Y451466D03*
X950315Y464851D03*
X959816Y472905D03*
X955816Y473419D03*
X949823Y487982D03*
X949876Y478486D03*
X949823Y483982D03*
X962563Y485128D03*
X954182Y481467D03*
X949823Y499982D03*
X958974Y504825D03*
X956474D03*
X953974D03*
X949823Y491982D03*
Y495982D03*
X958915Y517401D03*
X956415D03*
X953915D03*
X959466Y522569D03*
Y525369D03*
X958081Y531882D03*
X955581D03*
X961166Y529169D03*
X952531Y531948D03*
X960581Y531882D03*
X953816Y555194D03*
X951016D03*
X958016D03*
X960816D03*
X953816Y571194D03*
X951016D03*
X953816Y563194D03*
X951016D03*
X958016D03*
X960816D03*
Y571194D03*
X958016D03*
X946625Y581222D03*
X949425D03*
X959573D03*
X962373D03*
X949425Y591215D03*
X946625D03*
X959573D03*
X962373D03*
X948427Y611091D03*
X962545Y607762D03*
X959745D03*
Y610562D03*
X962545D03*
X950865Y641817D03*
X949137Y666660D03*
X954526Y666671D03*
X957551Y698251D03*
X947556Y699550D03*
X954023Y725336D03*
X951195Y727165D03*
X952681Y735256D03*
X951151Y730111D03*
X959950Y734178D03*
X956323Y748412D03*
X957474Y764426D03*
X955086Y779798D03*
X956017Y770300D03*
X957500Y780800D03*
X956051Y793937D03*
X955076Y784861D03*
X950475Y789361D03*
X955225Y788984D03*
X951461Y812223D03*
X951791Y808121D03*
X947735Y824921D03*
X957379Y826586D03*
X954760Y826734D03*
X951708Y818894D03*
X956239Y829577D03*
X948935Y835800D03*
X954700Y842700D03*
X960100Y846665D03*
X954700Y837700D03*
X961175Y838525D03*
X947735Y854935D03*
X953091Y857440D03*
X953217Y861440D03*
X955967Y860376D03*
X946700Y849200D03*
X955850Y862902D03*
X957900Y856300D03*
X950251Y874268D03*
X950291Y870240D03*
Y866240D03*
X953145Y874240D03*
X950300Y877800D03*
X953240Y876834D03*
X952738Y886624D03*
X953587Y902814D03*
X950567Y927654D03*
X961479Y927643D03*
X954567Y927654D03*
X947029Y915242D03*
X959545Y918306D03*
X946642Y991361D03*
X961671Y991564D03*
X953671D03*
X949671D03*
X948864Y1026762D03*
X954864D03*
X951864Y1023208D03*
X957864D03*
X957678Y1018555D03*
X961208Y1018592D03*
X960636Y1021917D03*
X959371Y1026985D03*
X948975Y1021325D03*
X951956Y1071604D03*
X949356D03*
X954556D03*
Y1074104D03*
X949356D03*
X951956D03*
X946756Y1071604D03*
Y1074104D03*
X961033Y1091391D03*
X946592Y1084666D03*
X948883Y1102760D03*
X948867Y1098724D03*
X955032Y1095407D03*
X961033Y1095984D03*
X956833Y1102760D03*
X950326Y1114103D03*
Y1123803D03*
X952926D03*
X955526D03*
Y1114103D03*
X958226D03*
X952926D03*
X958226Y1123803D03*
X956552Y1132870D03*
X959252D03*
X962255Y1136426D03*
X962024Y1145169D03*
X959524D03*
X957305Y1212887D03*
X957167Y1208069D03*
X958864Y1227209D03*
X950865Y1263058D03*
X953365D03*
X955865D03*
X953365Y1260558D03*
X950865D03*
X955865D03*
X948259Y1295965D03*
X949970Y1321749D03*
X952070Y1367717D03*
X949070D03*
X948832Y1371654D03*
X951832D03*
X952561Y1383465D03*
X952417Y1379528D03*
X949469D03*
X949385Y1375591D03*
X952385D03*
X952514Y1391339D03*
X952716Y1387402D03*
X952180Y1407087D03*
X950239Y1409555D03*
X948235Y1406262D03*
X946725Y1427744D03*
Y1430744D03*
X949725D03*
Y1427744D03*
X960883Y1427997D03*
Y1430997D03*
X946725Y1433744D03*
X949725D03*
X946725Y1439744D03*
X949725D03*
X946725Y1436744D03*
X949725D03*
X960883Y1433997D03*
Y1436997D03*
Y1439997D03*
X952695Y1444139D03*
X956238Y1455139D03*
Y1458139D03*
Y1461139D03*
Y1464139D03*
X952676Y1461039D03*
Y1464039D03*
Y1458039D03*
Y1455039D03*
X956238Y1467139D03*
Y1469902D03*
X952676Y1467039D03*
X946470Y1510528D03*
Y1505328D03*
X956035Y1545333D03*
X959035D03*
X953035D03*
X950035D03*
X959035Y1542333D03*
X956035D03*
X953035D03*
X950035D03*
X947094Y1545353D03*
Y1542353D03*
X951457Y1639797D03*
X978036Y-77691D03*
Y-64265D03*
X978051Y-75176D03*
X975011Y-76371D03*
Y-65585D03*
X978051Y-66780D03*
X969811Y53597D03*
X963177Y92849D03*
X970094Y95236D03*
X978271Y109410D03*
Y102323D03*
X970137Y103037D03*
X970271Y116496D03*
Y109410D03*
X978271Y116496D03*
X970271Y130670D03*
Y123583D03*
X978271Y130670D03*
Y123583D03*
X963360Y121459D03*
X966347Y137756D03*
X978271D03*
X978051Y162368D03*
X968906Y207978D03*
Y212978D03*
Y215478D03*
Y210478D03*
Y223726D03*
Y228726D03*
Y231226D03*
Y226226D03*
X970865Y264068D03*
X973365D03*
X972160Y258880D03*
X974952Y293796D03*
X972452D03*
X976763Y307303D03*
X972147Y323681D03*
X977150Y328472D03*
X973338Y345018D03*
X977150Y335472D03*
Y331972D03*
Y338972D03*
X975631Y346612D03*
X969623Y405614D03*
X971721Y407762D03*
X968348Y402369D03*
X963577Y426391D03*
X975932Y437508D03*
X971932D03*
X971826Y430187D03*
X966694Y427599D03*
X968462Y429368D03*
X962769Y458466D03*
X973695Y448874D03*
X969109Y449352D03*
X970840Y457339D03*
X968340D03*
X962816Y442919D03*
X967816Y472905D03*
X972397Y472954D03*
X970840Y459839D03*
Y462339D03*
X968340D03*
Y459839D03*
X963816Y472905D03*
X976397Y473045D03*
X965412Y485138D03*
X969297Y478625D03*
Y475825D03*
X970997Y482425D03*
X970412Y485138D03*
X967912D03*
X976873Y491214D03*
X973843Y500086D03*
X978723Y504699D03*
X976223D03*
X973723D03*
X976873Y493714D03*
X978425Y516979D03*
X973425D03*
X974406Y521804D03*
X975925Y516979D03*
X978668Y527449D03*
X974406Y524304D03*
X970713Y531378D03*
Y528878D03*
X970745Y539731D03*
X967042Y537658D03*
X964012Y546830D03*
X970745Y542231D03*
X978303Y541895D03*
X975803D03*
X967042Y540458D03*
X975503Y544895D03*
X978581Y572975D03*
Y582747D03*
X965173Y581222D03*
Y591215D03*
X976962Y608311D03*
X976027Y620653D03*
Y617853D03*
X968145Y610562D03*
X965345Y607762D03*
Y610562D03*
X968145Y607762D03*
X977857Y605443D03*
X973857D03*
X967302Y627948D03*
X969491Y629362D03*
X978865Y642184D03*
X963187Y667620D03*
X973138Y667621D03*
X966797Y667653D03*
X970197D03*
X965774Y706907D03*
X973712Y722064D03*
X968589Y722434D03*
X970839Y729923D03*
X965042Y722234D03*
X971081Y722637D03*
X978352Y730766D03*
X963950Y734178D03*
X978059Y747438D03*
X965983Y763567D03*
X966127Y776382D03*
X976764Y786563D03*
X968094Y799792D03*
X976186Y789819D03*
X964070Y807686D03*
Y813006D03*
X977218Y802178D03*
X967562Y802982D03*
X964036Y818961D03*
X968319Y826191D03*
X978214Y821224D03*
X967337Y828901D03*
X976635Y835018D03*
X976800Y838011D03*
X974282D03*
X976902Y847135D03*
X970040Y842903D03*
X969309Y839334D03*
X971808Y851242D03*
X975925Y854783D03*
X967510Y868971D03*
X978201Y897500D03*
X971144Y908972D03*
X972278Y934429D03*
X968507Y937615D03*
X971443Y938828D03*
X969806Y993033D03*
X965671Y991564D03*
X963864Y1026762D03*
Y1023208D03*
X965716Y1091346D03*
X965671Y1095940D03*
X972776Y1096659D03*
X967148Y1123803D03*
X969748D03*
X969648Y1114103D03*
X967048D03*
X972348Y1123803D03*
X975048D03*
X972248Y1114103D03*
X974948D03*
X965405Y1136426D03*
X970485Y1132870D03*
X967885D03*
X968874Y1145169D03*
X966374D03*
X978614Y1210568D03*
Y1214838D03*
X978169Y1221268D03*
X965917Y1236799D03*
Y1229899D03*
Y1232399D03*
Y1246199D03*
Y1243699D03*
Y1239299D03*
X978727Y1284908D03*
X978857Y1360945D03*
X963883Y1430997D03*
Y1427997D03*
X966883Y1430997D03*
Y1427997D03*
X969883D03*
Y1430997D03*
X975883Y1427997D03*
Y1430997D03*
X972883D03*
Y1427997D03*
X963883Y1433997D03*
X966883D03*
X969883D03*
X963883Y1436997D03*
Y1439997D03*
X966883Y1436997D03*
Y1439997D03*
X969883Y1436997D03*
Y1439997D03*
X975883Y1433997D03*
X972883D03*
X975883Y1436997D03*
X972883D03*
X975883Y1439997D03*
X972883D03*
X971467Y1509515D03*
X974067D03*
X972567Y1512115D03*
X969967D03*
X976667Y1509515D03*
X977767Y1506915D03*
X975167D03*
X969967D03*
X972567D03*
X975167Y1512115D03*
X977767D03*
X971140Y1514693D03*
X968540D03*
X973740D03*
X976340D03*
X977547Y1546081D03*
X974547D03*
X971547D03*
X971457Y1639797D03*
X981289Y-77677D03*
Y-64279D03*
X981292Y-69484D03*
Y-72384D03*
X981304Y-75162D03*
Y-66794D03*
X988606Y5374D03*
X987919Y24773D03*
Y44773D03*
X978958Y85193D03*
Y82593D03*
Y77393D03*
Y74793D03*
Y79993D03*
X983554Y94017D03*
X987554D03*
X991554D03*
X987283Y101701D03*
Y98551D03*
X987682Y115401D03*
X992674D03*
Y110445D03*
X987682D03*
X994833Y103783D03*
X990833D03*
X981029Y104249D03*
Y107649D03*
X992674Y124618D03*
X987682D03*
Y129574D03*
X992674D03*
X985595Y147540D03*
X989367Y141247D03*
X985595Y151540D03*
X980651Y162368D03*
X987751Y162793D03*
Y165393D03*
Y167993D03*
Y170493D03*
X989959Y181366D03*
X986748Y181426D03*
X992754Y181009D03*
X989245Y191941D03*
X986956Y184221D03*
X989573Y184012D03*
X994695Y213132D03*
X979362Y208213D03*
Y210713D03*
Y213213D03*
X983434Y208695D03*
X985934Y211695D03*
X990992Y213859D03*
Y211359D03*
X983434Y211695D03*
X987331Y229286D03*
X991024Y224712D03*
Y222212D03*
X983069Y226141D03*
X979362Y231461D03*
Y228961D03*
Y226461D03*
Y215713D03*
X994695Y215632D03*
X987331Y231786D03*
X985812Y236611D03*
X988312D03*
X983312D03*
X983014Y248891D03*
X988014D03*
X985514D03*
X990939Y256535D03*
X994939Y256303D03*
X986429Y270026D03*
X983929D03*
X981129D03*
X983929Y267526D03*
X986429D03*
X981129D03*
X985766Y288190D03*
X982966D03*
X985766Y285690D03*
X982966D03*
X980466Y288190D03*
Y285690D03*
X993992Y290755D03*
X989992D03*
X993132Y310942D03*
X993243Y321325D03*
X987055Y320273D03*
X993920Y335454D03*
X993420Y337954D03*
X990420Y340454D03*
Y337954D03*
X992045Y366559D03*
X984045D03*
X988045D03*
X980045D03*
X991392Y409230D03*
X979932Y437508D03*
X982792Y447269D03*
X982670Y450201D03*
X980397Y473045D03*
X985303Y464652D03*
Y462152D03*
Y459652D03*
X987803Y464652D03*
Y462152D03*
Y459652D03*
X992206Y478586D03*
Y481086D03*
X980544Y482134D03*
Y484634D03*
X992206Y476086D03*
X988499Y480705D03*
X983989Y475946D03*
Y478446D03*
X992206Y491133D03*
Y498633D03*
X988134Y495151D03*
X985634D03*
X980576Y492987D03*
Y495487D03*
X988134Y498151D03*
X992206Y493633D03*
Y496133D03*
X982375Y522129D03*
X989936Y519531D03*
X987436D03*
X982436D03*
X984936D03*
X982375Y527129D03*
Y524629D03*
X989068Y532949D03*
X982375Y537877D03*
X992306Y555897D03*
Y553297D03*
X989888Y548366D03*
X987388D03*
X982388D03*
X984888D03*
X982375Y542877D03*
Y545377D03*
Y540377D03*
X981795Y572842D03*
X992306Y561097D03*
Y563697D03*
Y558497D03*
X986301Y570686D03*
X989096Y570478D03*
X985903Y579475D03*
X985357Y585507D03*
X989950D03*
X989513Y576484D03*
X989156Y573689D03*
X986510Y573303D03*
X985401Y590145D03*
X989995Y590190D03*
X981857Y597232D03*
X989857Y605443D03*
X983843Y619513D03*
Y616713D03*
Y613913D03*
X993857Y605443D03*
X981857Y605637D03*
X983843Y633205D03*
Y636005D03*
X980703Y625013D03*
X983843Y638805D03*
X983712Y722064D03*
X984307Y748432D03*
X981876Y745179D03*
X988371Y764143D03*
X983786Y765647D03*
X985030Y781204D03*
X988329Y781445D03*
X991990Y773974D03*
X984963Y785387D03*
X979313Y814316D03*
X987501Y812573D03*
X987903Y818645D03*
X979203Y829159D03*
X982300Y821200D03*
X993061Y833135D03*
X979203Y837159D03*
X989700Y846500D03*
X987202Y846395D03*
X987319Y843589D03*
X979203Y833159D03*
X989800Y843900D03*
X987200Y848940D03*
X988820Y858903D03*
X990457Y852043D03*
X983269Y853883D03*
X981700Y856300D03*
X980529Y879097D03*
X988231Y878203D03*
X984892Y868720D03*
X979891Y876589D03*
X987790Y896596D03*
X995133Y888503D03*
X988054Y888283D03*
X990300Y897500D03*
X982787Y899757D03*
X979592Y902849D03*
X982783Y909995D03*
X979498Y907500D03*
X989311Y920364D03*
X983227Y968565D03*
X988461Y1013841D03*
X988240Y1020015D03*
Y1016923D03*
Y1023968D03*
X980726Y1080659D03*
Y1088659D03*
X984909Y1081071D03*
X983751Y1078675D03*
X980969Y1076659D03*
X980726Y1084659D03*
X981087Y1101902D03*
X980852Y1098643D03*
X980726Y1104659D03*
Y1092664D03*
X986645Y1108465D03*
X989513Y1097683D03*
X995009Y1131223D03*
X991763Y1140378D03*
Y1128378D03*
Y1134378D03*
X984558Y1140774D03*
X988112Y1137774D03*
X984558Y1128774D03*
Y1134774D03*
X987804Y1131619D03*
X988389Y1302558D03*
X984817Y1303297D03*
X979001Y1288925D03*
X990613Y1324248D03*
Y1327048D03*
X993413Y1324248D03*
Y1327048D03*
X990501Y1320756D03*
X981857Y1360945D03*
X988784Y1361974D03*
X980501Y1369685D03*
X983501D03*
X980139Y1381496D03*
X980166Y1373622D03*
X980203Y1377559D03*
X980047Y1397245D03*
X980092Y1389370D03*
X980139Y1393308D03*
X978944Y1413859D03*
X981944D03*
X984136Y1401636D03*
X987136D03*
X986949Y1430997D03*
Y1427997D03*
X983949D03*
X989949Y1430997D03*
Y1427997D03*
X983949Y1430997D03*
X992949Y1427997D03*
Y1430997D03*
X986949Y1433997D03*
X983949D03*
X989949D03*
X992949D03*
X986949Y1436997D03*
X983949D03*
X986949Y1439997D03*
X983949D03*
X989949Y1436997D03*
Y1439997D03*
X992949Y1436997D03*
Y1439997D03*
X978934Y1444392D03*
X979538Y1464039D03*
Y1461039D03*
Y1458039D03*
Y1455039D03*
Y1467039D03*
Y1469802D03*
X978987Y1489832D03*
X979267Y1509515D03*
X984467D03*
X981867D03*
X985567Y1512115D03*
Y1506915D03*
X980367D03*
X982967D03*
Y1512115D03*
X980367D03*
X989667Y1509515D03*
X992267D03*
X987067D03*
X988167Y1512115D03*
X990767D03*
Y1506915D03*
X988167D03*
X984140Y1514693D03*
X981540D03*
X978940D03*
X986740D03*
X989340D03*
X986773Y1546081D03*
X983773D03*
X980773D03*
X991457Y1639797D03*
X1005256Y-48539D03*
X1002003D03*
X1005241Y-46024D03*
X1001988D03*
X1008281Y-47219D03*
X1002000Y-40834D03*
X1005256Y-38239D03*
X1002003Y-38225D03*
X1002000Y-43334D03*
X1005241Y-35724D03*
X1002000Y-32720D03*
X1001988Y-35710D03*
X1002000Y-30120D03*
X1008281Y-36919D03*
X1011187Y-43526D03*
Y-40126D03*
X1005256Y-25113D03*
X1002003Y-25027D03*
X1005241Y-27628D03*
X1001988Y-27542D03*
X1008281Y-26433D03*
X1007508Y3000D03*
X1011284Y68581D03*
X1000631Y84140D03*
Y76140D03*
Y80140D03*
X1011297Y80581D03*
X1003379Y72615D03*
Y76587D03*
X995563Y94017D03*
X1006000Y103621D03*
X1003076Y117557D03*
X998084D03*
X997768Y106186D03*
X1009191Y112083D03*
X1003076Y122513D03*
Y131731D03*
X998084Y122513D03*
Y131731D03*
X1001175Y146461D03*
X1003076Y136687D03*
X998084D03*
X1000077Y152367D03*
X1001777Y180572D03*
X1006460Y180527D03*
X997929Y168697D03*
X1010183Y192421D03*
X1001777Y185165D03*
X1006415Y185121D03*
X995745Y184619D03*
X999017Y191941D03*
X1003029Y192300D03*
X997725Y206760D03*
X1003526Y206767D03*
X1006026D03*
X1001026D03*
X1010291Y199582D03*
X1002271Y228221D03*
Y231021D03*
X1010506Y221642D03*
X1003656Y221708D03*
X1006156D03*
X1000571Y224421D03*
X1001156Y221708D03*
X1002822Y236189D03*
X1005322D03*
X1007822D03*
X998939Y256535D03*
X1002763Y248765D03*
X1005263D03*
X1007763D03*
X999826Y278734D03*
X1008260Y268195D03*
X1005460D03*
X1002960D03*
X1008260Y270695D03*
X1002960D03*
X1005460D03*
X1008563Y293645D03*
X1006063D03*
Y290845D03*
Y288345D03*
X1008563Y290845D03*
Y288345D03*
X1004635Y300276D03*
X1008635D03*
X1000698D03*
X1010499Y309062D03*
X998667Y322239D03*
X1004544Y318050D03*
X1004933Y314535D03*
X997921Y333654D03*
X1009770Y344486D03*
X997020Y345354D03*
X1003076Y332496D03*
X1000420Y348954D03*
Y353954D03*
X996024Y352132D03*
X1001825Y581659D03*
X997857Y605443D03*
X995913Y619758D03*
Y616958D03*
Y614158D03*
X1001857Y605443D03*
X995913Y633450D03*
Y636250D03*
X1003900Y628700D03*
X1001605Y627605D03*
X1005800Y637600D03*
X1002883Y622521D03*
X995913Y639050D03*
X1001676Y678015D03*
X1011185Y724519D03*
X1009562Y722438D03*
X1008342Y761735D03*
X1003539Y762632D03*
X1003990Y765899D03*
X1002751Y757169D03*
X1002834Y777394D03*
X1007027Y792973D03*
X998376Y810970D03*
X999825Y819488D03*
X1002699Y819475D03*
X1002887Y834342D03*
X1000369D03*
X1011144Y844340D03*
X1010977Y841737D03*
X1004577Y853679D03*
X1005607Y874859D03*
Y877859D03*
X1004713Y871389D03*
X998313Y888295D03*
X1002930Y906785D03*
X1004953Y923995D03*
X1008935Y924007D03*
X1010119Y933822D03*
X1004994Y955372D03*
X1007919Y948822D03*
X1011019D03*
X1004719D03*
X1006222Y980337D03*
X1010009Y998100D03*
X1005301Y1006560D03*
X999879Y998507D03*
X999700Y1018400D03*
X1008759Y1023900D03*
X995317Y1137378D03*
X996213Y1324248D03*
Y1327048D03*
X1009333Y1346693D03*
Y1343293D03*
X1008312Y1363533D03*
X1008452Y1376752D03*
X1008483Y1372734D03*
X1008387Y1380797D03*
X998600Y1373400D03*
X997401Y1381200D03*
X1007850Y1368835D03*
X1006211Y1397662D03*
X1009338Y1391597D03*
Y1388597D03*
X1008138Y1407186D03*
Y1409986D03*
X1005338Y1407186D03*
Y1409986D03*
X1008138Y1415586D03*
Y1412786D03*
X1005338Y1415586D03*
Y1412786D03*
X1008138Y1418386D03*
X1005338D03*
X998949Y1427997D03*
Y1430997D03*
X995949D03*
Y1427997D03*
X1009981Y1431097D03*
Y1428097D03*
X1006981D03*
Y1431097D03*
X998949Y1433997D03*
X995949D03*
X998949Y1436997D03*
X995949D03*
X998949Y1439997D03*
X995949D03*
X1009981Y1434097D03*
X1006981D03*
X1009981Y1437097D03*
X1006981D03*
X1009981Y1440097D03*
X1006981D03*
X1002194Y1444392D03*
X1002538Y1463939D03*
Y1460939D03*
Y1457939D03*
Y1454939D03*
Y1466939D03*
Y1469702D03*
X1008549Y1509815D03*
X1007049Y1507215D03*
X1011149Y1509815D03*
X1009649Y1507215D03*
Y1512415D03*
X1007049D03*
X1008222Y1514993D03*
X1005622D03*
X1010822D03*
X1010606Y1547824D03*
X1007611Y1561247D03*
Y1558247D03*
Y1555247D03*
Y1552247D03*
X1004611Y1561247D03*
Y1558247D03*
Y1555247D03*
Y1552247D03*
X1010659Y1568771D03*
Y1565771D03*
X1010653Y1571669D03*
X1013683Y-44304D03*
Y-39348D03*
Y-29348D03*
Y-34304D03*
X1027508Y3000D03*
X1023373Y60922D03*
X1018209Y55513D03*
X1015059D03*
X1020519Y60438D03*
X1020254Y97068D03*
X1015402Y91951D03*
X1026200Y94374D03*
X1015427Y88801D03*
X1018344Y94351D03*
X1021341Y86046D03*
X1014006Y117261D03*
X1021537Y113394D03*
X1025755Y102249D03*
X1024186Y110784D03*
X1021537Y116594D03*
X1024289Y130898D03*
X1021537Y119594D03*
X1025927Y134579D03*
X1020378Y161306D03*
X1012134Y152562D03*
X1017629Y157370D03*
X1021713Y180665D03*
Y172665D03*
Y176665D03*
Y168665D03*
X1027055Y195176D03*
X1013812Y186629D03*
X1021713Y196665D03*
Y192665D03*
X1026915Y203393D03*
X1021745Y212864D03*
Y200864D03*
Y204864D03*
Y208864D03*
Y221864D03*
Y216864D03*
X1026794Y218085D03*
X1017386Y219379D03*
X1023502Y252371D03*
Y248371D03*
X1014420Y265897D03*
X1011920D03*
X1027216Y289440D03*
X1022604Y290262D03*
X1016635Y300276D03*
X1012635D03*
X1025749D03*
X1020635D03*
X1022435Y312865D03*
X1021848Y310396D03*
X1013354Y323362D03*
X1021451Y322879D03*
X1026032Y322906D03*
X1013327Y327453D03*
X1013318Y333190D03*
X1022845Y340944D03*
X1013313Y339909D03*
X1015195Y428305D03*
X1012188Y443421D03*
X1018238Y678647D03*
X1018155Y684132D03*
X1015659Y679654D03*
Y683054D03*
X1025116Y698332D03*
X1022937Y691421D03*
X1024932Y717856D03*
X1014641Y724436D03*
X1012851Y722417D03*
X1026916Y719769D03*
X1013486Y750773D03*
X1015804Y760454D03*
X1024684Y756485D03*
X1026090Y770943D03*
X1021895Y771974D03*
X1019375Y783056D03*
X1018044Y793592D03*
X1014064Y793660D03*
X1015800Y807535D03*
X1014587Y802788D03*
X1025859Y802275D03*
X1013821Y813520D03*
X1014781Y810319D03*
X1016320Y828481D03*
X1021895Y818974D03*
X1020703Y833659D03*
X1025219Y842155D03*
X1025239Y845070D03*
X1020703Y837659D03*
X1013918Y851306D03*
X1016973Y877196D03*
X1016574Y874537D03*
X1016798Y890299D03*
X1012842Y910685D03*
X1026340Y917761D03*
X1018419Y917575D03*
X1019519Y937922D03*
X1023319D03*
X1017619Y932122D03*
X1014719Y938322D03*
X1027319D03*
X1023519Y951522D03*
X1018919D03*
X1014009Y980356D03*
X1018009D03*
X1014009Y988813D03*
X1021924Y980456D03*
X1022009Y988813D03*
Y997860D03*
X1018009D03*
X1026009D03*
X1025448Y1008262D03*
X1014009Y997860D03*
X1017998Y1009655D03*
X1015198D03*
X1025448Y1011762D03*
X1011782Y1016591D03*
X1022594Y1035114D03*
X1022143Y1030672D03*
X1019143D03*
X1016143D03*
X1017297Y1102091D03*
X1026606Y1102591D03*
X1023106Y1102091D03*
X1017297Y1114691D03*
X1023106D03*
X1026606D03*
X1017297Y1109564D03*
X1023144Y1122164D03*
X1017297D03*
X1023106Y1127291D03*
X1026606D03*
X1017297Y1139891D03*
X1023106D03*
X1026606D03*
X1017297Y1127291D03*
X1023144Y1134764D03*
X1017297D03*
X1026606Y1152491D03*
X1017297D03*
X1023106D03*
X1023144Y1147364D03*
X1017297D03*
Y1165091D03*
X1023106D03*
X1026606D03*
X1023144Y1159964D03*
X1017297D03*
Y1172564D03*
Y1177691D03*
X1023106D03*
X1026606D03*
X1023162Y1174445D03*
X1017297Y1185164D03*
X1020434Y1205579D03*
X1026968Y1223749D03*
X1025434Y1320606D03*
X1011829Y1347471D03*
Y1342515D03*
X1015286Y1344924D03*
X1023358Y1363921D03*
X1013991Y1360842D03*
X1021623Y1373216D03*
X1012338Y1388597D03*
Y1391597D03*
X1015338D03*
Y1388597D03*
X1021338D03*
Y1391597D03*
X1018338D03*
Y1388597D03*
X1027338D03*
Y1391597D03*
X1024338D03*
Y1388597D03*
X1012981Y1431097D03*
Y1428097D03*
X1015981D03*
Y1431097D03*
X1021981Y1428097D03*
Y1431097D03*
X1018981D03*
Y1428097D03*
X1012981Y1434097D03*
X1015981D03*
X1012981Y1437097D03*
Y1440097D03*
X1015981Y1437097D03*
Y1440097D03*
X1021981Y1434097D03*
X1018981D03*
X1021981Y1437097D03*
X1018981D03*
X1021981Y1440097D03*
X1018981D03*
X1025615Y1444492D03*
X1025138Y1463839D03*
Y1460839D03*
Y1457839D03*
Y1454839D03*
Y1466839D03*
Y1469602D03*
X1020023Y1489637D03*
X1013749Y1509815D03*
X1016349D03*
X1021549D03*
X1018949D03*
X1024149D03*
X1022649Y1507215D03*
X1025249D03*
X1017449D03*
X1020049D03*
X1014849D03*
X1012249D03*
X1026749Y1509815D03*
X1012249Y1512415D03*
X1014849D03*
X1025249D03*
X1022649D03*
X1020049D03*
X1017449D03*
X1013422Y1514993D03*
X1023822D03*
X1021222D03*
X1018622D03*
X1016022D03*
X1026422D03*
X1013606Y1547824D03*
X1016606D03*
X1019606D03*
X1013659Y1568771D03*
X1016659D03*
X1019659D03*
X1013659Y1565771D03*
X1016659D03*
X1019659D03*
X1013653Y1571669D03*
X1016653D03*
X1019653D03*
X1011457Y1639797D03*
X1043492Y4469D03*
X1036772Y109172D03*
X1039772D03*
X1038779Y106495D03*
X1029755Y102249D03*
X1042523Y116497D03*
X1033506Y116594D03*
X1038779Y102495D03*
X1031780Y133298D03*
X1042523Y130670D03*
Y123584D03*
X1033506Y119594D03*
X1038513Y146012D03*
X1040419Y141228D03*
X1042523Y137757D03*
X1038513Y142862D03*
X1043307Y150847D03*
X1032055Y195176D03*
X1031674Y198883D03*
X1029555Y195176D03*
X1042102D03*
X1033103Y206838D03*
X1035603D03*
X1029415Y203393D03*
X1042183Y210509D03*
X1029594Y218085D03*
X1036107Y221970D03*
X1036173Y226320D03*
X1036107Y219470D03*
Y216970D03*
X1033394Y216385D03*
X1038065Y236121D03*
X1035099Y238589D03*
X1042860Y242078D03*
X1038091Y232971D03*
X1037984Y253198D03*
X1030184Y288709D03*
X1037290Y296293D03*
X1033890D03*
X1038068Y298789D03*
X1033112D03*
X1041496Y300276D03*
X1029639Y300141D03*
X1031354Y325901D03*
Y322905D03*
X1030220Y313554D03*
X1031382Y340947D03*
X1031310Y337888D03*
X1031377Y333671D03*
X1031362Y329268D03*
X1042948Y333696D03*
X1043106Y340230D03*
X1029885Y711762D03*
X1030753Y732213D03*
X1033200Y731700D03*
X1038796Y763272D03*
X1035619Y755809D03*
X1038344Y756476D03*
X1038678Y776750D03*
X1042880Y794924D03*
X1039251Y812340D03*
X1042414Y801443D03*
X1041100Y838500D03*
X1035185Y862793D03*
X1037685Y862789D03*
X1028155Y879413D03*
X1030300Y881400D03*
X1037709Y886209D03*
X1043252Y902501D03*
X1033019Y933022D03*
Y935822D03*
X1030819Y938422D03*
X1031219Y949922D03*
X1033370Y953994D03*
X1038009Y988813D03*
X1030009D03*
Y997860D03*
X1034009D03*
X1038252Y1009354D03*
X1034752D03*
X1028943D03*
X1042009Y997860D03*
X1038009D03*
X1034752Y1021954D03*
X1028943Y1016827D03*
X1034790D03*
X1043553Y1035384D03*
X1028943Y1029427D03*
X1034790D03*
X1039499Y1098758D03*
X1039053Y1105091D03*
Y1117691D03*
Y1130291D03*
Y1142891D03*
Y1155491D03*
Y1168091D03*
Y1180691D03*
X1040600Y1210600D03*
X1035384Y1215195D03*
X1029797Y1220921D03*
X1043588Y1227300D03*
X1034513Y1333665D03*
X1042586Y1345824D03*
X1030338Y1391597D03*
Y1388597D03*
X1032867Y1431213D03*
Y1428213D03*
X1029867D03*
X1035867Y1431213D03*
Y1428213D03*
X1029867Y1431213D03*
X1038867Y1428213D03*
Y1431213D03*
X1041867D03*
Y1428213D03*
X1032867Y1434213D03*
X1029867D03*
X1035867D03*
X1038867D03*
X1032867Y1437213D03*
X1029867D03*
X1032867Y1440213D03*
X1029867D03*
X1035867Y1437213D03*
Y1440213D03*
X1038867Y1437213D03*
Y1440213D03*
X1041867Y1434213D03*
Y1437213D03*
Y1440213D03*
X1029349Y1509815D03*
X1027849Y1507215D03*
Y1512415D03*
X1031457Y1639797D03*
X1044853Y24773D03*
Y44773D03*
X1052174Y53597D03*
X1047373Y95111D03*
X1049823Y109410D03*
X1054523Y116496D03*
Y109410D03*
Y102323D03*
X1049823Y116497D03*
X1047323D03*
X1051742Y106561D03*
X1049823Y130670D03*
X1047323D03*
Y123584D03*
X1049823Y123583D03*
X1054523Y130670D03*
Y123583D03*
Y137756D03*
X1047323Y137757D03*
X1047102Y195176D03*
X1046120Y199248D03*
X1044602Y195176D03*
X1049602D03*
X1051055Y213539D03*
X1046120Y201748D03*
X1049120Y202048D03*
X1044683Y210509D03*
X1046456Y206806D03*
X1043956D03*
X1044501Y238689D03*
X1045275Y247292D03*
X1052736Y238714D03*
X1048736D03*
X1048217Y246874D03*
X1050437Y244297D03*
X1048695Y280161D03*
X1045364Y279895D03*
X1051796Y279965D03*
X1050164Y302748D03*
X1050076Y305512D03*
X1046674Y340031D03*
X1045966Y346808D03*
X1052367Y402291D03*
X1057359D03*
X1052367Y397335D03*
X1057359D03*
X1054959Y411509D03*
X1049967Y416465D03*
Y411509D03*
X1054959Y425682D03*
X1049967D03*
X1054959Y416465D03*
X1049967Y439855D03*
X1054959Y430638D03*
X1049967D03*
X1054959Y439855D03*
X1049967Y444811D03*
X1050777Y450750D03*
X1054959Y444811D03*
X1049967Y468609D03*
X1054959D03*
X1049967Y473565D03*
X1054959D03*
X1049967Y487738D03*
X1054959D03*
X1049967Y482782D03*
X1054959D03*
Y517699D03*
X1049967Y512743D03*
X1054959D03*
X1049967Y517699D03*
Y526916D03*
X1054959Y531872D03*
X1049967D03*
X1054959Y526916D03*
X1054876Y536382D03*
X1055885Y554555D03*
X1059843Y597580D03*
X1059782Y594668D03*
X1044112Y778835D03*
X1046068Y792742D03*
X1046930Y796557D03*
X1045744Y800835D03*
X1048328Y808166D03*
X1055700Y840900D03*
X1053913Y837718D03*
X1045300Y872352D03*
X1054900Y879321D03*
X1058155Y887635D03*
X1050295Y891100D03*
X1057961Y931919D03*
X1054009Y988813D03*
X1046009D03*
Y997860D03*
X1054009D03*
X1050009D03*
X1058009D03*
X1059689Y1012354D03*
Y1024954D03*
X1050699D03*
Y1012354D03*
X1046485Y1034538D03*
X1048043Y1105091D03*
Y1117691D03*
Y1130291D03*
Y1155491D03*
Y1142891D03*
Y1168091D03*
Y1180691D03*
X1050605Y1224472D03*
X1051249Y1290288D03*
X1052660Y1293257D03*
X1050002Y1293283D03*
X1052221Y1336984D03*
X1049204Y1337377D03*
X1049670Y1347462D03*
X1046075Y1350650D03*
X1049493Y1350694D03*
X1044867Y1428213D03*
Y1431213D03*
Y1434213D03*
Y1437213D03*
Y1440213D03*
X1048403Y1444608D03*
X1051457Y1639797D03*
X1075256Y-77419D03*
X1072003Y-77405D03*
X1071988Y-85290D03*
X1075241D03*
X1072000Y-82600D03*
X1072003Y-87805D03*
X1075256D03*
X1072000Y-80100D03*
Y-72000D03*
Y-69400D03*
X1071988Y-66722D03*
X1075241Y-66808D03*
X1072003Y-64207D03*
X1075256Y-64293D03*
X1075241Y-74904D03*
X1071988Y-74890D03*
X1072174Y53597D03*
X1062985Y82984D03*
Y75184D03*
Y77784D03*
Y80384D03*
X1065539Y92849D03*
X1062985Y85584D03*
X1072456Y95236D03*
X1062523D03*
X1072499Y103037D03*
X1062523Y102323D03*
X1062775Y109410D03*
Y116496D03*
X1072633D03*
Y109410D03*
X1062947Y124576D03*
X1072633Y130670D03*
Y123583D03*
X1064000Y130670D03*
X1069224Y137756D03*
X1063995D03*
X1071268Y207978D03*
Y212978D03*
Y215478D03*
Y210478D03*
Y226226D03*
Y223726D03*
Y228726D03*
Y231226D03*
X1074597Y264180D03*
X1074522Y258880D03*
X1074814Y293796D03*
X1061325Y339509D03*
X1060679Y360151D03*
Y364276D03*
Y368276D03*
X1060369Y390223D03*
X1065361D03*
X1062234Y378600D03*
Y382600D03*
X1060369Y395179D03*
Y404396D03*
Y409352D03*
X1065361Y395179D03*
Y404396D03*
Y409352D03*
X1060369Y418569D03*
Y423525D03*
X1065361D03*
Y418569D03*
X1060369Y432743D03*
Y437699D03*
X1065361Y432743D03*
Y437699D03*
X1062349Y458711D03*
X1064876Y453682D03*
X1063113Y455921D03*
X1061693Y463600D03*
X1065361Y489895D03*
X1060369D03*
Y480677D03*
Y475721D03*
X1065361Y480677D03*
Y475721D03*
X1060369Y494851D03*
X1065361D03*
X1060369Y519855D03*
X1065361D03*
Y524811D03*
X1060369D03*
Y538984D03*
Y534028D03*
X1065361Y538984D03*
Y534028D03*
X1071548Y555234D03*
X1071263Y562003D03*
X1062066Y599588D03*
X1061328Y589556D03*
X1061267Y592354D03*
X1062069Y596095D03*
X1062098Y603600D03*
X1062066Y607588D03*
X1061342Y610269D03*
X1061496Y612786D03*
X1062098Y619600D03*
X1066559Y634946D03*
X1062098Y623600D03*
X1060698Y931619D03*
X1069685Y933391D03*
X1066878Y931909D03*
X1070009Y988813D03*
X1069607Y980131D03*
X1066009Y980330D03*
X1062009Y988813D03*
X1066009Y997860D03*
X1062009D03*
X1074009D03*
X1070778Y1012252D03*
X1073525Y1012428D03*
X1066933Y1040567D03*
X1076110Y1029535D03*
X1071641Y1058029D03*
X1060172Y1050481D03*
X1071348Y1050503D03*
X1074232Y1055836D03*
X1060768Y1053457D03*
X1074650Y1070006D03*
X1071457Y1639797D03*
X1078281Y-86399D03*
X1083683Y-78528D03*
Y-83484D03*
X1081187Y-79306D03*
Y-82706D03*
X1078281Y-65613D03*
Y-76099D03*
X1083683Y-73484D03*
Y-68528D03*
X1090280Y44773D03*
X1081320Y85193D03*
Y82593D03*
Y79993D03*
Y77393D03*
Y74793D03*
X1089916Y94017D03*
X1085916D03*
X1089645Y101701D03*
Y98551D03*
X1090044Y110445D03*
Y115401D03*
X1080633Y102323D03*
Y116496D03*
Y109410D03*
X1083391Y104249D03*
Y107649D03*
X1080633Y130670D03*
Y123583D03*
X1090044Y124618D03*
Y129574D03*
X1080633Y137756D03*
X1087957Y147540D03*
X1091729Y141247D03*
X1087957Y151540D03*
X1083013Y162368D03*
X1090113Y165393D03*
Y162793D03*
X1080413Y162368D03*
X1090113Y170493D03*
Y167993D03*
X1092321Y181366D03*
X1089110Y181426D03*
X1091607Y191941D03*
X1091935Y184012D03*
X1089318Y184221D03*
X1081724Y208213D03*
X1085796Y208695D03*
Y211695D03*
X1081724Y210713D03*
Y213213D03*
X1088296Y211695D03*
X1085431Y226141D03*
X1081724Y226461D03*
X1089693Y229286D03*
X1081724Y231461D03*
Y228961D03*
Y215713D03*
X1089693Y231786D03*
X1085674Y236611D03*
X1088174D03*
X1090674D03*
X1090376Y248891D03*
X1087876D03*
X1085376D03*
X1077097Y264180D03*
X1083491Y267526D03*
X1088791D03*
X1086291D03*
X1083491Y270026D03*
X1086291D03*
X1088791D03*
X1088128Y285690D03*
Y288190D03*
X1085328D03*
X1082828Y285690D03*
X1085328D03*
X1082828Y288190D03*
X1077314Y293796D03*
X1092354Y290755D03*
X1077855Y327478D03*
X1077252Y323521D03*
Y318565D03*
X1077602Y314060D03*
X1080351Y328256D03*
X1079748Y322743D03*
Y319343D03*
X1077855Y332434D03*
X1080351Y331656D03*
X1082297Y340770D03*
X1085615Y339815D03*
X1079863Y345660D03*
X1092561Y353374D03*
X1082787Y348501D03*
X1091031Y374810D03*
X1091542Y389154D03*
Y410413D03*
Y396240D03*
Y403327D03*
Y417500D03*
Y424587D03*
Y431673D03*
Y438760D03*
Y445847D03*
Y467539D03*
Y474626D03*
Y488799D03*
Y481713D03*
Y495886D03*
Y511673D03*
Y518760D03*
Y525847D03*
Y532933D03*
Y540020D03*
Y547106D03*
X1089788Y550907D03*
X1087288D03*
X1089788Y553407D03*
X1087288D03*
X1089096Y541863D03*
Y545263D03*
X1091558Y566929D03*
X1091272Y569426D03*
X1088949Y568475D03*
X1089206Y570962D03*
X1086859Y569928D03*
X1085512Y572070D03*
X1090823Y602197D03*
X1091287Y595108D03*
X1078920Y856700D03*
X1090375Y899047D03*
X1076800Y1012900D03*
X1079809Y1034386D03*
X1078755Y1031518D03*
X1079178Y1037884D03*
X1076868Y1047293D03*
X1079910Y1045264D03*
X1083483Y1523433D03*
X1083283Y1526583D03*
X1090876Y1554183D03*
X1086469Y1588435D03*
X1082176Y1600598D03*
X1090904Y1599047D03*
X1090747Y1617415D03*
X1085474Y1629028D03*
X1092000Y1644980D03*
X1102993Y84140D03*
Y76140D03*
Y80140D03*
X1105741Y76587D03*
Y72615D03*
X1097925Y94017D03*
X1093916D03*
X1100446Y117557D03*
X1095036Y115401D03*
Y110445D03*
X1105438Y117557D03*
X1097195Y103783D03*
X1108362Y103621D03*
X1100130Y106186D03*
X1093195Y103783D03*
X1095036Y129574D03*
Y124618D03*
X1105438Y131731D03*
Y122513D03*
X1100446Y131731D03*
Y122513D03*
X1103537Y146461D03*
X1100446Y136687D03*
X1105438D03*
X1102439Y152367D03*
X1104139Y180572D03*
X1108822Y180527D03*
X1095116Y181009D03*
X1100291Y168697D03*
X1104139Y185165D03*
X1108777Y185121D03*
X1098107Y184619D03*
X1101379Y191941D03*
X1100087Y206760D03*
X1105888Y206767D03*
X1108388D03*
X1103388D03*
X1093354Y213859D03*
Y211359D03*
X1097057Y213132D03*
X1093386Y224712D03*
Y222212D03*
X1104633Y228221D03*
X1106018Y221708D03*
X1108518D03*
X1102933Y224421D03*
X1103518Y221708D03*
X1104633Y231021D03*
X1097057Y215632D03*
X1105184Y236189D03*
X1107684D03*
X1101301Y256535D03*
X1093301D03*
X1105125Y248765D03*
X1107625D03*
X1097301Y256303D03*
X1102331Y279208D03*
X1107822Y268195D03*
X1105322D03*
Y270695D03*
X1107822D03*
X1108425Y293645D03*
Y290845D03*
Y288345D03*
X1096354Y290755D03*
X1093478Y310305D03*
X1108779Y327705D03*
X1100703Y340560D03*
X1103432Y340544D03*
X1097976Y340477D03*
X1101999Y353495D03*
X1098845Y353404D03*
X1093994Y374003D03*
X1093841Y371335D03*
X1099342Y389154D03*
X1106161D03*
X1099342Y396240D03*
X1100621Y404911D03*
X1104691Y396240D03*
X1099575Y412571D03*
X1108776Y422864D03*
X1100762Y426299D03*
X1108846Y429832D03*
X1108451Y436447D03*
X1101073Y445847D03*
X1099342Y467539D03*
Y474626D03*
X1108395Y472772D03*
X1099603Y480828D03*
X1101553Y498834D03*
X1105002Y516841D03*
X1108253Y510565D03*
X1099342Y518760D03*
Y511673D03*
Y525847D03*
X1099949Y550123D03*
X1099827Y552872D03*
X1101581Y572334D03*
X1099272Y562443D03*
X1101040Y560675D03*
X1099813Y574102D03*
X1108236Y577716D03*
X1105298Y598400D03*
Y602400D03*
Y594400D03*
Y614400D03*
Y606400D03*
Y610400D03*
X1108045Y677843D03*
X1092769Y936975D03*
X1095080Y1513398D03*
X1099900Y1535700D03*
X1095250Y1531600D03*
X1096264Y1562285D03*
X1100876Y1554183D03*
X1093713Y1585583D03*
X1093682Y1582433D03*
X1098498Y1590435D03*
X1104233Y1587983D03*
X1107620Y1606752D03*
Y1603602D03*
X1101474Y1637820D03*
X1093474Y1638213D03*
X1123052Y57511D03*
X1114781Y58013D03*
X1113646Y68581D03*
X1122881Y60438D03*
X1113659Y80581D03*
X1122613Y97042D03*
X1117764Y91951D03*
X1117789Y88801D03*
X1123703Y86046D03*
X1120706Y94351D03*
X1116368Y117261D03*
X1123899Y113394D03*
Y116594D03*
X1111553Y112083D03*
X1123899Y119594D03*
X1122740Y161306D03*
X1114496Y152562D03*
X1119991Y157370D03*
X1124075Y180665D03*
Y172665D03*
Y168665D03*
Y176665D03*
X1112545Y192421D03*
X1116174Y186629D03*
X1124075Y196665D03*
X1114708Y190185D03*
X1124188Y186778D03*
X1124107Y200864D03*
Y212864D03*
Y204864D03*
Y216864D03*
Y221864D03*
X1112868Y221642D03*
X1119748Y219379D03*
X1110184Y236189D03*
X1110125Y248765D03*
X1116782Y265897D03*
X1114282D03*
X1110622Y268195D03*
Y270695D03*
X1110925Y293645D03*
Y290845D03*
Y288345D03*
X1123500Y329000D03*
X1115000D03*
X1123500Y339000D03*
Y334000D03*
X1115000D03*
Y339000D03*
X1117453Y389154D03*
X1124753Y389153D03*
X1122253Y396240D03*
X1124753D03*
X1122253Y403327D03*
X1124753Y403326D03*
X1122253Y410413D03*
X1124753D03*
X1117453Y396240D03*
Y403327D03*
Y410413D03*
X1109468Y414823D03*
X1122253Y424586D03*
X1124753D03*
X1117453Y417500D03*
Y424586D03*
X1122253Y417500D03*
X1124753Y417499D03*
X1122253Y438760D03*
X1124753D03*
Y431673D03*
X1117453D03*
Y438760D03*
X1122253Y431673D03*
X1110486Y447953D03*
X1122253Y445847D03*
X1117453D03*
X1109653Y467539D03*
X1124753D03*
X1117453D03*
X1122253Y474626D03*
X1124753D03*
X1117453D03*
X1122253Y488799D03*
X1124753D03*
X1117453D03*
X1109129Y487711D03*
X1109242Y479104D03*
X1124753Y481712D03*
X1122253D03*
X1117453Y481713D03*
X1122253Y495886D03*
X1117453D03*
X1109653D03*
X1124753Y518760D03*
X1122253D03*
X1124753Y511673D03*
X1117453D03*
Y518760D03*
X1124753Y532933D03*
X1122253D03*
Y540020D03*
Y525846D03*
X1124753D03*
X1117453Y525847D03*
Y532933D03*
Y540020D03*
Y554193D03*
Y547106D03*
X1117913Y565414D03*
Y567914D03*
Y570414D03*
X1118847Y561420D03*
Y558917D03*
X1117913Y572914D03*
Y575414D03*
X1122705Y588515D03*
X1114668Y577937D03*
X1117453Y602205D03*
Y595118D03*
X1122718Y598857D03*
X1122705Y591015D03*
X1121191Y612555D03*
X1120512Y617332D03*
X1121022Y607750D03*
X1115320Y646449D03*
X1118863Y662981D03*
X1112839Y668885D03*
X1115054Y662981D03*
X1113244Y691851D03*
X1116296D03*
X1111785Y686971D03*
X1118855Y705043D03*
X1118105Y707592D03*
X1112000Y1644980D03*
X1125735Y60922D03*
X1128562Y94374D03*
X1139134Y109172D03*
X1141141Y106495D03*
X1132117Y102249D03*
X1128117D03*
X1126548Y110784D03*
X1135868Y116594D03*
X1141141Y102495D03*
X1134142Y133298D03*
X1126142D03*
X1135868Y119594D03*
X1140875Y146012D03*
X1128289Y134579D03*
X1140875Y142862D03*
X1134036Y198883D03*
X1134417Y195176D03*
X1131917D03*
X1129417D03*
X1137965Y206838D03*
X1131777Y203393D03*
X1129277D03*
X1135465Y206838D03*
X1129156Y218085D03*
X1131956D03*
X1138469Y221970D03*
X1138535Y226320D03*
X1138469Y219470D03*
Y216970D03*
X1135756Y216385D03*
X1137461Y238589D03*
X1140427Y236121D03*
X1140453Y232971D03*
X1140346Y253198D03*
X1125864Y252371D03*
Y248371D03*
X1129553Y389153D03*
Y396240D03*
Y403326D03*
Y410413D03*
Y424586D03*
Y417499D03*
Y431673D03*
Y438760D03*
X1126931Y453564D03*
X1130355Y453483D03*
X1129553Y467539D03*
X1125178Y459792D03*
X1129553Y474626D03*
X1134629Y465551D03*
X1129553Y488799D03*
Y481712D03*
X1126622Y506256D03*
X1129553Y518760D03*
Y511673D03*
Y532933D03*
Y525846D03*
X1138166Y534759D03*
X1139673Y530000D03*
X1138098Y543925D03*
X1138673Y555000D03*
X1139173Y540500D03*
X1138373Y549800D03*
X1138173Y547075D03*
X1126633Y560500D03*
X1138213Y558800D03*
X1138277Y562800D03*
X1125287Y592897D03*
X1129471Y732571D03*
X1129637Y1465913D03*
Y1461182D03*
Y1456451D03*
X1138298Y1465513D03*
Y1460782D03*
X1129637Y1476536D03*
Y1481267D03*
X1138298Y1476136D03*
Y1470244D03*
Y1480867D03*
X1129637Y1471805D03*
Y1496621D03*
X1138298Y1491490D03*
Y1485598D03*
Y1496221D03*
X1129637Y1491890D03*
Y1487159D03*
X1138298Y1500952D03*
Y1511576D03*
X1129637Y1507245D03*
Y1502514D03*
Y1511976D03*
X1138298Y1506845D03*
Y1516307D03*
X1129637Y1563544D03*
Y1558813D03*
X1138298Y1563144D03*
Y1572606D03*
X1129637Y1568275D03*
Y1578898D03*
Y1574167D03*
X1138298Y1567875D03*
Y1578498D03*
X1129637Y1583629D03*
Y1594253D03*
Y1589522D03*
X1138298Y1583229D03*
Y1593853D03*
Y1587960D03*
Y1598584D03*
Y1603315D03*
X1129637Y1609607D03*
Y1598984D03*
Y1604876D03*
X1138298Y1609207D03*
X1129637Y1614338D03*
X1138298Y1613938D03*
Y1618669D03*
X1132000Y1644980D03*
X1147214Y44773D03*
X1154535Y53597D03*
X1149735Y95111D03*
X1142134Y109172D03*
X1156885Y116496D03*
Y102323D03*
Y109410D03*
X1152185D03*
Y116497D03*
X1149685D03*
X1144885D03*
X1154104Y106561D03*
X1152185Y130670D03*
X1149685D03*
Y123584D03*
X1152185Y123583D03*
X1144885Y130670D03*
Y123584D03*
X1156885Y130670D03*
Y123583D03*
X1142781Y141228D03*
X1156885Y137756D03*
X1149685Y137757D03*
X1144885D03*
X1145669Y150847D03*
X1149464Y195176D03*
X1148482Y199248D03*
X1144464Y195176D03*
X1146964D03*
X1151964D03*
X1153417Y213539D03*
X1151482Y202048D03*
X1146318Y206806D03*
X1144545Y210509D03*
X1147045D03*
X1148818Y206806D03*
X1148482Y201748D03*
X1146863Y238689D03*
X1155098Y238714D03*
X1147637Y247292D03*
X1151098Y238714D03*
X1145222Y242078D03*
X1150579Y246874D03*
X1152799Y244297D03*
X1145761Y324148D03*
X1142440Y392718D03*
Y400718D03*
Y408718D03*
Y396718D03*
X1157451Y618288D03*
X1156275Y656321D03*
X1156023Y678462D03*
X1155146Y699491D03*
X1149437Y728541D03*
X1152512Y728543D03*
X1152316Y746625D03*
X1148962Y747253D03*
X1149345Y771517D03*
X1145910Y794217D03*
X1151277Y790996D03*
X1154652Y791056D03*
X1149627Y813323D03*
X1146985Y812642D03*
X1145910Y803642D03*
X1152510Y844642D03*
X1146960Y1465913D03*
Y1461182D03*
X1155621Y1465513D03*
Y1460782D03*
X1146960Y1456451D03*
X1155621Y1480867D03*
X1146960Y1471805D03*
Y1476536D03*
Y1481267D03*
X1155621Y1476136D03*
Y1470244D03*
Y1491490D03*
Y1485598D03*
Y1496221D03*
X1146960Y1487159D03*
Y1491890D03*
Y1496621D03*
Y1507245D03*
Y1502514D03*
X1155621Y1506845D03*
Y1500952D03*
Y1511576D03*
X1146960Y1511976D03*
X1155621Y1516307D03*
X1146960Y1563544D03*
X1155621Y1563144D03*
X1146960Y1558813D03*
X1155621Y1572606D03*
X1146960Y1568275D03*
X1155621Y1567875D03*
X1146960Y1574167D03*
Y1578898D03*
X1155621Y1578498D03*
X1146960Y1594253D03*
X1155621Y1593853D03*
Y1587960D03*
X1146960Y1583629D03*
X1155621Y1583229D03*
X1146960Y1589522D03*
Y1609607D03*
Y1604876D03*
Y1598984D03*
X1155621Y1609207D03*
Y1598584D03*
Y1603315D03*
X1146960Y1614338D03*
X1155621Y1613938D03*
Y1618669D03*
X1152000Y1644980D03*
X1165347Y82984D03*
Y75184D03*
Y77784D03*
Y80384D03*
X1167756Y92734D03*
X1165347Y85584D03*
X1164885Y95236D03*
Y102323D03*
X1165137Y109410D03*
Y116496D03*
X1165309Y124576D03*
X1166362Y130670D03*
X1171586Y137756D03*
X1166357D03*
X1173630Y207978D03*
Y210478D03*
Y212978D03*
Y215478D03*
Y226226D03*
Y223726D03*
Y228726D03*
Y231226D03*
X1173559Y304948D03*
X1171445Y422088D03*
X1168902Y431029D03*
X1167931Y435029D03*
X1169173Y427017D03*
X1168685Y438323D03*
X1168851Y449873D03*
X1171255Y456287D03*
X1168398Y456309D03*
X1168851Y445873D03*
X1173278Y472579D03*
X1168478D03*
X1173278Y479666D03*
X1168478D03*
Y486752D03*
X1173278D03*
X1168478Y493839D03*
X1173278D03*
X1168478Y523800D03*
Y516713D03*
X1173278D03*
Y523800D03*
Y537973D03*
X1168478D03*
X1173278Y530886D03*
X1168478D03*
X1161274Y550462D03*
X1159535Y546712D03*
Y542712D03*
X1165400Y553300D03*
X1167900D03*
X1173278Y566752D03*
X1168478D03*
Y580926D03*
X1173278D03*
Y588013D03*
X1168478D03*
X1173278Y573839D03*
X1168478D03*
Y602186D03*
X1173278D03*
Y595099D03*
X1168478D03*
X1173278Y609272D03*
X1168478D03*
Y616359D03*
X1173278D03*
X1161451Y618288D03*
X1163157Y638125D03*
X1160275Y656321D03*
X1164275D03*
X1162863Y678519D03*
X1159173Y678462D03*
X1170465Y677836D03*
X1157646Y699491D03*
X1162646D03*
X1160146D03*
X1169256Y694983D03*
X1170603Y715281D03*
X1163774Y713347D03*
X1166115Y718469D03*
X1163751Y719498D03*
X1168577Y733812D03*
X1171934Y733857D03*
X1173034Y765060D03*
X1157985Y791142D03*
X1161291Y791662D03*
X1173697Y791911D03*
X1169697Y791935D03*
X1164925Y791607D03*
X1160516Y800900D03*
X1169266Y800799D03*
X1159887Y869106D03*
X1164283Y1465913D03*
Y1456451D03*
Y1461182D03*
X1172944Y1465513D03*
Y1460782D03*
Y1470244D03*
Y1480867D03*
X1164283Y1471805D03*
Y1476536D03*
Y1481267D03*
X1172944Y1476136D03*
X1164283Y1487159D03*
Y1491890D03*
Y1496621D03*
X1172944Y1491490D03*
Y1485598D03*
Y1496221D03*
X1164283Y1507245D03*
Y1502514D03*
X1172944Y1506845D03*
Y1500952D03*
Y1511576D03*
X1164283Y1511976D03*
X1172944Y1516307D03*
X1164283Y1558813D03*
Y1563544D03*
X1172944Y1563144D03*
Y1567875D03*
X1164283Y1574167D03*
Y1578898D03*
X1172944Y1578498D03*
Y1572606D03*
X1164283Y1568275D03*
Y1583629D03*
X1172944Y1583229D03*
X1164283Y1589522D03*
Y1594253D03*
X1172944Y1593853D03*
Y1587960D03*
Y1598584D03*
Y1603315D03*
X1164283Y1609607D03*
Y1604876D03*
Y1598984D03*
X1172944Y1609207D03*
X1164283Y1614338D03*
X1172944Y1613938D03*
Y1618669D03*
X1172000Y1644980D03*
X1174535Y53597D03*
X1183682Y85193D03*
Y82593D03*
Y74793D03*
Y79993D03*
Y77393D03*
X1188278Y94017D03*
X1174818Y95236D03*
X1174861Y103037D03*
X1174995Y116496D03*
Y109410D03*
X1182995Y116496D03*
Y109410D03*
Y102323D03*
X1185753Y107649D03*
Y104249D03*
X1174995Y130670D03*
Y123583D03*
X1182995Y130670D03*
Y123583D03*
Y137756D03*
X1182775Y162368D03*
X1185375D03*
X1188158Y211695D03*
X1184086Y210713D03*
Y213213D03*
Y208213D03*
X1188158Y208695D03*
X1184086Y231461D03*
Y228961D03*
X1187793Y226141D03*
X1184086Y226461D03*
Y215713D03*
X1188036Y236611D03*
X1187738Y248891D03*
X1176959Y264180D03*
X1179459D03*
X1177035Y257919D03*
X1185853Y267526D03*
X1188653D03*
X1185853Y270026D03*
X1188653D03*
X1179676Y293796D03*
X1187690Y288190D03*
X1185190Y285690D03*
X1187690D03*
X1185190Y288190D03*
X1177176Y293796D03*
X1176858Y306534D03*
X1179901Y306366D03*
X1181706Y310131D03*
X1178045Y312193D03*
X1181379Y316049D03*
X1174929Y319167D03*
X1182911Y336516D03*
X1177036Y334148D03*
X1179761Y336380D03*
X1187996Y331992D03*
X1188598Y390500D03*
Y381500D03*
X1179184Y410394D03*
X1180118Y430098D03*
Y440098D03*
Y437598D03*
Y435098D03*
Y432598D03*
X1178083Y442856D03*
X1189122Y442606D03*
X1180578Y458406D03*
Y451319D03*
X1179184Y453881D03*
Y446595D03*
X1188739Y446606D03*
X1188378Y466027D03*
X1180402Y462264D03*
X1175778Y465492D03*
X1180578D03*
X1188520Y475262D03*
X1175778Y472579D03*
X1180578D03*
X1190046Y463479D03*
X1188520Y489435D03*
Y482666D03*
X1175778Y479666D03*
X1180578Y479665D03*
Y486752D03*
X1175778D03*
X1180578Y493839D03*
X1188336Y495088D03*
X1175778Y509626D03*
X1180578Y523799D03*
Y516713D03*
Y509626D03*
X1175778Y516713D03*
Y523800D03*
X1189071Y514608D03*
X1188993Y522134D03*
X1188378Y509626D03*
X1180578Y537973D03*
X1175778Y530886D03*
X1180578D03*
X1189475Y535677D03*
X1189636Y529136D03*
X1180578Y559665D03*
Y566752D03*
X1175778D03*
Y559665D03*
X1188378D03*
X1188759Y565574D03*
X1175778Y580926D03*
X1180578D03*
Y588012D03*
X1175778D03*
X1180578Y573839D03*
X1175778D03*
X1188406Y574338D03*
X1175778Y602185D03*
X1180578D03*
X1175778Y595099D03*
X1180578D03*
X1175778Y609272D03*
X1180578Y616358D03*
Y609272D03*
X1188505Y616358D03*
X1177745Y771744D03*
X1174595D03*
X1176500Y784933D03*
X1190062Y844378D03*
X1187703Y849734D03*
X1186742Y855466D03*
X1183431Y868340D03*
X1187431D03*
X1180239Y868430D03*
X1177775Y894053D03*
X1176577Y885974D03*
X1179858Y883455D03*
X1179727Y886197D03*
X1181654Y894671D03*
X1185058Y883475D03*
X1178480Y915220D03*
X1187151Y921000D03*
X1178000Y936500D03*
X1188431Y936568D03*
X1182000Y936500D03*
X1189219Y940703D03*
X1187200Y963400D03*
X1184547Y1215452D03*
X1181605Y1465913D03*
Y1456451D03*
Y1461182D03*
Y1471805D03*
Y1476536D03*
Y1481267D03*
Y1487159D03*
Y1491890D03*
Y1496621D03*
Y1507245D03*
Y1502514D03*
Y1511976D03*
Y1558813D03*
Y1563544D03*
Y1568275D03*
Y1574167D03*
Y1578898D03*
Y1583629D03*
Y1589522D03*
Y1594253D03*
Y1598984D03*
Y1609607D03*
Y1604876D03*
Y1614338D03*
X1193330Y5374D03*
X1192643Y24773D03*
Y44773D03*
X1205355Y84140D03*
Y76140D03*
Y80140D03*
X1196278Y94017D03*
X1200287D03*
X1192278D03*
X1192007Y101701D03*
Y98551D03*
X1202808Y117557D03*
X1197398Y110445D03*
Y115401D03*
X1192406Y110445D03*
Y115401D03*
X1199557Y103783D03*
X1195557D03*
X1202492Y106186D03*
X1197398Y129574D03*
Y124618D03*
X1192406D03*
Y129574D03*
X1202808Y122513D03*
Y131731D03*
X1205899Y146461D03*
X1202808Y136687D03*
X1190319Y147540D03*
X1194091Y141247D03*
X1204801Y152367D03*
X1190319Y151540D03*
X1192475Y165393D03*
Y162793D03*
Y167993D03*
Y170493D03*
X1194683Y181366D03*
X1191472Y181426D03*
X1197478Y181009D03*
X1202653Y168697D03*
X1200469Y184619D03*
X1193969Y191941D03*
X1203741D03*
X1194297Y184012D03*
X1191680Y184221D03*
X1202449Y206760D03*
X1205750Y206767D03*
X1195716Y211359D03*
Y213859D03*
X1199419Y213132D03*
X1190658Y211695D03*
X1192055Y229286D03*
X1195748Y224712D03*
Y222212D03*
X1205295Y224421D03*
X1205880Y221708D03*
X1199419Y215632D03*
X1192055Y231786D03*
X1190536Y236611D03*
X1193036D03*
X1192738Y248891D03*
X1190238D03*
X1203663Y256535D03*
X1195663D03*
X1199663Y256303D03*
X1204693Y279208D03*
X1191153Y267526D03*
Y270026D03*
X1194716Y290755D03*
X1190490Y285690D03*
Y288190D03*
X1198716Y290755D03*
X1192500Y322400D03*
X1201113Y315039D03*
X1190127Y324142D03*
X1198248Y381500D03*
X1198468Y430760D03*
X1198489Y433570D03*
X1198305Y437072D03*
X1198346Y439963D03*
X1198552Y452018D03*
X1198590Y443180D03*
X1198610Y454744D03*
X1193000Y444841D03*
X1192686Y449961D03*
X1198689Y465492D03*
X1198655Y460250D03*
X1196420Y470136D03*
X1198689Y472579D03*
Y486752D03*
Y479665D03*
Y493839D03*
Y509626D03*
Y516713D03*
X1195149Y537973D03*
X1197629Y525483D03*
X1197550Y532756D03*
X1198689Y559665D03*
Y566752D03*
X1198539Y579978D03*
X1198689Y573839D03*
X1198753Y608117D03*
X1198997Y790610D03*
X1192431Y868620D03*
X1192152Y884399D03*
X1192367Y903785D03*
X1190210Y900909D03*
X1192990Y914873D03*
X1195118Y936296D03*
X1191151D03*
X1193219Y940703D03*
X1197173Y940645D03*
X1199615Y950670D03*
X1196352Y951033D03*
X1191219Y967757D03*
X1201794Y985289D03*
X1191928Y987314D03*
X1198644Y985289D03*
X1195757Y988131D03*
X1198845Y998504D03*
X1203419Y1011161D03*
X1200008D03*
X1196300Y998600D03*
X1202028Y998349D03*
X1204919Y1021860D03*
X1202268Y1013551D03*
X1199700Y1013661D03*
X1201800Y1019431D03*
X1190267Y1465513D03*
Y1460782D03*
X1198928Y1465914D03*
Y1456452D03*
Y1461183D03*
Y1481268D03*
X1190267Y1476136D03*
Y1470244D03*
Y1480867D03*
X1198928Y1476537D03*
Y1471806D03*
X1190267Y1485598D03*
Y1496221D03*
X1198928Y1491891D03*
Y1487160D03*
Y1496622D03*
X1190267Y1491490D03*
Y1506845D03*
Y1500952D03*
Y1511576D03*
X1198928Y1507246D03*
Y1502515D03*
Y1511977D03*
X1190267Y1516307D03*
X1198928Y1558813D03*
X1190267Y1563144D03*
X1198928Y1563544D03*
X1190267Y1567875D03*
X1198928Y1568275D03*
X1190267Y1578498D03*
Y1572606D03*
X1198928Y1578898D03*
Y1574167D03*
X1190267Y1583229D03*
X1198928Y1583629D03*
X1190267Y1593853D03*
Y1587960D03*
X1198928Y1594253D03*
Y1589522D03*
X1190267Y1609207D03*
Y1598584D03*
Y1603315D03*
X1198928Y1609607D03*
Y1598984D03*
Y1604876D03*
X1190267Y1613938D03*
Y1618669D03*
X1198928Y1614338D03*
X1192000Y1644980D03*
X1212232Y3000D03*
X1219783Y55513D03*
X1216008Y68581D03*
X1216021Y80581D03*
X1208103Y72615D03*
Y76587D03*
X1220126Y91951D03*
X1220151Y88801D03*
X1218730Y117261D03*
X1207800Y117557D03*
X1210724Y103621D03*
X1213915Y112083D03*
X1207800Y122513D03*
Y131731D03*
Y136687D03*
X1216858Y152562D03*
X1222353Y157370D03*
X1206501Y180572D03*
X1211184Y180527D03*
X1214907Y192421D03*
X1206501Y185165D03*
X1211139Y185121D03*
X1218536Y186629D03*
X1210268Y198671D03*
X1217070Y190185D03*
X1207753Y192300D03*
X1208250Y206767D03*
X1210750D03*
X1215230Y221642D03*
X1206995Y228221D03*
X1208380Y221708D03*
X1210880D03*
X1206995Y231021D03*
X1222110Y219379D03*
X1207546Y236189D03*
X1210046D03*
X1212546D03*
X1207487Y248765D03*
X1209987D03*
X1212487D03*
X1219144Y265897D03*
X1216644D03*
X1212984Y268195D03*
X1210184D03*
X1207684D03*
X1212984Y270695D03*
X1207684D03*
X1210184D03*
X1213287Y293645D03*
Y290845D03*
Y288345D03*
X1210787Y293645D03*
Y290845D03*
Y288345D03*
X1217139Y324139D03*
X1220723Y324466D03*
X1221337Y332017D03*
X1220985Y342319D03*
X1215776Y331072D03*
X1217177Y369925D03*
X1206693Y384410D03*
X1206673Y410394D03*
Y403307D03*
X1209426Y433069D03*
Y430469D03*
Y435669D03*
Y440869D03*
Y438269D03*
X1206626Y433069D03*
Y430469D03*
Y435669D03*
Y440869D03*
Y438269D03*
X1206489Y458406D03*
X1212680Y445908D03*
X1216630Y445787D03*
X1209980Y451677D03*
X1207480Y454177D03*
X1209980D03*
X1207480Y451677D03*
X1206489Y465492D03*
Y472579D03*
X1209184Y463618D03*
Y460218D03*
X1206489Y479665D03*
Y486752D03*
Y493839D03*
Y523799D03*
Y516713D03*
Y509626D03*
Y537973D03*
Y530886D03*
Y566752D03*
Y559665D03*
Y580925D03*
Y588012D03*
Y573839D03*
Y602185D03*
Y595099D03*
Y616358D03*
Y609272D03*
X1212000Y1644980D03*
X1231351Y-77080D03*
X1234592Y-79984D03*
X1234604Y-77094D03*
X1231336Y-87691D03*
X1234589Y-87777D03*
X1231351Y-85176D03*
X1234604Y-85262D03*
X1234592Y-82584D03*
X1228311Y-86371D03*
X1222909Y-83456D03*
Y-78500D03*
X1225405Y-79278D03*
Y-82678D03*
X1234592Y-71970D03*
X1231336Y-74565D03*
X1234589Y-74579D03*
X1231336Y-64265D03*
X1234589D03*
X1234592Y-69470D03*
X1231351Y-66780D03*
X1234604D03*
X1228311Y-65585D03*
Y-75885D03*
X1222909Y-68500D03*
Y-73456D03*
X1236692Y-48727D03*
X1236707Y-46212D03*
X1233667Y-47421D03*
X1228265Y-44406D03*
X1236692Y-35515D03*
X1236707Y-38030D03*
X1233667Y-36835D03*
X1228265Y-39450D03*
Y-29450D03*
Y-34406D03*
X1230761Y-43628D03*
Y-40228D03*
X1236692Y-25215D03*
X1236707Y-27730D03*
X1233667Y-26535D03*
X1232232Y3000D03*
X1222933Y55513D03*
X1228097Y60922D03*
X1225243Y60438D03*
X1225041Y97080D03*
X1230924Y94374D03*
X1226065Y86046D03*
X1223068Y94351D03*
X1230479Y102249D03*
X1234479D03*
X1228910Y110784D03*
X1226261Y113394D03*
X1238230Y116594D03*
X1226261D03*
X1229195Y130898D03*
X1236504Y133298D03*
X1238230Y119594D03*
X1226261D03*
X1230651Y134579D03*
X1225102Y161306D03*
X1226437Y180665D03*
Y172665D03*
Y176665D03*
Y168665D03*
X1236779Y195176D03*
X1236398Y198883D03*
X1234279Y195176D03*
X1231779D03*
X1226437Y192665D03*
X1226550Y186778D03*
X1234139Y203393D03*
X1231639D03*
X1226469Y200864D03*
Y212864D03*
X1237827Y206838D03*
X1226469Y204864D03*
Y216864D03*
Y221864D03*
X1231518Y218085D03*
X1234318D03*
X1238118Y216385D03*
X1228226Y252371D03*
Y248371D03*
X1238055Y303839D03*
X1229028Y311740D03*
X1234100Y322924D03*
X1224186Y316731D03*
X1229922Y324550D03*
X1234904Y316942D03*
X1232197Y316964D03*
X1238293Y317296D03*
X1230077Y336324D03*
X1229438Y332584D03*
X1234656Y353506D03*
X1231506Y353470D03*
X1223431Y377912D03*
X1225755Y369391D03*
X1229122Y369355D03*
X1222601Y369251D03*
X1223431Y393924D03*
Y389912D03*
Y385912D03*
Y381912D03*
Y409924D03*
Y405924D03*
Y401924D03*
Y397912D03*
X1232670Y466528D03*
X1237662D03*
X1232670Y471484D03*
X1237662D03*
Y480701D03*
X1232670D03*
Y485657D03*
X1237662D03*
X1232670Y515617D03*
X1237662D03*
X1232670Y510661D03*
X1237662D03*
Y524835D03*
Y529791D03*
X1232670Y524835D03*
Y529791D03*
X1232833Y539315D03*
X1232149Y550137D03*
X1234941D03*
X1232670Y565657D03*
Y560701D03*
X1237662Y565657D03*
Y560701D03*
X1232670Y579830D03*
X1237662Y589047D03*
X1232670D03*
X1237662Y574874D03*
X1232670D03*
X1237662Y579830D03*
Y603221D03*
X1232670D03*
Y594003D03*
X1237662D03*
Y608177D03*
X1232670D03*
X1235930Y626229D03*
X1235292Y622912D03*
X1237500Y632405D03*
X1238034Y629961D03*
X1238695Y627313D03*
X1232000Y1644980D03*
X1239945Y-48727D03*
X1239960Y-46212D03*
X1239948Y-32920D03*
X1239945Y-35529D03*
X1239948Y-30420D03*
Y-40934D03*
X1239960Y-38044D03*
X1239948Y-43534D03*
X1239945Y-25215D03*
X1239960Y-27730D03*
X1248216Y4469D03*
X1249577Y24773D03*
Y44773D03*
X1252097Y95111D03*
X1243503Y106495D03*
X1244496Y109172D03*
X1241496D03*
X1247247Y116497D03*
X1254547Y109410D03*
Y116497D03*
X1252047D03*
X1243503Y102495D03*
X1247247Y123584D03*
Y130670D03*
X1252047Y123584D03*
X1254547Y123583D03*
Y130670D03*
X1252047D03*
X1243237Y146012D03*
X1245143Y141228D03*
X1247247Y137757D03*
X1252047D03*
X1250307Y140296D03*
X1243237Y142862D03*
X1248031Y150847D03*
X1251826Y195176D03*
X1254326D03*
X1249326D03*
X1250844Y199248D03*
X1246826Y195176D03*
X1240327Y206838D03*
X1249407Y210509D03*
X1253844Y202048D03*
X1250844Y201748D03*
X1251180Y206806D03*
X1248680D03*
X1246907Y210509D03*
X1240831Y221970D03*
X1240897Y226320D03*
X1240831Y219470D03*
Y216970D03*
X1249999Y247292D03*
X1239823Y238589D03*
X1242789Y236121D03*
X1253460Y238714D03*
X1247584Y242078D03*
X1252941Y246874D03*
X1242815Y232971D03*
X1242708Y253198D03*
X1253245Y416888D03*
Y419488D03*
Y422088D03*
X1243072Y473640D03*
X1248064D03*
X1243072Y487813D03*
X1248064D03*
X1243072Y478596D03*
X1248064D03*
X1243072Y492769D03*
X1248064D03*
X1243072Y522730D03*
X1248064Y517774D03*
Y522730D03*
X1243072Y517774D03*
X1248064Y531947D03*
Y536903D03*
X1243072D03*
Y531947D03*
X1253087Y553101D03*
X1241629Y550065D03*
X1248064Y567813D03*
X1241752Y564843D03*
X1243072Y567813D03*
X1248064Y572769D03*
X1243072D03*
X1248064Y581987D03*
Y586943D03*
X1243072D03*
Y581987D03*
Y601116D03*
X1248064D03*
X1243072Y596160D03*
X1248064D03*
X1243072Y610333D03*
Y615289D03*
X1248064D03*
Y610333D03*
X1246800Y1001600D03*
X1248106Y1004700D03*
X1245400Y1003700D03*
X1249200Y1014000D03*
X1248721Y1025864D03*
X1246000Y1014800D03*
X1252148Y1026223D03*
X1252500Y1014288D03*
X1246300Y1027800D03*
X1253424Y1138130D03*
X1250928Y1142828D03*
X1249363Y1173065D03*
X1255439Y1172008D03*
X1251802Y1186071D03*
X1253056Y1194917D03*
X1245900Y1528000D03*
X1253904Y1519645D03*
X1256898Y53597D03*
X1267709Y82984D03*
Y75184D03*
Y77784D03*
Y80384D03*
X1270263Y92849D03*
X1267709Y85584D03*
X1267247Y95236D03*
X1267499Y116496D03*
X1259247D03*
Y102323D03*
Y109410D03*
X1267247Y102323D03*
X1267499Y109410D03*
X1256466Y106561D03*
X1267671Y124576D03*
X1268724Y130670D03*
X1259247D03*
Y123583D03*
X1268719Y137756D03*
X1259247D03*
X1255779Y213539D03*
X1257460Y238714D03*
X1255161Y244297D03*
X1264481Y300223D03*
X1266962Y302167D03*
X1262665Y302730D03*
X1263328Y309003D03*
X1258925Y324075D03*
X1262075D03*
X1261659Y318258D03*
X1264088Y320382D03*
X1259500Y330000D03*
X1257000Y333500D03*
X1264215Y333215D03*
X1262500Y330655D03*
X1256000Y338000D03*
X1259991Y340691D03*
X1256000Y340500D03*
X1266219Y374300D03*
X1268659Y377173D03*
X1264659D03*
X1267944Y371767D03*
X1261764Y391533D03*
X1264336Y412106D03*
X1268328Y421489D03*
Y418889D03*
Y416289D03*
X1261623Y447486D03*
X1259223Y458334D03*
X1270397Y447081D03*
X1259223Y454334D03*
X1267843Y473571D03*
Y488618D03*
Y491118D03*
Y481071D03*
Y478571D03*
Y476071D03*
Y493618D03*
X1270951Y491870D03*
X1269629Y848124D03*
X1270892Y856343D03*
X1271121Y892513D03*
X1270276Y897062D03*
X1269221Y894760D03*
X1270515Y908277D03*
X1269876Y1132319D03*
X1260539Y1134729D03*
X1267921D03*
X1263921D03*
X1263873Y1148000D03*
X1266709Y1160168D03*
X1258736Y1188223D03*
X1271246Y1178240D03*
X1268573Y1193019D03*
X1264573D03*
X1268571Y1201043D03*
X1264575D03*
X1261538Y1199814D03*
X1255296Y1196056D03*
X1263449Y1217228D03*
X1266113Y1219895D03*
X1269388Y1223170D03*
X1263242Y1523458D03*
X1262985Y1519459D03*
X1260260Y1546500D03*
X1276898Y53597D03*
X1286044Y85539D03*
Y82939D03*
Y75139D03*
Y80339D03*
Y77739D03*
X1272809Y90615D03*
X1277180Y95236D03*
X1277223Y103037D03*
X1277357Y116496D03*
Y109410D03*
X1285357Y116496D03*
Y109410D03*
Y102323D03*
Y123583D03*
X1277357Y130670D03*
Y123583D03*
X1285357Y130670D03*
X1273555Y137756D03*
X1285357D03*
X1285137Y162368D03*
X1275992Y215478D03*
Y212978D03*
Y210478D03*
Y207978D03*
X1286448Y213213D03*
Y210713D03*
Y208213D03*
X1275992Y223726D03*
Y226226D03*
Y231226D03*
Y228726D03*
X1286448Y226461D03*
Y228961D03*
Y231461D03*
Y215713D03*
X1281821Y264180D03*
X1279321D03*
X1279246Y258880D03*
X1279538Y293796D03*
X1282038D03*
X1271571Y281185D03*
X1283494Y339495D03*
X1284419Y359377D03*
X1281834Y374839D03*
X1280699Y377173D03*
X1284659D03*
X1274436Y377350D03*
X1275940Y392228D03*
X1271346Y392183D03*
X1276659Y385123D03*
X1275407Y402867D03*
X1271391Y396866D03*
X1275984D03*
X1278724Y409032D03*
X1282760Y401066D03*
X1272421Y403300D03*
X1271828Y405889D03*
Y408489D03*
Y413689D03*
Y411089D03*
Y416289D03*
Y421489D03*
Y418889D03*
Y424089D03*
X1272215Y442518D03*
Y439718D03*
Y432718D03*
Y435518D03*
X1282092Y442118D03*
Y439318D03*
X1271828Y426689D03*
X1279127Y450091D03*
X1282092Y449118D03*
Y446318D03*
X1281737Y452740D03*
X1272927Y450091D03*
X1275927D03*
X1273397Y447081D03*
X1283455Y468088D03*
Y465288D03*
X1280616Y472189D03*
X1272927Y462060D03*
X1275927D03*
X1279505Y487570D03*
Y490070D03*
X1286005Y485580D03*
X1280631Y480194D03*
Y477694D03*
X1277897Y478876D03*
Y476376D03*
X1274415Y477053D03*
X1271915D03*
X1276060Y496258D03*
X1273451Y491870D03*
X1276060Y493758D03*
X1283400Y715500D03*
Y719700D03*
X1279539Y748576D03*
X1282539Y751076D03*
X1279539Y763576D03*
X1282539Y766076D03*
X1279539Y758576D03*
X1282539Y761076D03*
X1279539Y753576D03*
Y772576D03*
Y768576D03*
Y780576D03*
Y784576D03*
X1285092Y819500D03*
X1285500Y827500D03*
X1281388Y827388D03*
X1281331Y843331D03*
X1285500Y835500D03*
X1283025Y848305D03*
X1274417Y861964D03*
X1271438Y861846D03*
X1285500Y863500D03*
Y859500D03*
Y855500D03*
X1282317Y880193D03*
X1285500Y867500D03*
X1279460Y869487D03*
X1285302Y877283D03*
X1282285Y865602D03*
X1285493Y892175D03*
X1285302Y885783D03*
Y881783D03*
X1281075Y911075D03*
X1282184Y898854D03*
X1283494Y907176D03*
X1277039Y916484D03*
X1275493Y929858D03*
X1279493D03*
X1284021Y940008D03*
X1281400Y940256D03*
X1281733Y949475D03*
X1275788Y1124088D03*
X1273865Y1132497D03*
X1282421Y1137129D03*
X1271921Y1134729D03*
X1275794D03*
X1282830Y1146937D03*
Y1150087D03*
X1272120Y1159455D03*
X1280306Y1162817D03*
Y1170767D03*
X1276573Y1193019D03*
X1280573D03*
X1272573D03*
X1272541Y1201043D03*
X1276575Y1201039D03*
X1280575Y1200969D03*
X1277108Y1211664D03*
X1279402Y1213958D03*
X1284198Y1218754D03*
X1280694Y1208993D03*
X1274446Y1228226D03*
X1272235Y1226016D03*
X1291756Y-48669D03*
X1288503D03*
X1291741Y-46154D03*
X1288488D03*
X1294781Y-47349D03*
X1300183Y-44434D03*
X1288500Y-40964D03*
X1291756Y-38369D03*
X1288503Y-38355D03*
X1288500Y-43464D03*
X1291741Y-35854D03*
X1288500Y-32950D03*
X1288488Y-35840D03*
X1288500Y-30350D03*
X1294781Y-37049D03*
X1300183Y-29478D03*
Y-34434D03*
Y-39478D03*
X1297687Y-40256D03*
Y-43656D03*
X1291756Y-25143D03*
X1288503Y-25157D03*
X1291741Y-27658D03*
X1288488Y-27672D03*
X1294781Y-26463D03*
X1302232Y3000D03*
X1295692Y5374D03*
X1303229Y23274D03*
X1295005Y24773D03*
X1297785Y30618D03*
Y33768D03*
X1302785Y31168D03*
X1295005Y44773D03*
X1302649Y94017D03*
X1298640D03*
X1290640D03*
X1294369Y101701D03*
X1294640Y94017D03*
X1294369Y98551D03*
X1301919Y103783D03*
X1299760Y110445D03*
Y115401D03*
X1294768Y110445D03*
Y115401D03*
X1297919Y103783D03*
X1288115Y104249D03*
Y107649D03*
X1294768Y129574D03*
X1299760D03*
Y124618D03*
X1294768D03*
X1294837Y162793D03*
X1287737Y162368D03*
X1294837Y165393D03*
Y167993D03*
Y170493D03*
X1299840Y181009D03*
X1293834Y181426D03*
X1297045Y181366D03*
X1296331Y191941D03*
X1302831Y184619D03*
X1294042Y184221D03*
X1296659Y184012D03*
X1301781Y213132D03*
X1298078Y211359D03*
Y213859D03*
X1290520Y211695D03*
X1293020D03*
X1290520Y208695D03*
X1290155Y226141D03*
X1294417Y229286D03*
X1298110Y222212D03*
Y224712D03*
X1301781Y215632D03*
X1290398Y236611D03*
X1295398D03*
X1292898D03*
X1294417Y231786D03*
X1298025Y256535D03*
X1290100Y248891D03*
X1292600D03*
X1295100D03*
X1302025Y256303D03*
X1293515Y270026D03*
X1291015D03*
X1288215D03*
Y267526D03*
X1293515D03*
X1291015D03*
X1290052Y288190D03*
X1292852D03*
Y285690D03*
X1297078Y290755D03*
X1301078D03*
X1287552Y288190D03*
X1290052Y285690D03*
X1287552D03*
X1301500Y329000D03*
X1294425Y321425D03*
X1294000Y324000D03*
X1303000Y326692D03*
X1292731Y331820D03*
X1300400Y339619D03*
Y344575D03*
X1293000Y338500D03*
X1303000Y331000D03*
X1302896Y343797D03*
Y340397D03*
X1299959Y351454D03*
X1294080Y349820D03*
X1303158Y371043D03*
X1291410Y371060D03*
X1295410Y371076D03*
X1291165Y395248D03*
X1293100Y409539D03*
X1296100D03*
Y407039D03*
X1295764Y401981D03*
X1298264D03*
X1300037Y398278D03*
X1297537D03*
X1292618Y413611D03*
X1295118D03*
X1300118D03*
X1297618D03*
X1292383Y424067D03*
X1294883D03*
X1299883D03*
X1297383D03*
X1299757Y438293D03*
Y441093D03*
X1290092Y442118D03*
Y439318D03*
Y449118D03*
Y446318D03*
X1299757Y450041D03*
Y452841D03*
Y455641D03*
X1290272Y458309D03*
Y454309D03*
X1299757Y443893D03*
X1290272Y462309D03*
X1287719Y470001D03*
X1290219D03*
X1288144Y489036D03*
X1291005Y485580D03*
X1288505D03*
X1301314Y484882D03*
X1290380Y495636D03*
Y492836D03*
X1296783Y511956D03*
X1300817Y568635D03*
X1289317Y706932D03*
X1295491Y798821D03*
X1290066Y804246D03*
X1289730Y806845D03*
X1300516Y832047D03*
X1296770Y828775D03*
X1300504Y835985D03*
X1300204Y859088D03*
X1300097Y851193D03*
X1300091Y854824D03*
X1293500Y879800D03*
Y871800D03*
Y875800D03*
X1288164Y892354D03*
X1296866Y894993D03*
X1293272Y887800D03*
X1293500Y883800D03*
X1291955Y901295D03*
X1294264Y905595D03*
X1301657Y899129D03*
X1288500Y901254D03*
X1298966Y899610D03*
X1296466D03*
X1289547Y928047D03*
X1298000Y917000D03*
X1294075D03*
X1292500Y928000D03*
X1298090Y940852D03*
X1295453Y940953D03*
X1302500Y939500D03*
X1296500Y961500D03*
X1289500Y949500D03*
X1300500Y960000D03*
X1290792Y961363D03*
X1300500Y970187D03*
X1292836Y975244D03*
X1292631Y979845D03*
X1299717Y1024136D03*
X1297852Y1014475D03*
X1295815Y1124943D03*
X1295893Y1122182D03*
X1302866Y1461182D03*
Y1456451D03*
Y1465913D03*
Y1476536D03*
Y1471805D03*
Y1481267D03*
Y1491890D03*
Y1487159D03*
Y1496621D03*
Y1507245D03*
Y1502514D03*
Y1511976D03*
Y1558813D03*
Y1563544D03*
Y1578898D03*
Y1574167D03*
Y1568275D03*
Y1594253D03*
Y1589522D03*
Y1583629D03*
Y1609607D03*
Y1598984D03*
Y1604876D03*
Y1614338D03*
X1292000Y1644980D03*
X1310853Y37543D03*
X1318859Y45448D03*
X1307717Y84140D03*
Y76140D03*
Y80140D03*
X1310162Y117557D03*
X1305170D03*
X1313086Y103621D03*
X1304854Y106186D03*
X1316277Y112083D03*
X1310162Y122513D03*
Y131731D03*
X1305170Y122513D03*
Y131731D03*
X1310162Y136687D03*
X1305170D03*
X1313546Y180527D03*
X1308863Y180572D03*
X1305015Y168697D03*
X1308863Y185165D03*
X1317269Y192421D03*
X1313501Y185121D03*
X1306103Y191941D03*
X1319432Y190185D03*
X1310115Y192300D03*
X1304811Y206760D03*
X1308112Y206767D03*
X1313112D03*
X1310612D03*
X1313242Y221708D03*
X1310742D03*
X1309357Y228221D03*
X1317592Y221642D03*
X1308242Y221708D03*
X1307657Y224421D03*
X1309908Y236189D03*
X1314908D03*
X1312408D03*
X1306025Y256535D03*
X1312349Y248765D03*
X1309849D03*
X1314849D03*
X1307055Y279208D03*
X1310046Y268195D03*
X1312546D03*
X1315346D03*
X1319006Y265897D03*
X1312546Y270695D03*
X1310046D03*
X1315346D03*
X1313149Y288345D03*
Y290845D03*
Y293645D03*
X1315649Y288345D03*
Y290845D03*
Y293645D03*
X1318362Y310562D03*
X1314569Y318013D03*
X1312069D03*
X1317584Y313058D03*
X1305928Y318250D03*
X1308428D03*
X1315256Y336510D03*
X1315397Y333709D03*
X1316017Y349889D03*
X1308410Y370899D03*
X1305910Y377581D03*
X1310172Y367956D03*
X1311283Y370801D03*
X1308826Y389402D03*
X1306113Y383817D03*
X1312626Y387702D03*
X1315426D03*
X1306113Y386317D03*
Y388817D03*
X1313691Y402642D03*
X1316191D03*
X1310546Y409904D03*
X1309117Y398949D03*
X1306617Y401949D03*
X1310866Y413611D03*
X1313366D03*
X1315866D03*
X1315806Y423944D03*
X1313306D03*
X1310806D03*
X1309750Y438293D03*
Y441093D03*
Y455641D03*
Y450041D03*
Y452841D03*
Y443893D03*
X1308010Y466409D03*
X1311488Y471560D03*
X1307835Y470382D03*
X1307996Y487382D03*
X1311488Y479560D03*
X1307919Y478382D03*
X1307825Y482382D03*
X1311488Y475560D03*
X1318160Y520053D03*
X1317945Y523058D03*
X1319000Y566500D03*
Y562500D03*
Y558500D03*
Y582500D03*
Y586500D03*
Y574500D03*
Y578500D03*
Y605000D03*
Y590500D03*
Y613000D03*
Y621000D03*
Y609000D03*
Y629000D03*
Y633000D03*
Y625000D03*
Y637000D03*
Y653500D03*
Y649500D03*
Y657500D03*
Y669500D03*
Y665500D03*
Y673500D03*
Y681500D03*
Y677500D03*
Y696500D03*
Y700500D03*
Y704500D03*
Y712500D03*
Y716500D03*
Y720500D03*
Y724500D03*
Y728500D03*
Y732500D03*
X1305412Y799061D03*
X1317000Y788000D03*
X1313000D03*
X1305134Y812065D03*
X1319000Y811620D03*
X1317000Y804000D03*
X1313000D03*
X1310715Y820491D03*
Y822991D03*
Y817991D03*
X1310687Y830206D03*
Y832706D03*
Y827706D03*
X1308857Y836076D03*
X1310971Y842319D03*
X1305786Y867704D03*
X1310994Y866859D03*
X1309753Y877589D03*
X1305740Y877534D03*
X1310535Y870775D03*
X1308220Y889253D03*
X1311061Y889361D03*
X1319500Y901500D03*
X1305356Y902597D03*
X1319500Y905000D03*
X1316893Y925603D03*
X1313867Y925605D03*
X1311325Y928918D03*
X1319554Y925585D03*
X1318375Y943951D03*
X1309103Y936559D03*
X1306500Y936500D03*
X1315779Y943743D03*
X1303907Y960093D03*
X1311000Y961500D03*
X1307000Y970000D03*
X1307580Y990314D03*
X1317254Y990777D03*
X1317053Y988111D03*
X1319874Y989856D03*
X1304664Y1023462D03*
X1309937Y1037038D03*
X1319326Y1040723D03*
X1315606Y1042825D03*
X1312873Y1036543D03*
X1319221Y1058097D03*
Y1060697D03*
X1313459Y1081599D03*
X1310589Y1097278D03*
X1313089D03*
X1316869Y1107997D03*
X1319069Y1112397D03*
X1318969Y1109397D03*
X1316869Y1113797D03*
Y1110897D03*
X1317437Y1152684D03*
Y1160834D03*
X1318178Y1198321D03*
Y1200821D03*
Y1192621D03*
Y1190121D03*
X1319237Y1221428D03*
X1311237D03*
X1315237D03*
X1311237Y1233428D03*
Y1229428D03*
Y1225428D03*
X1315237Y1237428D03*
Y1233428D03*
Y1229428D03*
Y1225428D03*
X1319237Y1237428D03*
Y1233428D03*
Y1229428D03*
X1307167Y1245696D03*
X1315237Y1241428D03*
X1319237D03*
X1308276Y1276446D03*
X1308107Y1283395D03*
X1310773Y1282411D03*
X1303900Y1288000D03*
X1318287Y1295381D03*
X1311527Y1465513D03*
Y1460782D03*
Y1480867D03*
Y1476136D03*
Y1470244D03*
Y1491490D03*
Y1485598D03*
Y1496221D03*
Y1506845D03*
Y1500952D03*
Y1511576D03*
Y1516307D03*
Y1563144D03*
Y1567875D03*
Y1578498D03*
Y1572606D03*
Y1583229D03*
Y1593853D03*
Y1587960D03*
Y1609207D03*
Y1598584D03*
Y1603315D03*
Y1613938D03*
Y1618669D03*
X1312000Y1644980D03*
X1328500Y-80100D03*
X1331756Y-77419D03*
X1328503Y-77405D03*
X1331756Y-87805D03*
X1328503D03*
X1328500Y-82600D03*
X1331741Y-85290D03*
X1328488D03*
X1334781Y-86499D03*
X1331741Y-74904D03*
X1328500Y-72000D03*
X1328488Y-74890D03*
X1331756Y-64193D03*
X1328503Y-64207D03*
X1331741Y-66708D03*
X1328488Y-66722D03*
X1328500Y-69400D03*
X1334781Y-76099D03*
Y-65513D03*
X1322232Y3000D03*
X1334223Y33425D03*
X1331073Y33400D03*
X1322853Y37530D03*
X1321092Y117261D03*
X1328799Y172665D03*
Y180665D03*
Y168665D03*
Y176665D03*
X1320898Y186629D03*
X1328799Y192665D03*
Y196665D03*
X1328912Y186778D03*
X1328831Y212864D03*
Y200864D03*
Y204864D03*
Y221864D03*
Y216864D03*
X1324472Y219379D03*
X1321506Y265897D03*
X1330414Y310058D03*
X1325458D03*
X1334110Y310562D03*
X1321762D03*
X1329636Y307562D03*
X1326236D03*
X1322540Y313058D03*
X1333332D03*
X1332563Y326356D03*
X1325573Y326719D03*
X1331085Y334347D03*
X1323816D03*
Y341615D03*
X1331085Y348868D03*
X1323816D03*
X1326489Y356945D03*
X1331005Y356670D03*
X1320903Y370995D03*
X1333331Y370905D03*
X1329064Y370951D03*
X1325007D03*
X1334109Y373401D03*
X1334285Y386567D03*
X1331606D03*
X1328896D03*
X1320594Y387151D03*
Y382151D03*
Y384651D03*
X1333049Y399268D03*
Y401768D03*
Y396768D03*
X1321016Y399161D03*
Y401661D03*
Y396661D03*
X1325941Y408240D03*
X1328441D03*
X1323441D03*
X1326059Y420393D03*
X1326020Y424240D03*
X1323559Y420393D03*
X1328559D03*
X1326020Y426740D03*
X1329097Y435321D03*
Y438121D03*
X1326297Y435321D03*
Y438121D03*
X1329097Y440921D03*
X1326297D03*
X1329626Y455039D03*
X1329097Y443721D03*
X1326297D03*
X1332927Y468607D03*
X1325927Y474513D03*
X1329606Y459170D03*
X1326912Y493153D03*
X1325630Y513238D03*
X1321450Y520268D03*
X1321164Y523130D03*
X1331096Y549931D03*
X1335000Y586500D03*
Y594500D03*
X1327000Y609000D03*
Y621000D03*
X1335000Y637000D03*
Y641000D03*
X1327011Y646064D03*
X1335000Y677500D03*
Y681500D03*
Y685500D03*
Y724500D03*
Y728500D03*
Y732500D03*
X1326970Y736464D03*
X1330324Y779030D03*
X1333000Y788000D03*
X1329000D03*
X1321000D03*
X1325000D03*
X1331000Y811620D03*
X1327000D03*
X1329000Y804000D03*
X1325000D03*
X1333000D03*
X1323000Y811620D03*
X1335000D03*
X1335803Y826500D03*
X1323205Y867665D03*
X1331056Y904557D03*
X1336000Y900500D03*
X1324000Y901000D03*
X1331078Y900500D03*
X1330500Y925500D03*
X1334500D03*
X1333425Y930925D03*
X1324000D03*
X1329199Y933825D03*
X1328457Y959986D03*
X1335343Y961727D03*
X1321028Y961749D03*
X1332500Y961500D03*
X1321104Y964398D03*
X1323554Y967623D03*
X1332000Y969500D03*
X1327000D03*
X1329503Y991088D03*
X1334909Y990340D03*
X1332404Y988215D03*
X1329834Y988132D03*
X1324735Y989966D03*
X1327267Y988271D03*
X1322427Y988221D03*
X1333974Y1033483D03*
X1320549Y1037876D03*
X1322773Y1040599D03*
X1331890Y1051919D03*
X1329221Y1058097D03*
X1321721D03*
X1324221D03*
X1326721D03*
Y1060697D03*
X1329221D03*
X1321721D03*
X1324221D03*
X1326163Y1082501D03*
X1326189Y1085205D03*
X1329163Y1082501D03*
X1329189Y1085205D03*
X1326189Y1088205D03*
X1326471Y1091227D03*
X1329189Y1088205D03*
X1323189Y1085205D03*
Y1087705D03*
X1323163Y1082501D03*
X1323021Y1090956D03*
X1331359Y1098898D03*
X1334956Y1105552D03*
X1321069Y1107997D03*
X1323021Y1093956D03*
X1331162Y1104792D03*
X1332669Y1106867D03*
X1333905Y1123101D03*
X1331405D03*
X1323405D03*
X1321169Y1110597D03*
X1321954Y1113648D03*
X1326254D03*
X1328754D03*
X1323405Y1118801D03*
Y1116101D03*
X1320279Y1131935D03*
Y1134435D03*
Y1136935D03*
Y1139435D03*
X1334305Y1129301D03*
X1331805D03*
X1329305D03*
X1326805D03*
X1324305D03*
X1321805D03*
X1334305Y1125801D03*
X1331805D03*
X1323405D03*
X1320279Y1141935D03*
Y1146935D03*
Y1144435D03*
X1326269Y1152713D03*
Y1155213D03*
X1325635Y1172384D03*
Y1162384D03*
Y1164884D03*
Y1167384D03*
Y1169884D03*
X1323135Y1172384D03*
Y1162384D03*
Y1164884D03*
Y1167384D03*
Y1169884D03*
X1334793Y1179421D03*
Y1181921D03*
Y1184421D03*
Y1186921D03*
X1320493Y1186709D03*
Y1184209D03*
Y1181709D03*
Y1179209D03*
X1325635Y1174884D03*
X1323135D03*
X1320493Y1204405D03*
X1334793Y1204617D03*
X1331643Y1200821D03*
Y1198321D03*
Y1192621D03*
Y1190121D03*
X1320493Y1206905D03*
Y1211905D03*
Y1209405D03*
X1334793Y1207117D03*
Y1209617D03*
Y1212117D03*
X1327237Y1221428D03*
X1331237D03*
X1335237D03*
X1323237D03*
X1327237Y1237428D03*
Y1233428D03*
Y1229428D03*
Y1225428D03*
X1331237Y1237428D03*
Y1233428D03*
Y1225428D03*
X1335237Y1233428D03*
Y1229428D03*
Y1225428D03*
X1323237Y1233428D03*
Y1229428D03*
Y1225428D03*
X1335237Y1241428D03*
X1323237Y1245428D03*
Y1241428D03*
X1327237Y1245428D03*
Y1241428D03*
X1331237Y1245428D03*
Y1241428D03*
X1335237Y1245428D03*
X1333876Y1257160D03*
Y1260160D03*
X1324886Y1278962D03*
X1330070Y1297498D03*
X1335470D03*
X1328850Y1465513D03*
Y1460782D03*
X1320189Y1465913D03*
Y1456451D03*
Y1461182D03*
X1328850Y1476136D03*
Y1470244D03*
X1320189Y1481267D03*
X1328850Y1480867D03*
X1320189Y1471805D03*
Y1476536D03*
X1328850Y1491490D03*
Y1485598D03*
X1320189Y1496621D03*
X1328850Y1496221D03*
X1320189Y1487159D03*
Y1491890D03*
Y1502514D03*
X1328850Y1506845D03*
Y1500952D03*
Y1511576D03*
X1320189Y1511976D03*
Y1507245D03*
X1328850Y1516307D03*
X1320189Y1558813D03*
Y1563544D03*
X1328850Y1563144D03*
Y1567875D03*
X1320189Y1574167D03*
Y1578898D03*
X1328850Y1578498D03*
Y1572606D03*
X1320189Y1568275D03*
X1328850Y1583229D03*
X1320189Y1589522D03*
Y1594253D03*
X1328850Y1593853D03*
Y1587960D03*
X1320189Y1583629D03*
X1328850Y1603315D03*
X1320189Y1609607D03*
Y1604876D03*
Y1598984D03*
X1328850Y1609207D03*
Y1598584D03*
Y1613938D03*
Y1618669D03*
X1320189Y1614338D03*
X1332000Y1644980D03*
X1340183Y-83484D03*
Y-78528D03*
X1337687Y-79306D03*
Y-82706D03*
X1340183Y-68528D03*
Y-73484D03*
X1342232Y3000D03*
X1336646Y22627D03*
X1336551Y26534D03*
X1340320Y147540D03*
X1344092Y141247D03*
X1340320Y151540D03*
X1348419Y265222D03*
X1340104Y279117D03*
X1337510Y310562D03*
X1338288Y313058D03*
X1338378Y334347D03*
X1338275Y341603D03*
X1346009Y336080D03*
X1346093Y340805D03*
X1338378Y348830D03*
X1346065Y347106D03*
X1338471Y356959D03*
X1338287Y370905D03*
X1337509Y373401D03*
X1342810Y408104D03*
X1345610D03*
X1348410D03*
X1336388Y424939D03*
X1342527Y420375D03*
X1345327D03*
X1348127D03*
X1347897Y433975D03*
X1346483Y436164D03*
X1336388Y427439D03*
X1347846Y461607D03*
X1339846D03*
X1339049Y471334D03*
X1343846Y461607D03*
X1346378Y623734D03*
X1345451Y699032D03*
X1344768Y737675D03*
Y741675D03*
Y745675D03*
Y749675D03*
Y753675D03*
Y761675D03*
Y757675D03*
X1336450Y765675D03*
X1347136Y780040D03*
X1344768Y773675D03*
Y781350D03*
X1341000Y788000D03*
X1345000D03*
X1337000D03*
X1348917D03*
X1349000Y804000D03*
X1351000Y811620D03*
X1347000D03*
X1343000D03*
X1337000Y804000D03*
X1345000D03*
X1341000D03*
X1349976Y829000D03*
X1350000Y825500D03*
X1340000Y900000D03*
X1351500Y903000D03*
Y906500D03*
X1340000Y906000D03*
Y903000D03*
X1351511Y900000D03*
X1350500Y925500D03*
X1338500D03*
X1342500D03*
X1346500D03*
X1338500Y930500D03*
X1350500D03*
X1342500D03*
X1346500D03*
X1341820Y947407D03*
X1337514Y988259D03*
X1343465Y1026123D03*
X1340665D03*
X1343465Y1028923D03*
X1340665D03*
X1347380Y1057998D03*
Y1055498D03*
X1344880D03*
Y1057998D03*
X1347380Y1060498D03*
Y1062998D03*
X1344880D03*
Y1060498D03*
X1347552Y1091816D03*
Y1089316D03*
X1345052Y1081816D03*
Y1084316D03*
Y1086816D03*
X1347552D03*
Y1084316D03*
X1350418Y1090288D03*
X1347552Y1081816D03*
X1339349Y1098767D03*
X1344241Y1106298D03*
X1348997Y1107997D03*
X1350418Y1093088D03*
X1339234Y1101917D03*
X1339169Y1106897D03*
X1341984Y1110092D03*
X1345650Y1115896D03*
X1348997Y1113797D03*
Y1110897D03*
X1351197Y1112397D03*
X1351097Y1109397D03*
X1345650Y1118396D03*
X1339305Y1129301D03*
X1336805D03*
X1339305Y1125801D03*
X1336805D03*
X1343505Y1136935D03*
Y1134435D03*
Y1139435D03*
Y1131935D03*
X1349907D03*
Y1134435D03*
Y1136935D03*
Y1139435D03*
X1352407Y1131935D03*
Y1134435D03*
Y1136935D03*
Y1139435D03*
X1347300Y1128332D03*
X1343725Y1128738D03*
X1343505Y1146935D03*
Y1144435D03*
Y1141935D03*
X1349907D03*
Y1146935D03*
Y1144435D03*
X1352407Y1141935D03*
Y1146935D03*
Y1144435D03*
X1336669Y1152713D03*
Y1155213D03*
X1351405Y1154902D03*
Y1152402D03*
X1343905Y1162384D03*
Y1164884D03*
Y1167384D03*
Y1169884D03*
Y1172384D03*
X1341405D03*
Y1169884D03*
Y1167384D03*
Y1164884D03*
Y1162384D03*
X1350963Y1172384D03*
Y1169884D03*
Y1167384D03*
Y1164884D03*
Y1162384D03*
X1351149Y1158200D03*
X1347423Y1186709D03*
Y1184209D03*
Y1181709D03*
Y1179209D03*
X1343905Y1174884D03*
X1341405D03*
X1350963D03*
X1347423Y1204405D03*
X1337108Y1200821D03*
Y1198321D03*
X1345108Y1200821D03*
Y1198321D03*
X1337108Y1192621D03*
Y1190121D03*
X1345108D03*
Y1192621D03*
X1347423Y1209405D03*
Y1211905D03*
Y1206905D03*
X1347237Y1221428D03*
X1343237D03*
X1339237D03*
X1347237Y1237428D03*
Y1233428D03*
Y1229428D03*
X1343237D03*
Y1233428D03*
Y1237428D03*
X1339237D03*
Y1233428D03*
Y1229428D03*
Y1225428D03*
X1347237Y1245428D03*
Y1241428D03*
X1343237Y1245428D03*
X1339237D03*
Y1241428D03*
X1339876Y1257160D03*
X1342876D03*
X1345876Y1260160D03*
Y1257160D03*
X1348876Y1260160D03*
Y1257160D03*
X1351876D03*
X1336876Y1260160D03*
Y1257160D03*
X1342876Y1260160D03*
X1339876D03*
X1340870Y1297498D03*
X1346270D03*
X1351670D03*
X1337512Y1461182D03*
X1346173Y1465513D03*
Y1460782D03*
X1337512Y1465913D03*
Y1456451D03*
X1346173Y1476136D03*
Y1470244D03*
X1337512Y1481267D03*
X1346173Y1480867D03*
X1337512Y1471805D03*
Y1476536D03*
X1346173Y1485598D03*
Y1491490D03*
X1337512Y1487159D03*
Y1491890D03*
Y1496621D03*
X1346173Y1496221D03*
X1337512Y1507245D03*
Y1502514D03*
X1346173Y1506845D03*
Y1500952D03*
Y1511576D03*
X1337512Y1511976D03*
X1346173Y1516307D03*
X1337512Y1558813D03*
Y1563544D03*
X1346173Y1563144D03*
X1337512Y1574167D03*
Y1578898D03*
X1346173Y1578498D03*
Y1572606D03*
X1337512Y1568275D03*
X1346173Y1567875D03*
X1337512Y1583629D03*
X1346173Y1583229D03*
X1337512Y1589522D03*
Y1594253D03*
X1346173Y1593853D03*
Y1587960D03*
X1337512Y1609607D03*
Y1604876D03*
Y1598984D03*
X1346173Y1609207D03*
Y1598584D03*
Y1603315D03*
X1337512Y1614338D03*
X1346173Y1613938D03*
Y1618669D03*
X1352000Y1644980D03*
X1362232Y3000D03*
X1355900Y146461D03*
X1354802Y152367D03*
X1366859Y152562D03*
X1361039Y327099D03*
X1363535Y327877D03*
X1361039Y332055D03*
X1364039Y334973D03*
Y339929D03*
X1361039Y342847D03*
X1366535Y335751D03*
Y339151D03*
X1363535Y331277D03*
Y343625D03*
X1364039Y350721D03*
X1361039Y347803D03*
X1364039Y355677D03*
X1366535Y354899D03*
Y351499D03*
X1363535Y347025D03*
X1360719Y424601D03*
X1360352Y447101D03*
X1355255Y607532D03*
X1352817Y788000D03*
X1363000Y811620D03*
X1353000Y804000D03*
X1359000Y811620D03*
X1357000Y804000D03*
X1361000D03*
X1354185Y906498D03*
X1367000Y904500D03*
X1363000Y900500D03*
X1367000D03*
X1354500Y925500D03*
X1366500D03*
X1358500D03*
X1362500D03*
Y930500D03*
X1366500D03*
X1354500D03*
X1358500D03*
X1363173Y994483D03*
X1363905Y1000855D03*
X1366493Y1000828D03*
X1364765Y1004766D03*
X1367444Y1003763D03*
X1367884Y1018825D03*
X1357265Y1022766D03*
X1357765Y1019766D03*
X1361265D03*
X1357265Y1026266D03*
X1364237Y1043140D03*
X1357265Y1030266D03*
Y1034266D03*
X1363941Y1047047D03*
X1364418Y1090568D03*
Y1093068D03*
X1361037Y1098428D03*
X1367084Y1105552D03*
X1353197Y1107997D03*
X1363290Y1104792D03*
X1364797Y1106867D03*
X1355533Y1123101D03*
X1363533D03*
X1366033D03*
X1353297Y1110597D03*
X1354082Y1113648D03*
X1355533Y1116101D03*
Y1118801D03*
X1360882Y1113648D03*
X1358382D03*
X1366433Y1129301D03*
X1355533Y1125801D03*
X1363933D03*
X1366433D03*
X1353933Y1129301D03*
X1356433D03*
X1358933D03*
X1361433D03*
X1363933D03*
X1357397Y1155213D03*
Y1152713D03*
X1366797D03*
Y1155213D03*
X1353463Y1172384D03*
Y1169884D03*
Y1167384D03*
Y1164884D03*
Y1162384D03*
X1361723Y1179421D03*
Y1181921D03*
Y1184421D03*
Y1186921D03*
X1353463Y1174884D03*
X1361723Y1204617D03*
X1364038Y1198321D03*
Y1200821D03*
Y1190121D03*
Y1192621D03*
X1361723Y1212117D03*
Y1209617D03*
Y1207117D03*
X1363876Y1260160D03*
Y1257160D03*
X1354876Y1260160D03*
X1357876D03*
X1360876Y1257160D03*
X1357876D03*
X1354876D03*
X1366876Y1260160D03*
Y1257160D03*
X1357070Y1297498D03*
X1354834Y1465913D03*
Y1456451D03*
Y1461182D03*
X1363496Y1465513D03*
Y1460782D03*
X1354834Y1481267D03*
X1363496Y1476136D03*
Y1470244D03*
Y1480867D03*
X1354834Y1471805D03*
Y1476536D03*
Y1487159D03*
Y1496621D03*
X1363496Y1485598D03*
Y1491490D03*
Y1496221D03*
X1354834Y1491890D03*
Y1502514D03*
Y1511976D03*
X1363496Y1511576D03*
Y1506845D03*
Y1500952D03*
X1354834Y1507245D03*
X1363496Y1516307D03*
X1354834Y1558813D03*
Y1563544D03*
X1363496Y1563144D03*
Y1572606D03*
X1354834Y1568275D03*
Y1574167D03*
Y1578898D03*
X1363496Y1567875D03*
Y1578498D03*
X1354834Y1583629D03*
Y1589522D03*
Y1594253D03*
X1363496Y1583229D03*
Y1593853D03*
Y1587960D03*
X1354834Y1609607D03*
Y1604876D03*
Y1598984D03*
X1363496Y1609207D03*
Y1598584D03*
Y1603315D03*
X1354834Y1614338D03*
X1363496Y1613938D03*
Y1618669D03*
X1382232Y3000D03*
X1376262Y113394D03*
X1378911Y110784D03*
X1380480Y102249D03*
X1384480D03*
X1376262Y116594D03*
X1378505Y133298D03*
X1376262Y119594D03*
X1380652Y134579D03*
X1375103Y161306D03*
X1372354Y157370D03*
X1384280Y195176D03*
X1381780D03*
X1384140Y203393D03*
X1381640D03*
X1384319Y218085D03*
X1378227Y252371D03*
Y248371D03*
X1384265Y320871D03*
Y325371D03*
X1383551Y337808D03*
X1384265Y329871D03*
X1384253Y346826D03*
X1384447Y356871D03*
X1375073D03*
Y361371D03*
X1383505Y349437D03*
X1372232Y361298D03*
X1384174Y362641D03*
X1373748Y397758D03*
X1377024Y397713D03*
X1375171Y424741D03*
X1375375Y428995D03*
X1375400Y435192D03*
X1375360Y432234D03*
X1383556Y558338D03*
X1383608Y571927D03*
X1383184Y587653D03*
X1383000Y584500D03*
X1383556Y604838D03*
X1383425Y590425D03*
X1383608Y618427D03*
X1381118Y634033D03*
X1383425Y636925D03*
X1378957Y630957D03*
X1383425Y640075D03*
X1381244Y673623D03*
X1383425Y684140D03*
Y681425D03*
X1383000Y675500D03*
X1381932Y722547D03*
X1383425Y731575D03*
Y728425D03*
X1378957Y722457D03*
X1371000Y811620D03*
X1373000Y804000D03*
X1369000D03*
X1381428Y812287D03*
X1375193Y811724D03*
X1376708Y901000D03*
X1374369Y925499D03*
X1370500Y925500D03*
X1382500D03*
X1374500Y930500D03*
X1370500D03*
X1378500D03*
X1371379Y986717D03*
X1383162Y991829D03*
X1370384Y1004680D03*
X1383669Y1011303D03*
X1373534Y1004680D03*
X1383669Y1017303D03*
Y1023303D03*
X1374034Y1015825D03*
X1376359Y1016825D03*
X1376601Y1030218D03*
X1373874Y1035716D03*
X1374451Y1090568D03*
Y1093068D03*
X1371477Y1098767D03*
X1377087Y1106365D03*
X1371362Y1101917D03*
X1371297Y1106897D03*
X1382456Y1107997D03*
X1374112Y1110092D03*
X1377778Y1115896D03*
X1384656Y1112397D03*
X1382456Y1110897D03*
Y1113797D03*
X1384556Y1109397D03*
X1377778Y1118396D03*
X1375633Y1136935D03*
Y1134435D03*
Y1139435D03*
Y1131935D03*
X1383366D03*
Y1134435D03*
Y1136935D03*
Y1139435D03*
X1368933Y1125801D03*
X1371433D03*
X1368933Y1129301D03*
X1371433D03*
X1383024Y1152684D03*
X1376861D03*
X1375633Y1146935D03*
Y1144435D03*
Y1141935D03*
X1383366D03*
Y1146935D03*
Y1144435D03*
X1369233Y1169884D03*
Y1172384D03*
X1371733D03*
Y1169884D03*
Y1167384D03*
Y1164884D03*
Y1162384D03*
X1369233D03*
Y1164884D03*
Y1167384D03*
X1376861Y1160834D03*
X1383024D03*
X1369233Y1174884D03*
X1371733D03*
X1375459Y1197471D03*
Y1193471D03*
X1379959Y1197471D03*
Y1193471D03*
X1377390Y1244055D03*
Y1250760D03*
Y1254164D03*
X1372300Y1422900D03*
X1379858Y1420701D03*
X1372157Y1461183D03*
Y1456452D03*
Y1465914D03*
Y1471806D03*
Y1476537D03*
Y1481268D03*
Y1487160D03*
Y1491891D03*
Y1496622D03*
Y1502515D03*
Y1507246D03*
Y1511977D03*
Y1558813D03*
Y1563544D03*
Y1568275D03*
Y1574167D03*
Y1578898D03*
Y1583629D03*
Y1589522D03*
Y1594253D03*
Y1604876D03*
Y1598984D03*
Y1609607D03*
Y1614338D03*
X1372000Y1644980D03*
X1398216Y4469D03*
X1399577Y24773D03*
Y44773D03*
X1391497Y109172D03*
X1394497D03*
X1393504Y106495D03*
X1397248Y116497D03*
X1388231Y116594D03*
X1393504Y102495D03*
X1386505Y133298D03*
X1397248Y130670D03*
Y123584D03*
X1388231Y119594D03*
X1393238Y146012D03*
X1395144Y141228D03*
X1397248Y137757D03*
X1393238Y142862D03*
X1398032Y150847D03*
X1386399Y198883D03*
X1386780Y195176D03*
X1399327D03*
X1396827D03*
X1400845Y199248D03*
X1390328Y206838D03*
X1387828D03*
X1400845Y201748D03*
X1398681Y206806D03*
X1401181D03*
X1399408Y210509D03*
X1396908D03*
X1390832Y216970D03*
Y219470D03*
X1390898Y226320D03*
X1390832Y221970D03*
X1388119Y216385D03*
X1400000Y247292D03*
X1399226Y238689D03*
X1392790Y236121D03*
X1389824Y238589D03*
X1397585Y242078D03*
X1392816Y232971D03*
X1392709Y253198D03*
X1385943Y323222D03*
X1385971Y327688D03*
X1386143Y331982D03*
X1386057Y341200D03*
X1385971Y336791D03*
X1386286Y350218D03*
X1387847Y366710D03*
X1397550Y390484D03*
X1400231Y390256D03*
X1387814Y397136D03*
X1389295Y408443D03*
X1396528Y397454D03*
X1399571Y397418D03*
X1393575Y397310D03*
X1390553Y397436D03*
X1391623Y409900D03*
X1386809Y414173D03*
X1387125Y417312D03*
X1393177Y424804D03*
X1389431Y421593D03*
X1388788Y428348D03*
X1393208Y428109D03*
X1393336Y431100D03*
X1393944Y507856D03*
X1394044Y510990D03*
X1397079Y536726D03*
Y527726D03*
Y552726D03*
Y540726D03*
Y548726D03*
X1395605Y556217D03*
X1390741Y565000D03*
X1391086Y577192D03*
X1400912Y581222D03*
X1391087Y581317D03*
X1400912Y591215D03*
X1398946Y621311D03*
X1390741Y611500D03*
Y607500D03*
Y615500D03*
X1391587Y627817D03*
X1391586Y623692D03*
X1398946Y629311D03*
Y625311D03*
X1397000Y656000D03*
X1388414Y675000D03*
X1397000Y703000D03*
X1388241Y722000D03*
X1386335Y803704D03*
X1390537Y803679D03*
X1394537Y803653D03*
X1395955Y832697D03*
X1399872Y845109D03*
X1396916Y862829D03*
X1391316Y857849D03*
X1388488Y857822D03*
X1395561Y876204D03*
X1396163Y868597D03*
X1390182Y873460D03*
X1387582Y873487D03*
X1388479Y892923D03*
X1385979D03*
X1390979D03*
X1387504Y899931D03*
X1390541Y900086D03*
X1398247Y926261D03*
X1388980Y921075D03*
X1401000Y925789D03*
X1398854Y987277D03*
X1395669Y1011303D03*
X1389669D03*
X1395669Y1017303D03*
Y1023303D03*
X1389669D03*
X1385732Y1029482D03*
X1387813Y1030952D03*
X1399852Y1039779D03*
X1390322Y1057998D03*
Y1055498D03*
X1392822D03*
Y1057998D03*
X1390322Y1060498D03*
Y1062998D03*
X1392822D03*
Y1060498D03*
X1388523Y1090090D03*
X1392691Y1089224D03*
Y1086724D03*
Y1084224D03*
Y1081724D03*
X1390191D03*
Y1084224D03*
Y1086724D03*
X1394496Y1098428D03*
X1400543Y1105552D03*
X1396749Y1104792D03*
X1388451Y1093048D03*
X1386656Y1107997D03*
X1398256Y1106867D03*
X1388992Y1123101D03*
X1396992D03*
X1399492D03*
X1386756Y1110597D03*
X1394341Y1113648D03*
X1388992Y1118801D03*
Y1116101D03*
X1387541Y1113648D03*
X1391841D03*
X1385866Y1131935D03*
Y1134435D03*
Y1136935D03*
Y1139435D03*
X1388992Y1125801D03*
X1397392D03*
X1399892D03*
X1387392Y1129301D03*
X1389892D03*
X1392392D03*
X1394892D03*
X1397392D03*
X1399892D03*
X1391856Y1155213D03*
Y1152713D03*
X1385866Y1141935D03*
Y1146935D03*
Y1144435D03*
X1388722Y1162384D03*
Y1164884D03*
Y1167384D03*
Y1169884D03*
Y1172384D03*
X1391222Y1162384D03*
Y1164884D03*
Y1167384D03*
Y1169884D03*
Y1172384D03*
X1388722Y1174884D03*
X1391222D03*
X1393695Y1186709D03*
Y1184209D03*
Y1181709D03*
Y1179209D03*
Y1204405D03*
X1391380Y1200821D03*
Y1198321D03*
Y1190121D03*
Y1192621D03*
X1393695Y1206905D03*
Y1211905D03*
Y1209405D03*
X1385821Y1260160D03*
X1391821Y1257160D03*
X1394821D03*
X1385821D03*
X1388821D03*
X1397821Y1260160D03*
Y1257160D03*
X1400821Y1260160D03*
Y1257160D03*
X1388821Y1260160D03*
X1394821D03*
X1391821D03*
X1385992Y1285466D03*
X1390492D03*
X1385052Y1303139D03*
X1392000Y1644980D03*
X1406898Y53597D03*
X1417248Y95236D03*
X1402098Y95111D03*
X1417248Y102323D03*
X1409248Y109410D03*
Y102323D03*
X1404548Y116497D03*
X1402048D03*
X1404548Y109410D03*
X1409248Y116496D03*
X1406467Y106561D03*
X1402048Y130670D03*
Y123584D03*
X1404548Y123583D03*
X1409248Y130670D03*
Y123583D03*
X1404548Y130670D03*
X1409248Y137756D03*
X1402048Y137757D03*
X1401827Y195176D03*
X1404327D03*
X1405780Y213539D03*
X1403845Y202048D03*
X1407461Y238714D03*
X1403461D03*
X1402942Y246874D03*
X1405162Y244297D03*
X1408666Y324733D03*
X1402921Y322403D03*
X1409830Y347649D03*
X1404690Y362209D03*
X1416347Y384373D03*
X1416912Y386903D03*
X1416470Y381397D03*
X1402968Y390177D03*
X1416830Y407134D03*
X1411400Y398032D03*
X1414369Y398056D03*
X1413889Y415642D03*
X1415610Y417644D03*
X1411950Y448466D03*
X1414903Y469905D03*
X1406910Y487982D03*
Y478982D03*
Y483982D03*
X1411269Y481467D03*
X1406910Y499982D03*
X1416061Y504825D03*
X1413561D03*
X1411061D03*
X1406910Y495982D03*
Y491982D03*
X1416002Y517401D03*
X1413502D03*
X1411002D03*
X1416553Y522569D03*
Y525369D03*
X1415168Y531882D03*
X1412668D03*
X1409618Y531948D03*
X1401438Y534211D03*
X1408103Y555194D03*
X1410903D03*
X1415103D03*
X1408103Y563194D03*
X1410903D03*
X1408103Y571194D03*
X1410903D03*
X1415103Y563194D03*
Y571194D03*
X1406512Y581222D03*
X1403712D03*
X1416660D03*
X1403712Y591215D03*
X1406512D03*
X1416660D03*
X1405514Y611091D03*
X1401383Y611071D03*
X1416832Y610562D03*
Y607762D03*
X1407952Y641817D03*
X1405229Y652028D03*
X1405000Y656000D03*
Y660000D03*
X1410000Y685000D03*
Y681000D03*
X1404500Y675000D03*
X1405000Y699000D03*
X1410000Y689000D03*
Y701000D03*
Y697000D03*
Y705000D03*
Y709000D03*
Y713000D03*
X1405000Y707000D03*
Y703000D03*
X1410000Y733000D03*
X1404500Y722000D03*
X1410000Y729000D03*
Y725000D03*
Y749000D03*
Y745000D03*
Y741000D03*
Y757000D03*
Y753000D03*
Y761000D03*
X1413500Y832000D03*
Y828000D03*
Y848000D03*
Y840000D03*
Y836000D03*
Y844000D03*
Y864000D03*
Y860000D03*
Y856000D03*
Y852000D03*
Y872000D03*
Y868000D03*
Y888000D03*
X1404689Y910897D03*
X1413733Y911137D03*
X1412376Y907848D03*
X1414876D03*
X1417376D03*
X1409876D03*
X1413500Y904000D03*
Y900000D03*
X1417284Y911009D03*
X1413575Y915186D03*
X1416802Y936845D03*
X1416244Y942285D03*
X1413322Y958908D03*
X1405214Y965074D03*
X1404317Y989436D03*
X1411038Y985379D03*
X1416618Y992307D03*
X1401265Y989465D03*
X1407265D03*
X1414143Y985486D03*
X1402215Y1020440D03*
X1414851Y1058097D03*
X1412351D03*
X1407351D03*
X1409851D03*
X1417351D03*
X1414851Y1060697D03*
X1412351D03*
X1407351D03*
X1409851D03*
X1417351D03*
X1405677Y1086796D03*
X1408177D03*
X1410677D03*
X1413177D03*
X1415677D03*
Y1084296D03*
X1413177D03*
X1410677D03*
X1408177D03*
X1405677D03*
X1416005Y1090288D03*
X1404936Y1098767D03*
X1410546Y1106298D03*
X1404821Y1101917D03*
X1404756Y1106897D03*
X1416005Y1093088D03*
X1414584Y1107997D03*
X1411237Y1115896D03*
X1407571Y1110092D03*
X1414584Y1113797D03*
X1416784Y1112397D03*
X1414584Y1110897D03*
X1416684Y1109397D03*
X1411237Y1118396D03*
X1415494Y1139435D03*
Y1136935D03*
Y1134435D03*
Y1131935D03*
X1409092Y1136935D03*
Y1134435D03*
Y1139435D03*
Y1131935D03*
X1402392Y1125801D03*
X1404892D03*
X1402392Y1129301D03*
X1404892D03*
X1409425Y1129238D03*
X1413177Y1128894D03*
X1409092Y1141935D03*
X1416736Y1152713D03*
Y1155213D03*
X1402256D03*
Y1152713D03*
X1415494Y1144435D03*
Y1146935D03*
Y1141935D03*
X1409092Y1146935D03*
Y1144435D03*
X1409492Y1167384D03*
Y1169884D03*
Y1172384D03*
X1406992D03*
Y1169884D03*
X1416550Y1162384D03*
Y1164884D03*
Y1167384D03*
Y1169884D03*
Y1172384D03*
X1406992Y1167384D03*
Y1164884D03*
Y1162384D03*
X1409492D03*
Y1164884D03*
X1416736Y1158200D03*
X1416550Y1174884D03*
X1409492D03*
X1406992D03*
X1407995Y1179421D03*
Y1181921D03*
Y1184421D03*
Y1186921D03*
Y1204617D03*
X1410310Y1200821D03*
Y1198321D03*
X1404845D03*
Y1200821D03*
X1410310Y1192621D03*
Y1190121D03*
X1404845D03*
Y1192621D03*
X1407995Y1207117D03*
Y1209617D03*
Y1212117D03*
X1408736Y1222194D03*
X1412736D03*
X1416736D03*
X1408736Y1238194D03*
Y1234194D03*
Y1230194D03*
Y1226194D03*
X1412736Y1238194D03*
Y1234194D03*
Y1230194D03*
Y1226194D03*
X1416736Y1238194D03*
Y1234194D03*
Y1230194D03*
Y1226194D03*
X1412736Y1246194D03*
Y1242194D03*
X1416736Y1246194D03*
X1408736Y1242194D03*
Y1246194D03*
X1409821Y1260160D03*
X1412821D03*
Y1257160D03*
X1409821D03*
X1406821D03*
X1403821D03*
X1415821Y1260160D03*
Y1257160D03*
X1403821Y1260160D03*
X1406821D03*
X1409066Y1272899D03*
X1405066D03*
X1413066D03*
X1415903Y1282590D03*
X1404019Y1285290D03*
X1414346Y1303020D03*
X1410817Y1305417D03*
X1407825Y1426975D03*
X1408536Y1536570D03*
X1404239Y1547755D03*
X1407747Y1549054D03*
X1408044Y1559306D03*
X1403747Y1570433D03*
X1407255Y1571732D03*
X1412000Y1644980D03*
X1426898Y53597D03*
X1417710Y82984D03*
Y75184D03*
Y77784D03*
Y80384D03*
X1420264Y92849D03*
X1417710Y85584D03*
X1427181Y95236D03*
X1427224Y103037D03*
X1417500Y109410D03*
Y116496D03*
X1427358D03*
Y109410D03*
X1421700Y122900D03*
X1427358Y130670D03*
Y123583D03*
X1418725Y130670D03*
X1423515Y137756D03*
X1418720D03*
X1425993Y212978D03*
Y207978D03*
Y210478D03*
Y215478D03*
Y231226D03*
Y228726D03*
Y226226D03*
Y223726D03*
X1429322Y264180D03*
X1431822D03*
X1429247Y258880D03*
X1429539Y293796D03*
X1432039D03*
X1421005Y407616D03*
X1431019Y434508D03*
X1427019D03*
X1417903Y439919D03*
X1424196Y446352D03*
X1428782Y445874D03*
X1417856Y455466D03*
X1423427Y456839D03*
X1425927D03*
X1423427Y454339D03*
X1425927D03*
X1427484Y470045D03*
X1422903Y469905D03*
X1423427Y459339D03*
X1425927D03*
X1418903Y469905D03*
X1431484Y470045D03*
X1422499Y485138D03*
X1419650Y485128D03*
X1426384Y478625D03*
X1428084Y482425D03*
X1427499Y485138D03*
X1424999D03*
X1426384Y476125D03*
X1430930Y500086D03*
X1433310Y504699D03*
X1430810D03*
X1433012Y516979D03*
X1430512D03*
X1431493Y521804D03*
X1432955Y527449D03*
X1431493Y524304D03*
X1427800Y531378D03*
X1418253Y529169D03*
X1417668Y531882D03*
X1424129Y537658D03*
X1427832Y539731D03*
X1424129Y540458D03*
X1432590Y544895D03*
X1427832Y542231D03*
X1432890Y541895D03*
X1417903Y555194D03*
Y563194D03*
Y571194D03*
X1422260Y581222D03*
X1419460D03*
X1422260Y591215D03*
X1419460D03*
X1431000Y591000D03*
X1433114Y620653D03*
Y617853D03*
X1419632Y607762D03*
X1422432D03*
X1425232Y610562D03*
Y607762D03*
X1422432Y610562D03*
X1419632D03*
X1430944Y605443D03*
X1427233Y628183D03*
X1424389Y627948D03*
X1430481Y658153D03*
X1418000Y685000D03*
Y681000D03*
Y689000D03*
X1426000Y709000D03*
Y713000D03*
Y717000D03*
X1418000Y705000D03*
Y733000D03*
X1417969Y720894D03*
X1426000Y757000D03*
Y753000D03*
X1427000Y766500D03*
X1426000Y761000D03*
X1418023Y765343D03*
X1427000Y774500D03*
Y781834D03*
Y770500D03*
Y790500D03*
Y794500D03*
Y810500D03*
Y814500D03*
Y802500D03*
Y818500D03*
Y830500D03*
Y826500D03*
Y834500D03*
Y842500D03*
Y838500D03*
X1422813Y910065D03*
X1424126Y900295D03*
X1429059Y908579D03*
X1426085Y910281D03*
X1427553Y939200D03*
X1420699Y958452D03*
X1427473Y965621D03*
X1420740Y1004766D03*
Y1000766D03*
Y1008766D03*
X1428740Y1000766D03*
X1420740Y996766D03*
X1428864D03*
X1420740Y1016266D03*
Y1012266D03*
X1428740Y1016266D03*
X1428823Y1020266D03*
X1420740Y1030766D03*
X1420107Y1052514D03*
X1430005Y1090568D03*
Y1093068D03*
X1431876Y1098518D03*
X1426624Y1098428D03*
X1432671Y1105552D03*
X1428877Y1104792D03*
X1418784Y1107997D03*
X1430384Y1106867D03*
X1421120Y1123101D03*
X1429120D03*
X1431620D03*
X1418884Y1110597D03*
X1421120Y1116101D03*
Y1118801D03*
X1426469Y1113648D03*
X1423969D03*
X1419669D03*
X1422020Y1129301D03*
X1424520D03*
X1427020D03*
X1429520D03*
X1432020D03*
X1417994Y1139435D03*
Y1136935D03*
Y1134435D03*
Y1131935D03*
X1421120Y1125801D03*
X1429520D03*
X1432020D03*
X1419520Y1129301D03*
X1432384Y1155213D03*
Y1152713D03*
X1422984D03*
Y1155213D03*
X1417994Y1144435D03*
Y1146935D03*
Y1141935D03*
X1419050Y1162384D03*
Y1164884D03*
Y1167384D03*
Y1169884D03*
Y1172384D03*
Y1174884D03*
X1420625Y1186709D03*
Y1184209D03*
Y1181709D03*
Y1179209D03*
Y1204405D03*
X1418310Y1198321D03*
Y1200821D03*
Y1192621D03*
Y1190121D03*
X1420625Y1206905D03*
Y1209405D03*
X1420736Y1222194D03*
X1424736D03*
X1428736D03*
X1432736D03*
X1420736Y1238194D03*
Y1234194D03*
Y1230194D03*
X1424736Y1234194D03*
Y1230194D03*
Y1226194D03*
X1428736Y1238194D03*
Y1234194D03*
Y1230194D03*
Y1226194D03*
X1432736Y1234194D03*
Y1226194D03*
X1420736Y1246194D03*
Y1242194D03*
X1424736Y1246194D03*
Y1242194D03*
X1428736Y1246194D03*
Y1242194D03*
X1421821Y1257160D03*
X1418821D03*
Y1260160D03*
X1421821D03*
X1425652Y1297411D03*
X1431080Y1301702D03*
X1421238Y1301712D03*
X1428009Y1301760D03*
X1424732Y1301603D03*
X1433386Y1343309D03*
X1428840Y1407740D03*
X1432258Y1414600D03*
X1422176Y1491198D03*
X1430374Y1492474D03*
X1420877Y1494706D03*
X1423065Y1508327D03*
X1432499Y1512175D03*
X1423806Y1524252D03*
X1423930Y1520364D03*
X1429587Y1527450D03*
X1424245Y1543338D03*
X1425558Y1537432D03*
X1433405Y1546001D03*
X1425260Y1558072D03*
X1433558Y1555366D03*
X1423701Y1563978D03*
X1432913Y1568679D03*
X1432000Y1644980D03*
X1445692Y5374D03*
X1445005Y24773D03*
X1449685Y34228D03*
X1445005Y44773D03*
X1436045Y77393D03*
Y74793D03*
Y85193D03*
Y82593D03*
Y79993D03*
X1444641Y94017D03*
X1448641D03*
X1440641D03*
X1444370Y101701D03*
Y98551D03*
X1435358Y116496D03*
Y109410D03*
X1449761Y115401D03*
Y110445D03*
X1444769D03*
Y115401D03*
X1435358Y102323D03*
X1447920Y103783D03*
X1438116Y107649D03*
Y104249D03*
X1449761Y124618D03*
X1444769D03*
Y129574D03*
X1435358Y130670D03*
Y123583D03*
X1449761Y129574D03*
X1435358Y137756D03*
X1442682Y147540D03*
X1446454Y141247D03*
X1442682Y151540D03*
X1435138Y162368D03*
X1437738D03*
X1444838Y162793D03*
Y165393D03*
Y170493D03*
Y167993D03*
X1449841Y181009D03*
X1447046Y181366D03*
X1443835Y181426D03*
X1446332Y191941D03*
X1444043Y184221D03*
X1446660Y184012D03*
X1448079Y211359D03*
Y213859D03*
X1436449Y213213D03*
Y210713D03*
X1440521Y211695D03*
X1443021D03*
X1440521Y208695D03*
X1436449Y208213D03*
Y228961D03*
X1444418Y229286D03*
X1436449Y226461D03*
X1440156Y226141D03*
X1448111Y222212D03*
Y224712D03*
X1436449Y231461D03*
Y215713D03*
X1440399Y236611D03*
X1442899D03*
X1444418Y231786D03*
X1445399Y236611D03*
X1448026Y256535D03*
X1440101Y248891D03*
X1442601D03*
X1445101D03*
X1441016Y267526D03*
Y270026D03*
X1443516D03*
X1438216D03*
X1443516Y267526D03*
X1438216D03*
X1440053Y285690D03*
X1437553D03*
X1440053Y288190D03*
X1442853D03*
Y285690D03*
X1447079Y290755D03*
X1437553Y288190D03*
X1448948Y326448D03*
X1448822Y345324D03*
X1448734Y332910D03*
X1449060Y356861D03*
Y352361D03*
X1447502Y360785D03*
X1434697Y347125D03*
X1439719Y350387D03*
X1440568Y369566D03*
X1449619Y363290D03*
X1437758Y362584D03*
X1434608D03*
X1438768Y371655D03*
X1445906Y366030D03*
X1438588Y380589D03*
X1435019Y434508D03*
X1435424Y430361D03*
X1437757Y447201D03*
X1437879Y444269D03*
X1440390Y456652D03*
X1442890D03*
X1435484Y470045D03*
X1442890Y459152D03*
Y461652D03*
X1440390Y459152D03*
Y461652D03*
X1442786Y480705D03*
X1437631Y482134D03*
Y484634D03*
X1449293Y476086D03*
X1445586Y480705D03*
X1441076Y475946D03*
Y478446D03*
X1449293Y478586D03*
Y481086D03*
Y483886D03*
X1433960Y491214D03*
X1449293Y491133D03*
X1435810Y504699D03*
X1442721Y495151D03*
X1437663Y492987D03*
X1442421Y498151D03*
X1433960Y493714D03*
X1437663Y495487D03*
X1445221Y498151D03*
X1449293Y493633D03*
Y496133D03*
Y498633D03*
X1445221Y495151D03*
X1447036Y519518D03*
X1435512Y516979D03*
X1439462Y522129D03*
X1444536Y519518D03*
X1439536D03*
X1442036D03*
X1435755Y527449D03*
X1439462Y527129D03*
Y524629D03*
X1443555Y532949D03*
X1446355D03*
X1439462Y537877D03*
X1449393Y553297D03*
Y555897D03*
X1446988Y548418D03*
X1439462Y540377D03*
X1435390Y541895D03*
X1444488Y548418D03*
X1439488D03*
X1441988D03*
X1439462Y542877D03*
Y545377D03*
X1438882Y572842D03*
X1449393Y558497D03*
Y563697D03*
Y561097D03*
X1443388Y570686D03*
X1446183Y570478D03*
X1447037Y585507D03*
X1442444D03*
X1442990Y579475D03*
X1435668Y572975D03*
Y582747D03*
X1446600Y576484D03*
X1446243Y573689D03*
X1443597Y573303D03*
X1442488Y590145D03*
X1447082Y590190D03*
X1435241Y593796D03*
X1438944Y597232D03*
X1434049Y608311D03*
X1446944Y605443D03*
X1440930Y613913D03*
Y616713D03*
Y619513D03*
X1434944Y605443D03*
X1438944Y605637D03*
X1440930Y636005D03*
Y633205D03*
X1437790Y625013D03*
X1440930Y638805D03*
X1435952Y642184D03*
X1437784Y683532D03*
X1446323Y673183D03*
X1448991Y694392D03*
X1436567Y727532D03*
X1446538Y719548D03*
X1446717Y735536D03*
X1443000Y798500D03*
Y794500D03*
Y802500D03*
X1435000Y818500D03*
X1443000Y842500D03*
Y838500D03*
Y846500D03*
X1435000Y834500D03*
X1435212Y854042D03*
X1448726Y864400D03*
X1438188Y867633D03*
X1443041Y873683D03*
X1437703Y880067D03*
X1439891Y873821D03*
X1449072Y892581D03*
X1435288Y897500D03*
X1445367Y891888D03*
X1441223Y891957D03*
X1435745Y901500D03*
X1443231Y899006D03*
X1439103Y898564D03*
X1447261Y898571D03*
X1446022Y927000D03*
X1444453Y938806D03*
X1448137Y949440D03*
X1439031Y957683D03*
X1439449Y979009D03*
X1433996Y981437D03*
X1435669Y1005366D03*
X1440610Y1021567D03*
X1435266Y1031522D03*
X1435197Y1028372D03*
X1437064Y1098767D03*
X1442674Y1106365D03*
X1436949Y1101917D03*
X1436884Y1106897D03*
X1439699Y1110092D03*
X1443365Y1115896D03*
Y1118396D03*
X1441220Y1131935D03*
Y1139435D03*
Y1134435D03*
Y1136935D03*
X1434520Y1125801D03*
X1437020D03*
X1434520Y1129301D03*
X1437020D03*
X1441220Y1141935D03*
Y1144435D03*
Y1146935D03*
X1442448Y1152684D03*
Y1160834D03*
X1434820Y1162384D03*
Y1164884D03*
Y1167384D03*
Y1169884D03*
Y1172384D03*
X1437320D03*
Y1169884D03*
Y1167384D03*
Y1164884D03*
Y1162384D03*
X1434925Y1179421D03*
Y1181921D03*
Y1184421D03*
Y1186921D03*
X1434820Y1174884D03*
X1437320D03*
X1434925Y1204617D03*
X1437240Y1200821D03*
Y1198321D03*
Y1192621D03*
Y1190121D03*
X1434925Y1207117D03*
Y1209617D03*
Y1212117D03*
X1436736Y1222194D03*
Y1226194D03*
X1436408Y1303462D03*
X1444438Y1308312D03*
X1439482D03*
X1443660Y1310698D03*
X1440260D03*
X1441286Y1335776D03*
X1446817Y1335846D03*
X1441200Y1338700D03*
X1435900Y1340800D03*
X1439258Y1414600D03*
X1446135Y1530876D03*
X1443103Y1527201D03*
X1437293Y1546125D03*
X1441145Y1540415D03*
X1440153Y1563093D03*
X1443769Y1562173D03*
X1436801Y1568803D03*
X1464594Y3000D03*
X1462675Y14334D03*
X1452717Y34052D03*
X1455013Y43128D03*
X1457718Y84140D03*
Y76140D03*
Y80140D03*
X1460466Y76587D03*
Y72615D03*
X1452650Y94017D03*
X1460163Y117557D03*
X1455171D03*
X1463087Y103621D03*
X1451920Y103783D03*
X1454855Y106186D03*
X1455171Y122513D03*
X1460163Y131731D03*
Y122513D03*
X1455171Y131731D03*
X1458262Y146461D03*
X1460163Y136687D03*
X1455171D03*
X1457164Y152367D03*
X1463547Y180527D03*
X1458864Y180572D03*
X1455016Y168697D03*
X1464628Y171523D03*
X1458864Y185165D03*
X1463502Y185121D03*
X1452832Y184619D03*
X1456104Y191941D03*
X1454812Y206760D03*
X1458113Y206767D03*
X1463113D03*
X1460613D03*
X1451782Y213132D03*
X1463243Y221708D03*
X1460743D03*
X1458243D03*
X1457658Y224421D03*
X1459358Y231021D03*
Y228221D03*
X1451782Y215632D03*
X1459909Y236189D03*
X1464909D03*
X1462409D03*
X1456026Y256535D03*
X1459850Y248765D03*
X1464850D03*
X1462350D03*
X1452026Y256303D03*
X1457056Y279208D03*
X1460047Y270695D03*
Y268195D03*
X1462547Y270695D03*
Y268195D03*
X1465347Y270695D03*
Y268195D03*
X1465650Y293645D03*
X1451079Y290755D03*
X1465650Y288345D03*
Y290845D03*
X1463150Y288345D03*
Y290845D03*
Y293645D03*
X1451215Y323193D03*
X1451330Y327588D03*
X1459060Y320861D03*
Y325361D03*
X1451272Y340971D03*
X1451344Y336620D03*
X1451300Y332225D03*
X1459060Y329861D03*
Y338861D03*
Y343361D03*
Y334361D03*
X1451387Y345609D03*
X1451186Y350447D03*
X1458982Y356861D03*
X1459060Y347861D03*
Y352361D03*
X1455979Y391756D03*
X1459873Y391705D03*
X1458212Y403374D03*
X1458214Y406231D03*
X1464536Y433114D03*
X1458912Y581659D03*
X1454944Y605443D03*
X1453000Y614158D03*
Y616958D03*
Y619758D03*
X1450944Y605443D03*
X1458944D03*
X1453000Y633450D03*
Y636250D03*
Y639050D03*
X1455761Y683448D03*
X1460111Y683536D03*
X1451428Y673252D03*
X1460816Y727964D03*
X1455291Y759656D03*
X1455159Y763714D03*
X1453032Y769032D03*
X1453775Y813032D03*
X1461241Y867475D03*
X1462694Y874859D03*
Y877859D03*
X1460472Y885985D03*
X1457218Y888764D03*
X1452641Y888033D03*
X1459420Y899226D03*
X1451286Y898549D03*
X1451005Y931848D03*
X1461888Y936055D03*
X1462819Y949996D03*
X1462000Y960378D03*
Y957000D03*
X1460655Y964253D03*
X1457352Y976277D03*
X1466076Y979746D03*
X1459519Y989432D03*
X1462388Y1006560D03*
X1456966Y998507D03*
X1455939Y1018368D03*
X1465846Y1023900D03*
X1465503Y1030233D03*
X1452000Y1644980D03*
X1479409Y-83456D03*
Y-78500D03*
X1481905Y-79278D03*
Y-82678D03*
X1479409Y-68500D03*
Y-73456D03*
X1476822Y40780D03*
X1479972D03*
X1480460Y60922D03*
X1475296Y55513D03*
X1472146D03*
X1468371Y68581D03*
X1477606Y60438D03*
X1468384Y80581D03*
X1472489Y91951D03*
X1472514Y88801D03*
X1478428Y86046D03*
X1475431Y94351D03*
X1471093Y117261D03*
X1478624Y113394D03*
X1481273Y110784D03*
X1478624Y116594D03*
X1466278Y112083D03*
X1481368Y130898D03*
X1478624Y119594D03*
X1477465Y161306D03*
X1469221Y152562D03*
X1474716Y157370D03*
X1478800Y180665D03*
Y172665D03*
Y168665D03*
Y176665D03*
X1467270Y192421D03*
X1470899Y186629D03*
X1478800Y192665D03*
X1478913Y186778D03*
X1478832Y200864D03*
Y212864D03*
Y204864D03*
Y208864D03*
Y216864D03*
Y221864D03*
X1467593Y221642D03*
X1474473Y219379D03*
X1480589Y252371D03*
Y248371D03*
X1471507Y265897D03*
X1469007D03*
X1477549Y327200D03*
Y322700D03*
Y345200D03*
Y340700D03*
Y331700D03*
Y358700D03*
Y349700D03*
Y354200D03*
X1480702Y368516D03*
X1468309Y408861D03*
X1473364Y410724D03*
X1472403Y417338D03*
X1475236Y412482D03*
X1466231Y423671D03*
X1469538Y416795D03*
X1469293Y428815D03*
X1473900Y433100D03*
X1466653Y428582D03*
X1471375Y433115D03*
X1478710Y685630D03*
X1477597Y682997D03*
X1474713Y685247D03*
X1479297Y693630D03*
X1476794Y691447D03*
X1473525Y710052D03*
X1479500Y706500D03*
X1474425Y716075D03*
Y712925D03*
X1474000Y707000D03*
X1479962Y727500D03*
X1469116Y719055D03*
X1471415Y748629D03*
X1479500Y750500D03*
X1479759Y743500D03*
X1479657Y735500D03*
X1469957Y750957D03*
X1474425Y760075D03*
Y756925D03*
X1474000Y753093D03*
X1476677Y827626D03*
X1473634Y864337D03*
X1473489Y861354D03*
X1474060Y877196D03*
X1473468Y874267D03*
X1482387Y872940D03*
X1473433Y891043D03*
X1481454Y911570D03*
X1474075Y920575D03*
X1470925D03*
X1480343Y914776D03*
X1480109Y943496D03*
X1474349Y949394D03*
X1479441Y961941D03*
X1468500Y974181D03*
X1476500Y974000D03*
X1482237Y966028D03*
X1475096Y980330D03*
X1471096D03*
X1479096Y988813D03*
X1471296D03*
X1479096Y997860D03*
X1471096D03*
X1475096D03*
X1467096D03*
X1475062Y1008300D03*
Y1002453D03*
X1468869Y1018469D03*
X1479624Y1035102D03*
X1468371Y1030701D03*
X1476230Y1030672D03*
X1473230D03*
X1480193Y1102091D03*
X1474384D03*
X1480193Y1114691D03*
X1474384D03*
X1471374Y1118654D03*
X1474384Y1109564D03*
X1480231D03*
X1474384Y1122164D03*
X1480231D03*
X1480193Y1127291D03*
X1474384D03*
X1480193Y1139891D03*
X1474384D03*
Y1134764D03*
X1480231D03*
X1480193Y1152491D03*
X1474384D03*
Y1147364D03*
X1480231D03*
X1480193Y1165091D03*
X1474384Y1172564D03*
X1480231D03*
X1474384Y1159964D03*
X1480231D03*
X1480193Y1177691D03*
X1474384D03*
Y1185164D03*
X1480231D03*
X1477846Y1204932D03*
X1476094Y1465913D03*
Y1461182D03*
Y1456451D03*
Y1471805D03*
Y1481267D03*
Y1476536D03*
Y1491890D03*
Y1487159D03*
Y1496621D03*
Y1502514D03*
Y1511976D03*
Y1507245D03*
Y1563544D03*
Y1558813D03*
Y1568275D03*
Y1578898D03*
Y1574167D03*
Y1583629D03*
Y1594253D03*
Y1589522D03*
Y1609607D03*
Y1598984D03*
Y1604876D03*
Y1614338D03*
X1472000Y1644980D03*
X1487851Y-77080D03*
X1491092Y-79984D03*
X1491104Y-77094D03*
X1487836Y-87777D03*
X1491089D03*
X1487851Y-85262D03*
X1491104D03*
X1491092Y-82584D03*
X1484811Y-86371D03*
X1491092Y-71970D03*
X1487836Y-74565D03*
X1491089Y-74579D03*
X1487836Y-64265D03*
X1491089D03*
X1491092Y-69470D03*
X1487851Y-66780D03*
X1491104D03*
X1484811Y-65585D03*
Y-75885D03*
X1484594Y3000D03*
X1498621Y15043D03*
Y19043D03*
Y35043D03*
Y27043D03*
Y31043D03*
Y23043D03*
X1483287Y94374D03*
X1486842Y102249D03*
X1482842D03*
X1493859Y109172D03*
X1496859D03*
X1495866Y106495D03*
X1490593Y116594D03*
X1495866Y102495D03*
X1488867Y133298D03*
X1490593Y119594D03*
X1495600Y146012D03*
X1497506Y141228D03*
X1483014Y134579D03*
X1495600Y142862D03*
X1486642Y195176D03*
X1488761Y198883D03*
X1489142Y195176D03*
X1484142D03*
X1492690Y206838D03*
X1490190D03*
X1484002Y203393D03*
X1486502D03*
X1493260Y226320D03*
X1493194Y221970D03*
X1490481Y216385D03*
X1493194Y216970D03*
Y219470D03*
X1486681Y218085D03*
X1483881D03*
X1492186Y238589D03*
X1495152Y236121D03*
X1495178Y232971D03*
X1495071Y253198D03*
X1497446Y295877D03*
X1484796Y320359D03*
X1484968Y325025D03*
X1486360Y322700D03*
X1484876Y329377D03*
X1488255Y342921D03*
X1484682Y338394D03*
X1497760Y336543D03*
X1486360Y345200D03*
X1487152Y331272D03*
X1487926Y347387D03*
X1486360Y358700D03*
Y354200D03*
Y349700D03*
X1483813Y368516D03*
X1494286Y372699D03*
X1488000Y731500D03*
X1495500Y750500D03*
X1496473Y769000D03*
X1496763Y777000D03*
X1491062Y793003D03*
X1496500Y792000D03*
X1496756Y785000D03*
X1491425Y798425D03*
X1486957Y792457D03*
X1491425Y801575D03*
X1496845Y813000D03*
X1496621Y829000D03*
X1496447Y821000D03*
X1493092Y820444D03*
X1491425Y845575D03*
X1496500Y836000D03*
X1489650Y836985D03*
X1491425Y842425D03*
X1486957Y836457D03*
X1492625Y837324D03*
X1489805Y866386D03*
X1497488Y873839D03*
X1491414Y875383D03*
X1488138Y878339D03*
Y872839D03*
X1494000Y884000D03*
X1498084Y894825D03*
X1492101Y894860D03*
X1482566Y882154D03*
X1498446Y912370D03*
X1496383Y898023D03*
X1497208Y909740D03*
X1496500Y919000D03*
X1496000Y922000D03*
X1487075Y920925D03*
X1487240Y924453D03*
X1485100Y943900D03*
X1496425Y943075D03*
X1497063Y934000D03*
X1496072Y940201D03*
X1483324Y939324D03*
X1482921Y931324D03*
X1496072Y950044D03*
X1482591Y961909D03*
X1486500Y947000D03*
X1497075Y961000D03*
X1487240Y952012D03*
X1496072Y953981D03*
X1485226Y973886D03*
X1492560Y974654D03*
X1487096Y988813D03*
X1495096D03*
X1482535Y1008262D03*
Y1002453D03*
X1495339Y1009354D03*
X1491839D03*
X1486030D03*
X1491096Y997860D03*
X1483096D03*
X1495096D03*
X1487096D03*
X1482535Y1011762D03*
X1491839Y1021954D03*
X1486030D03*
Y1029427D03*
X1491877D03*
X1483693Y1102091D03*
X1496140Y1105091D03*
X1483693Y1114691D03*
X1496140Y1117691D03*
X1483693Y1127291D03*
Y1139891D03*
X1496140Y1130291D03*
X1483693Y1152491D03*
X1496140Y1155491D03*
Y1142891D03*
X1483693Y1165091D03*
X1496140Y1168091D03*
X1483693Y1177691D03*
X1496140Y1180691D03*
X1482705Y1200001D03*
X1498197Y1209607D03*
X1492471Y1215195D03*
X1484055Y1223749D03*
X1484755Y1465513D03*
Y1460782D03*
X1493417Y1465913D03*
Y1456451D03*
Y1461182D03*
Y1471805D03*
Y1476536D03*
Y1481267D03*
X1484755Y1476136D03*
Y1470244D03*
Y1480867D03*
Y1496221D03*
X1493417Y1487159D03*
Y1491890D03*
Y1496621D03*
X1484755Y1491490D03*
Y1485598D03*
Y1506845D03*
Y1500952D03*
Y1511576D03*
X1493417Y1507245D03*
Y1502514D03*
Y1511976D03*
X1484755Y1516307D03*
Y1563144D03*
X1493417Y1558813D03*
Y1563544D03*
Y1578898D03*
X1484755Y1567875D03*
Y1578498D03*
Y1572606D03*
X1493417Y1568275D03*
Y1574167D03*
X1484755Y1583229D03*
Y1593853D03*
Y1587960D03*
X1493417Y1583629D03*
Y1589522D03*
Y1594253D03*
X1484755Y1609207D03*
Y1598584D03*
Y1603315D03*
X1493417Y1609607D03*
Y1604876D03*
Y1598984D03*
X1484755Y1613938D03*
Y1618669D03*
X1493417Y1614338D03*
X1492000Y1644980D03*
X1514765Y-44536D03*
Y-39580D03*
Y-29580D03*
Y-34536D03*
X1500578Y4469D03*
X1501939Y24773D03*
Y44773D03*
X1509260Y53597D03*
X1504460Y95111D03*
X1511610Y116496D03*
Y109410D03*
Y102323D03*
X1499610Y116497D03*
X1506910D03*
X1504410D03*
X1506910Y109410D03*
X1508829Y106561D03*
X1511610Y123583D03*
X1499610Y130670D03*
Y123584D03*
X1506910Y130670D03*
X1504410D03*
Y123584D03*
X1506910Y123583D03*
X1511610Y130670D03*
Y137756D03*
X1499610Y137757D03*
X1504410D03*
X1500394Y150847D03*
X1506689Y195176D03*
X1501689D03*
X1503207Y199248D03*
X1499189Y195176D03*
X1504189D03*
X1508142Y213539D03*
X1506207Y202048D03*
X1503207Y201748D03*
X1499270Y210509D03*
X1501043Y206806D03*
X1501770Y210509D03*
X1503543Y206806D03*
X1509823Y238714D03*
X1502362Y247292D03*
X1501588Y238689D03*
X1505823Y238714D03*
X1499947Y242078D03*
X1505304Y246874D03*
X1507524Y244297D03*
X1500480Y295727D03*
X1503884Y295549D03*
X1501807Y323766D03*
X1501500Y321000D03*
X1509454Y402291D03*
X1514446D03*
X1509454Y397335D03*
X1514446D03*
X1512046Y411509D03*
X1507054Y416465D03*
Y411509D03*
X1512046Y425682D03*
X1507054D03*
X1512046Y416465D03*
Y439855D03*
X1507054D03*
X1512046Y430638D03*
X1507054D03*
X1512046Y444811D03*
X1507054D03*
X1507864Y450750D03*
X1507054Y468609D03*
X1512046D03*
X1507054Y473565D03*
X1512046D03*
X1507054Y487738D03*
X1512046D03*
X1507054Y482782D03*
X1512046D03*
X1507054Y517699D03*
X1512046D03*
X1507054Y512743D03*
X1512046D03*
X1511963Y536382D03*
X1507054Y526916D03*
X1512046Y531872D03*
X1507054D03*
X1512046Y526916D03*
X1513284Y552466D03*
X1504495Y796844D03*
X1510527Y833500D03*
X1504938Y859711D03*
X1500353Y859855D03*
X1500638Y873839D03*
X1512712Y867418D03*
X1507034Y888133D03*
X1507358Y909740D03*
X1507305Y912262D03*
X1510280Y899732D03*
X1510527Y908951D03*
X1513927D03*
X1505337Y921240D03*
X1514354Y938811D03*
X1510500Y931500D03*
X1513955Y950396D03*
X1512161Y957541D03*
X1505888Y965964D03*
X1501400Y966000D03*
X1514000Y968739D03*
X1510740Y973740D03*
X1498973Y975443D03*
X1511000Y970500D03*
X1511096Y988813D03*
X1503096D03*
X1507096Y997860D03*
X1503096D03*
X1511096D03*
X1499096D03*
X1507786Y1012354D03*
Y1024954D03*
X1503572Y1034538D03*
X1505130Y1105091D03*
Y1117691D03*
Y1130291D03*
Y1142891D03*
Y1155491D03*
Y1168091D03*
Y1180691D03*
X1500675Y1227300D03*
X1507692Y1224472D03*
X1502078Y1465513D03*
Y1460782D03*
X1510740Y1465913D03*
Y1456451D03*
Y1461182D03*
X1502078Y1470244D03*
Y1480867D03*
X1510740Y1471805D03*
Y1476536D03*
Y1481267D03*
X1502078Y1476136D03*
Y1491490D03*
Y1485598D03*
Y1496221D03*
X1510740Y1487159D03*
Y1491890D03*
Y1496621D03*
Y1507245D03*
Y1502514D03*
Y1511976D03*
X1502078Y1506845D03*
Y1500952D03*
Y1511576D03*
Y1516307D03*
X1510740Y1563544D03*
X1502078Y1563144D03*
X1510740Y1558813D03*
Y1578898D03*
X1502078Y1567875D03*
Y1578498D03*
Y1572606D03*
X1510740Y1568275D03*
Y1574167D03*
X1502078Y1583229D03*
Y1593853D03*
Y1587960D03*
X1510740Y1583629D03*
Y1589522D03*
Y1594253D03*
X1502078Y1609207D03*
Y1598584D03*
Y1603315D03*
X1510740Y1609607D03*
Y1604876D03*
Y1598984D03*
X1502078Y1613938D03*
Y1618669D03*
X1510740Y1614338D03*
X1512000Y1644980D03*
X1523192Y-48857D03*
X1526445D03*
X1523207Y-46342D03*
X1526460D03*
X1520167Y-47451D03*
X1526448Y-33050D03*
X1523192Y-35645D03*
X1526445Y-35659D03*
X1526448Y-30550D03*
X1523207Y-38160D03*
X1526448Y-41064D03*
X1526460Y-38174D03*
X1526448Y-43664D03*
X1520167Y-36965D03*
X1517261Y-40358D03*
Y-43758D03*
X1523192Y-25345D03*
X1526445D03*
X1523207Y-27860D03*
X1526460D03*
X1520167Y-26665D03*
X1529260Y53597D03*
X1520072Y82984D03*
Y75184D03*
Y77784D03*
Y80384D03*
X1522626Y92849D03*
X1520072Y85584D03*
X1529543Y95236D03*
X1519610D03*
X1529586Y103037D03*
X1519610Y102323D03*
X1519862Y109410D03*
Y116496D03*
X1529720D03*
Y109410D03*
X1520034Y124576D03*
X1529720Y130670D03*
Y123583D03*
X1521087Y130670D03*
X1526311Y137756D03*
X1521082D03*
X1528355Y210478D03*
Y215478D03*
Y212978D03*
Y207978D03*
Y228726D03*
Y223726D03*
Y226226D03*
Y231226D03*
X1515779Y351594D03*
X1517456Y390223D03*
X1522448D03*
X1519321Y382600D03*
X1517456Y395179D03*
Y404396D03*
Y409352D03*
X1522448Y395179D03*
Y404396D03*
Y409352D03*
X1517456Y418569D03*
Y423525D03*
X1522448D03*
Y418569D03*
Y437699D03*
X1517456Y432743D03*
Y437699D03*
X1522448Y432743D03*
X1519436Y458711D03*
X1521963Y453682D03*
X1520200Y455921D03*
X1518780Y463600D03*
X1517456Y489895D03*
X1522448D03*
X1517456Y480677D03*
Y475721D03*
X1522448Y480677D03*
Y475721D03*
X1517456Y494851D03*
X1522448D03*
X1517456Y519855D03*
X1522448D03*
Y538984D03*
X1517456D03*
Y524811D03*
Y534028D03*
X1522448D03*
Y524811D03*
X1528635Y555234D03*
X1528350Y562003D03*
X1519156Y596095D03*
X1516869Y594668D03*
X1518354Y592354D03*
X1518415Y589556D03*
X1519153Y599588D03*
X1516930Y597580D03*
X1519185Y603600D03*
X1519153Y607588D03*
X1519185Y619600D03*
X1523646Y634946D03*
X1519185Y623600D03*
X1524200Y646098D03*
X1519063Y876339D03*
X1518517Y878898D03*
X1518452Y873780D03*
X1517344Y896999D03*
X1515743Y888133D03*
X1517344Y903179D03*
X1517153Y908367D03*
X1516283Y912240D03*
X1519116D03*
X1523053Y912262D03*
X1522881Y901034D03*
X1522954Y897951D03*
X1523000Y923740D03*
X1526611Y921442D03*
X1525740Y928740D03*
X1521085Y921094D03*
X1515179D03*
X1527876Y939439D03*
X1528087Y936394D03*
X1527267Y932647D03*
X1522209Y937846D03*
X1524500Y949500D03*
X1525022Y957340D03*
X1530174Y956986D03*
X1529128Y952978D03*
X1521085Y957340D03*
X1525522Y971075D03*
X1525583Y968500D03*
X1530767Y972981D03*
X1519863Y977637D03*
X1525005Y974323D03*
X1523966Y980281D03*
X1530594Y979952D03*
X1519096Y988813D03*
X1515096Y997860D03*
X1531096D03*
X1519096D03*
X1523096D03*
X1516776Y1024954D03*
Y1012354D03*
X1517855Y1053457D03*
X1519401Y1465513D03*
Y1460782D03*
X1528062Y1465913D03*
Y1456451D03*
Y1461182D03*
Y1481267D03*
X1519401Y1476136D03*
Y1470244D03*
Y1480867D03*
X1528062Y1471805D03*
Y1476536D03*
X1519401Y1491490D03*
Y1485598D03*
Y1496221D03*
X1528062Y1487159D03*
Y1491890D03*
Y1496621D03*
X1519401Y1506845D03*
Y1500952D03*
Y1511576D03*
X1528062Y1507245D03*
Y1502514D03*
Y1511976D03*
X1519401Y1516307D03*
Y1563144D03*
X1528062Y1558813D03*
Y1563544D03*
Y1578898D03*
X1519401Y1567875D03*
Y1578498D03*
Y1572606D03*
X1528062Y1568275D03*
Y1574167D03*
X1519401Y1587960D03*
X1528062Y1583629D03*
Y1589522D03*
Y1594253D03*
X1519401Y1583229D03*
Y1593853D03*
Y1609207D03*
Y1598584D03*
Y1603315D03*
X1528062Y1609607D03*
Y1604876D03*
Y1598984D03*
X1519401Y1613938D03*
Y1618669D03*
X1528062Y1614338D03*
X1547367Y44773D03*
X1538407Y85539D03*
Y82939D03*
Y75139D03*
Y80339D03*
Y77739D03*
X1547003Y94017D03*
X1543003D03*
X1546732Y101701D03*
Y98551D03*
X1547131Y110445D03*
Y115401D03*
X1537720Y116496D03*
Y109410D03*
Y102323D03*
X1540478Y107649D03*
Y104249D03*
X1547131Y129574D03*
X1537720Y130670D03*
Y123583D03*
X1547131Y124618D03*
X1537720Y137756D03*
X1545044Y147540D03*
Y151540D03*
X1540100Y162368D03*
X1537500D03*
X1547200Y162793D03*
Y165393D03*
Y167993D03*
Y170493D03*
X1546197Y181426D03*
X1546405Y184221D03*
X1538811Y213213D03*
Y210713D03*
X1542883Y211695D03*
X1545383D03*
X1542883Y208695D03*
X1538811Y208213D03*
Y226461D03*
X1542518Y226141D03*
X1538811Y228961D03*
Y231461D03*
X1546780Y229286D03*
X1538811Y215713D03*
X1542761Y236611D03*
X1545261D03*
X1546780Y231786D03*
X1542463Y248891D03*
X1544963D03*
X1534184Y264180D03*
X1531684D03*
X1531609Y258880D03*
X1545878Y270026D03*
X1543378D03*
X1540578D03*
X1543378Y267526D03*
X1540578D03*
X1545878D03*
X1531901Y293796D03*
X1539915Y288190D03*
X1542415Y285690D03*
X1539915D03*
X1542415Y288190D03*
X1545215D03*
Y285690D03*
X1534401Y293796D03*
X1544736Y305156D03*
X1541534Y322850D03*
X1541283Y354553D03*
X1538133D03*
X1546183Y541863D03*
Y545263D03*
X1544375Y553407D03*
X1546875D03*
X1544375Y550907D03*
X1546875D03*
X1542704Y572162D03*
X1543946Y569928D03*
X1546293Y570962D03*
X1546036Y568475D03*
X1532067Y1041832D03*
X1531947Y1046212D03*
X1531546Y1062769D03*
X1545385Y1461183D03*
X1536724Y1465513D03*
Y1460782D03*
X1545385Y1465914D03*
Y1456452D03*
X1536724Y1476136D03*
Y1470244D03*
Y1480867D03*
X1545385Y1476537D03*
Y1471806D03*
Y1481268D03*
X1536724Y1491490D03*
Y1485598D03*
Y1496221D03*
X1545385Y1491891D03*
Y1487160D03*
Y1496622D03*
X1536724Y1506845D03*
Y1500952D03*
Y1511576D03*
X1545385Y1507246D03*
Y1502515D03*
Y1511977D03*
X1536724Y1516307D03*
X1545385Y1563544D03*
Y1558813D03*
X1536724Y1563144D03*
Y1567875D03*
X1545385Y1568275D03*
X1536724Y1578498D03*
Y1572606D03*
X1545385Y1578898D03*
Y1574167D03*
Y1594253D03*
Y1589522D03*
X1536724Y1583229D03*
X1545385Y1583629D03*
X1536724Y1593853D03*
Y1587960D03*
Y1609207D03*
Y1598584D03*
Y1603315D03*
X1545385Y1609607D03*
Y1598984D03*
Y1604876D03*
Y1614338D03*
X1536724Y1613938D03*
Y1618669D03*
X1532000Y1644980D03*
X1560080Y84140D03*
Y76140D03*
Y80140D03*
X1562828Y72615D03*
Y76587D03*
X1555012Y94017D03*
X1551003D03*
X1562525Y117557D03*
X1557533D03*
X1552123Y115401D03*
Y110445D03*
X1554282Y103783D03*
X1557217Y106186D03*
X1550282Y103783D03*
X1562525Y122513D03*
X1552123Y129574D03*
Y124618D03*
X1557533Y131731D03*
Y122513D03*
X1562525Y131731D03*
X1560624Y146461D03*
X1557533Y136687D03*
X1562525D03*
X1548816Y141247D03*
X1559526Y152367D03*
X1561226Y180572D03*
X1552203Y181009D03*
X1549408Y181366D03*
X1557378Y168697D03*
X1548694Y191941D03*
X1555194Y184619D03*
X1561226Y185165D03*
X1558466Y191941D03*
X1549022Y184012D03*
X1557174Y206760D03*
X1560475Y206767D03*
X1562975D03*
X1554144Y213132D03*
X1550441Y211359D03*
Y213859D03*
X1550473Y222212D03*
Y224712D03*
X1560605Y221708D03*
X1560020Y224421D03*
X1563105Y221708D03*
X1561720Y231021D03*
Y228221D03*
X1554144Y215632D03*
X1547761Y236611D03*
X1562271Y236189D03*
X1550388Y256535D03*
X1558388D03*
X1547463Y248891D03*
X1562212Y248765D03*
X1554388Y256303D03*
X1559418Y279208D03*
X1562409Y268195D03*
Y270695D03*
X1549441Y290755D03*
X1553441D03*
X1547972Y304906D03*
X1556151Y318596D03*
X1556294Y327814D03*
X1554403Y316363D03*
X1556437Y332022D03*
X1556380Y336917D03*
X1556498Y340958D03*
X1553910Y331798D03*
X1553862Y344867D03*
X1556353Y345636D03*
X1554403Y352363D03*
X1556429Y389154D03*
X1563248D03*
X1548629D03*
Y403327D03*
Y410413D03*
X1556429Y396240D03*
X1557708Y404911D03*
X1561778Y396240D03*
X1548629D03*
X1556662Y412571D03*
X1557849Y426299D03*
X1548629Y417500D03*
Y424587D03*
Y438760D03*
Y431673D03*
X1558160Y445847D03*
X1548629D03*
X1556429Y467539D03*
X1548629D03*
X1556429Y474626D03*
X1548629D03*
Y488799D03*
X1556690Y480828D03*
X1548629Y481713D03*
Y495886D03*
X1558640Y498834D03*
X1548629Y511673D03*
Y518760D03*
X1562089Y516841D03*
X1556429Y518760D03*
Y511673D03*
X1548629Y540020D03*
Y525847D03*
Y532933D03*
X1556429Y525847D03*
X1548629Y547106D03*
X1556914Y552872D03*
X1557036Y550123D03*
X1556359Y562443D03*
X1558668Y572334D03*
X1558127Y560675D03*
X1548359Y569426D03*
X1548645Y566929D03*
X1556900Y574102D03*
X1547910Y602197D03*
X1562385Y598400D03*
Y602400D03*
Y594400D03*
X1548374Y595108D03*
X1562385Y614400D03*
Y606400D03*
Y610400D03*
X1561535Y653161D03*
X1561552Y665455D03*
X1547813Y906581D03*
X1548629Y927836D03*
X1548504Y915689D03*
X1548616Y931602D03*
X1551099Y959096D03*
X1551163Y952888D03*
X1552000Y969850D03*
Y1644980D03*
X1576256Y-48799D03*
X1573003D03*
X1576241Y-46284D03*
X1572988D03*
X1579281Y-47479D03*
X1573000Y-41094D03*
X1576256Y-38499D03*
X1573003Y-38485D03*
X1573000Y-43594D03*
X1576241Y-35984D03*
X1573000Y-33080D03*
X1572988Y-35970D03*
X1573000Y-30480D03*
X1579281Y-37179D03*
X1576256Y-25273D03*
X1573003Y-25287D03*
X1576241Y-27788D03*
X1572988Y-27802D03*
X1579281Y-26693D03*
X1571895Y58013D03*
X1570733Y68581D03*
X1570746Y80581D03*
X1574851Y91951D03*
X1574876Y88801D03*
X1577793Y94351D03*
X1573455Y117261D03*
X1565449Y103621D03*
X1568640Y112083D03*
X1579827Y161306D03*
X1571583Y152562D03*
X1577078Y157370D03*
X1565909Y180527D03*
X1566990Y171523D03*
X1569632Y192421D03*
X1565864Y185121D03*
X1573261Y186629D03*
X1565475Y206767D03*
X1565605Y221708D03*
X1569955Y221642D03*
X1576835Y219379D03*
X1564771Y236189D03*
X1567271D03*
X1564712Y248765D03*
X1567212D03*
X1567709Y270695D03*
X1573869Y265897D03*
X1571369D03*
X1567709Y268195D03*
X1564909Y270695D03*
Y268195D03*
X1565512Y288345D03*
X1568012Y293645D03*
Y290845D03*
Y288345D03*
X1565512Y293645D03*
Y290845D03*
X1563877Y325363D03*
Y316363D03*
X1574845Y338843D03*
X1571625Y333549D03*
Y344131D03*
X1574775Y333549D03*
X1563877Y329863D03*
Y343363D03*
Y334363D03*
X1578587Y341787D03*
X1563877Y352363D03*
X1574540Y389154D03*
X1579340Y396240D03*
Y403327D03*
Y410413D03*
X1574540Y396240D03*
Y403327D03*
Y410413D03*
X1566555Y414823D03*
X1565863Y422864D03*
X1579340Y417500D03*
Y424586D03*
X1574540Y417500D03*
Y424586D03*
X1565933Y429832D03*
X1565538Y436447D03*
X1574540Y438760D03*
X1579340Y431673D03*
Y438760D03*
X1574540Y431673D03*
X1567573Y447953D03*
X1579340Y445847D03*
X1574540D03*
X1566740Y467539D03*
X1574540D03*
X1565482Y472772D03*
X1574540Y474626D03*
X1579340D03*
Y488799D03*
X1574540D03*
X1566216Y487711D03*
X1566329Y479104D03*
X1574540Y481713D03*
X1579340Y481712D03*
Y495886D03*
X1574540D03*
X1566740D03*
X1579340Y518760D03*
X1574540Y511673D03*
Y518760D03*
X1565050Y511673D03*
X1574540Y540020D03*
X1579340D03*
Y532933D03*
Y525846D03*
X1574540Y525847D03*
Y532933D03*
Y547106D03*
Y554193D03*
X1575000Y565414D03*
Y567914D03*
Y570414D03*
X1575934Y561420D03*
Y558917D03*
X1575000Y572914D03*
Y575414D03*
X1565323Y577716D03*
X1571755Y577937D03*
X1574540Y602205D03*
Y595118D03*
X1579753Y599100D03*
X1578679Y613047D03*
X1578114Y607563D03*
X1574222Y629872D03*
X1576297Y627600D03*
X1574880Y645891D03*
X1569926Y668885D03*
X1575950Y662981D03*
X1572141D03*
X1578000Y678776D03*
X1569434Y677111D03*
X1570331Y691851D03*
X1568872Y686971D03*
X1575942Y705043D03*
X1575192Y707592D03*
X1572000Y1644980D03*
X1583000Y-80014D03*
X1586256Y-77419D03*
X1583003Y-77405D03*
X1586256Y-87719D03*
X1583003D03*
X1583000Y-82514D03*
X1586241Y-85204D03*
X1582988D03*
X1589281Y-86399D03*
X1594683Y-83484D03*
Y-78528D03*
X1592187Y-79306D03*
Y-82706D03*
X1586241Y-74904D03*
X1583000Y-72000D03*
X1582988Y-74890D03*
X1586256Y-64207D03*
X1583003D03*
X1586241Y-66722D03*
X1582988D03*
X1583000Y-69400D03*
X1589281Y-76099D03*
Y-65613D03*
X1594683Y-68528D03*
Y-73484D03*
X1584683Y-44564D03*
Y-29608D03*
Y-34564D03*
Y-39608D03*
X1582187Y-43786D03*
Y-40386D03*
X1582822Y60922D03*
X1580327Y57448D03*
X1579968Y60438D03*
X1585649Y94374D03*
X1580790Y86046D03*
X1585204Y102249D03*
X1589204D03*
X1580986Y113394D03*
X1583635Y110784D03*
X1592955Y116594D03*
X1580986D03*
X1591229Y133298D03*
X1583229D03*
X1592955Y119594D03*
X1580986D03*
X1585376Y134579D03*
X1581162Y180665D03*
Y172665D03*
Y168665D03*
Y176665D03*
X1586504Y195176D03*
X1589004D03*
X1591123Y198883D03*
X1591504Y195176D03*
X1581162Y192665D03*
Y196665D03*
X1581275Y186778D03*
X1581194Y212864D03*
Y200864D03*
X1586364Y203393D03*
X1588864D03*
X1595052Y206838D03*
X1592552D03*
X1581194Y204864D03*
Y221864D03*
Y216864D03*
X1586243Y218085D03*
X1595622Y226320D03*
X1592843Y216385D03*
X1595556Y216970D03*
Y219470D03*
Y221970D03*
X1589043Y218085D03*
X1594548Y238589D03*
X1582951Y252371D03*
Y248371D03*
X1593290Y339876D03*
X1586640Y389153D03*
X1581840D03*
Y403326D03*
Y410413D03*
X1586640D03*
X1581840Y396240D03*
X1586640D03*
Y403326D03*
Y417499D03*
X1581840D03*
Y424586D03*
X1586640D03*
X1581840Y438760D03*
X1586640D03*
Y431673D03*
X1581840D03*
X1592635Y455911D03*
X1586640Y467539D03*
X1581840D03*
Y474626D03*
X1586640D03*
X1591443Y465332D03*
X1581840Y488799D03*
X1586640D03*
X1581840Y481712D03*
X1586640D03*
X1581840Y518760D03*
Y511673D03*
X1586640D03*
Y518760D03*
Y525846D03*
Y532933D03*
X1581840D03*
Y525846D03*
X1595185Y543925D03*
X1595760Y555000D03*
X1595460Y549800D03*
X1595260Y547075D03*
X1583720Y560500D03*
X1595364Y562800D03*
X1595300Y558800D03*
X1592020Y1433061D03*
X1592643Y1460707D03*
X1593019Y1457557D03*
X1591610Y1469940D03*
X1591775Y1473090D03*
X1591586Y1505130D03*
X1591925Y1512075D03*
X1591333Y1501980D03*
X1604301Y44773D03*
X1611622Y53597D03*
X1606822Y95111D03*
X1609272Y109410D03*
X1601972Y116497D03*
X1609272D03*
X1606772D03*
X1596221Y109172D03*
X1599221D03*
X1598228Y106495D03*
Y102495D03*
X1611191Y106561D03*
X1601972Y123584D03*
Y130670D03*
X1606772Y123584D03*
X1609272Y123583D03*
Y130670D03*
X1606772D03*
Y137757D03*
X1597962Y146012D03*
X1599868Y141228D03*
X1601972Y137757D03*
X1597962Y142862D03*
X1602756Y150847D03*
X1604051Y195176D03*
X1605569Y199248D03*
X1601551Y195176D03*
X1606551D03*
X1609051D03*
X1610504Y213539D03*
X1603405Y206806D03*
X1605905D03*
X1601632Y210509D03*
X1604132D03*
X1608569Y202048D03*
X1605569Y201748D03*
X1604724Y247292D03*
X1597514Y236121D03*
X1612185Y238714D03*
X1603950Y238689D03*
X1608185Y238714D03*
X1602309Y242078D03*
X1607666Y246874D03*
X1597540Y232971D03*
X1609886Y244297D03*
X1597433Y253198D03*
X1597006Y290417D03*
X1596691Y287397D03*
X1596197Y293477D03*
X1608240Y329000D03*
X1603664Y342596D03*
X1607947Y332326D03*
X1605966Y343794D03*
X1598223Y351003D03*
X1602138Y351047D03*
X1599127Y375587D03*
X1596253Y375633D03*
X1596714Y383003D03*
X1599527Y392718D03*
X1596534Y379760D03*
X1599527Y408718D03*
Y400718D03*
Y396718D03*
X1596760Y530000D03*
X1596260Y540500D03*
X1611316Y685800D03*
X1611027Y722427D03*
X1611327Y735973D03*
X1611627Y780327D03*
X1609500Y776100D03*
X1611873Y795127D03*
X1597225Y1437014D03*
X1600333Y1440504D03*
X1596836Y1446488D03*
X1600333Y1449068D03*
X1603363Y1460570D03*
X1597457Y1452556D03*
X1601968Y1453442D03*
X1597457Y1460662D03*
X1598500Y1472500D03*
X1606745Y1474242D03*
X1605430Y1468023D03*
X1597039Y1475100D03*
X1599726Y1474990D03*
X1602580Y1483108D03*
X1598000Y1486000D03*
X1604000Y1516000D03*
X1608500Y1515000D03*
X1600700Y1534300D03*
X1598574Y1543373D03*
X1622434Y82984D03*
Y80384D03*
Y75184D03*
Y77784D03*
X1624988Y92849D03*
X1622434Y85584D03*
X1621972Y95236D03*
Y102323D03*
X1622224Y109410D03*
Y116496D03*
X1613972D03*
Y102323D03*
Y109410D03*
X1622396Y124576D03*
X1623449Y130670D03*
X1613972D03*
Y123583D03*
X1623444Y137756D03*
X1613972D03*
X1626147Y351033D03*
X1628636Y422088D03*
X1625952Y431029D03*
X1626260Y427017D03*
X1625018Y435029D03*
X1625772Y438323D03*
X1625938Y449873D03*
X1621596Y456386D03*
X1625938Y445873D03*
X1625565Y472579D03*
Y479666D03*
Y486752D03*
Y493839D03*
Y523800D03*
Y516713D03*
Y537973D03*
Y530886D03*
X1616622Y546712D03*
Y542712D03*
X1625565Y566752D03*
Y588013D03*
Y573839D03*
Y580926D03*
Y602186D03*
Y595099D03*
Y609272D03*
Y616359D03*
X1614538Y618288D03*
X1620244Y638125D03*
X1627224Y643252D03*
X1613362Y656321D03*
X1621362D03*
X1617362D03*
X1613110Y678462D03*
X1616260D03*
X1619950Y678519D03*
X1615913Y692245D03*
X1624148Y708258D03*
X1628200Y711417D03*
X1612800Y705900D03*
X1620600D03*
X1620500Y723200D03*
X1628343Y747288D03*
X1616683Y744517D03*
X1620100Y738300D03*
X1627455Y759489D03*
X1624000Y760900D03*
X1612573Y761427D03*
X1619612Y783152D03*
X1620359Y774830D03*
X1619569Y796035D03*
X1620755Y787530D03*
X1613235Y808466D03*
X1620479Y815730D03*
X1620072Y801630D03*
X1628027Y801427D03*
X1616255Y824405D03*
X1613117Y828117D03*
X1619859Y839519D03*
X1618800Y1528558D03*
X1614200Y1519500D03*
X1614360Y1542860D03*
X1618600Y1532000D03*
X1631622Y53597D03*
X1640769Y85539D03*
Y82939D03*
Y75139D03*
Y80339D03*
Y77739D03*
X1631905Y95236D03*
X1631948Y103037D03*
X1632082Y116496D03*
Y109410D03*
X1640082Y116496D03*
Y109410D03*
Y102323D03*
X1642840Y104249D03*
Y107649D03*
X1632082Y130670D03*
Y123583D03*
X1640082Y130670D03*
Y123583D03*
X1628673Y137756D03*
X1640082D03*
X1639862Y162368D03*
X1642462D03*
X1641173Y213213D03*
Y210713D03*
Y208213D03*
X1630717Y210478D03*
Y215478D03*
Y212978D03*
Y207978D03*
X1641173Y231461D03*
X1630717Y223726D03*
Y226226D03*
Y231226D03*
Y228726D03*
X1641173Y226461D03*
X1644880Y226141D03*
X1641173Y228961D03*
Y215713D03*
X1644825Y248891D03*
X1634046Y264180D03*
X1636546D03*
X1633971Y258880D03*
X1642940Y267526D03*
Y270026D03*
X1644777Y288190D03*
X1642277Y285690D03*
X1644777D03*
X1642277Y288190D03*
X1636763Y293796D03*
X1634263D03*
X1629553Y329067D03*
X1632230Y330400D03*
X1635987Y335616D03*
X1629302Y334402D03*
X1640030Y335550D03*
X1636561Y343072D03*
X1629514Y331727D03*
X1630703Y350655D03*
X1636468Y345595D03*
X1630691Y347432D03*
X1640197Y374690D03*
X1638340Y379536D03*
X1641615Y379600D03*
X1636271Y410394D03*
X1637205Y440098D03*
Y437598D03*
Y435098D03*
Y432598D03*
Y430098D03*
X1635170Y442856D03*
X1637665Y458406D03*
Y451319D03*
X1636271Y453881D03*
X1637489Y462264D03*
X1632865Y465492D03*
X1637665D03*
Y472579D03*
X1632865D03*
X1630365D03*
Y479666D03*
X1632865D03*
X1637665Y479665D03*
Y486752D03*
X1630365D03*
X1632865D03*
X1630365Y493839D03*
X1637665D03*
X1632865Y509626D03*
Y516713D03*
X1630365D03*
Y523800D03*
X1632865D03*
X1637665Y523799D03*
Y516713D03*
Y509626D03*
X1630365Y530886D03*
X1637665D03*
X1632865D03*
X1637665Y537973D03*
X1630365D03*
X1637665Y559665D03*
Y566752D03*
X1630365D03*
X1632865D03*
Y559665D03*
Y573839D03*
X1630365Y580926D03*
X1632865D03*
X1637665D03*
Y588012D03*
X1630365Y588013D03*
X1632865Y588012D03*
X1637665Y573839D03*
X1630365D03*
X1632865Y602185D03*
X1630365Y602186D03*
X1637665Y602185D03*
Y595099D03*
X1632865D03*
X1630365D03*
Y616359D03*
X1632865Y609272D03*
X1630365D03*
X1637665Y616358D03*
Y609272D03*
X1637526Y699930D03*
X1637472Y717830D03*
X1631031Y732430D03*
X1628813Y727045D03*
X1635283Y728117D03*
X1631187Y750630D03*
X1629969Y740826D03*
X1630327Y774627D03*
X1629927Y787327D03*
X1644304Y891353D03*
X1641634Y1215452D03*
X1650417Y5374D03*
X1649730Y24773D03*
Y44773D03*
X1649365Y94017D03*
X1657374D03*
X1653365D03*
X1645365D03*
X1649094Y101701D03*
Y98551D03*
X1659895Y117557D03*
X1654485Y110445D03*
Y115401D03*
X1649493Y110445D03*
Y115401D03*
X1656644Y103783D03*
X1652644D03*
X1659579Y106186D03*
X1659895Y122513D03*
Y131731D03*
X1654485Y124618D03*
Y129574D03*
X1649493Y124618D03*
Y129574D03*
X1659895Y136687D03*
X1647406Y147540D03*
X1651178Y141247D03*
X1647406Y151540D03*
X1649562Y162793D03*
Y165393D03*
Y167993D03*
Y170493D03*
X1654565Y181009D03*
X1648559Y181426D03*
X1651770Y181366D03*
X1659740Y168697D03*
X1651056Y191941D03*
X1657556Y184619D03*
X1660828Y191941D03*
X1651384Y184012D03*
X1648767Y184221D03*
X1659536Y206760D03*
X1647745Y211695D03*
X1645245Y208695D03*
X1656506Y213132D03*
X1652803Y211359D03*
Y213859D03*
X1645245Y211695D03*
X1649142Y229286D03*
X1652835Y222212D03*
Y224712D03*
X1656506Y215632D03*
X1645123Y236611D03*
X1650123D03*
X1647623D03*
X1649142Y231786D03*
X1647325Y248891D03*
X1649825D03*
X1660750Y256535D03*
X1652750D03*
X1656750Y256303D03*
X1648240Y267526D03*
X1645740D03*
Y270026D03*
X1648240D03*
X1647577Y285690D03*
Y288190D03*
X1655803Y290755D03*
X1651803D03*
X1658200Y315039D03*
X1654771Y352088D03*
X1645685Y390500D03*
X1655335Y381500D03*
X1645685D03*
X1648835Y390500D03*
X1655555Y430760D03*
X1655576Y433570D03*
X1655392Y437072D03*
X1655433Y439963D03*
X1646209Y442606D03*
X1655677Y443180D03*
X1655697Y454744D03*
X1655639Y452018D03*
X1650087Y444841D03*
X1649773Y449961D03*
X1645826Y446606D03*
X1653507Y470136D03*
X1645465Y466027D03*
X1655776Y465492D03*
X1655742Y460250D03*
X1655776Y472579D03*
X1645607Y475262D03*
X1647133Y463479D03*
X1647604Y467367D03*
X1645607Y489435D03*
X1655776Y486752D03*
Y479665D03*
X1645607Y482666D03*
X1645423Y495088D03*
X1655776Y493839D03*
X1646158Y514608D03*
X1646080Y522134D03*
X1645465Y509626D03*
X1655776D03*
Y516713D03*
X1646562Y535677D03*
X1646723Y529136D03*
X1652236Y537973D03*
X1654716Y525483D03*
X1654637Y532756D03*
X1645465Y559665D03*
X1645846Y565574D03*
X1655776Y559665D03*
Y566752D03*
X1645493Y574338D03*
X1655626Y579978D03*
X1655776Y573839D03*
X1645592Y616358D03*
X1655840Y608117D03*
X1654572Y771702D03*
X1656112Y768669D03*
X1657042Y773604D03*
X1648375Y886766D03*
X1645128Y929263D03*
X1650205Y925911D03*
X1647763Y919268D03*
X1648387Y945554D03*
X1645342Y962120D03*
X1647470Y952125D03*
X1657091Y990823D03*
X1649571Y983857D03*
X1651443Y981515D03*
X1652944Y993796D03*
X1653414Y990590D03*
X1657983Y1460782D03*
X1649322Y1456451D03*
Y1465913D03*
X1657983Y1465513D03*
X1649322Y1461182D03*
Y1476536D03*
X1657983Y1476136D03*
Y1470244D03*
X1649322Y1471805D03*
Y1481267D03*
X1657983Y1480867D03*
X1649322Y1487159D03*
Y1496621D03*
X1657983Y1496221D03*
X1649322Y1491890D03*
X1657983Y1491490D03*
Y1485598D03*
Y1500952D03*
X1649322Y1502514D03*
X1657983Y1511576D03*
X1649322Y1511976D03*
Y1507245D03*
X1657983Y1506845D03*
Y1516307D03*
X1649322Y1558813D03*
Y1563544D03*
X1657983Y1563144D03*
Y1572606D03*
X1649322Y1574167D03*
Y1568275D03*
X1657983Y1567875D03*
X1649322Y1578898D03*
X1657983Y1578498D03*
X1649322Y1583629D03*
X1657983Y1583229D03*
X1649322Y1594253D03*
X1657983Y1593853D03*
Y1587960D03*
X1649322Y1589522D03*
Y1609607D03*
X1657983Y1609207D03*
X1649322Y1598984D03*
X1657983Y1598584D03*
Y1603315D03*
X1649322Y1604876D03*
Y1614338D03*
X1657983Y1613938D03*
Y1618669D03*
X1652000Y1644980D03*
X1669319Y3001D03*
X1676870Y55513D03*
X1673095Y68581D03*
X1662442Y84140D03*
Y76140D03*
Y80140D03*
X1673108Y80581D03*
X1665190Y76587D03*
Y72615D03*
X1677213Y91951D03*
X1677238Y88801D03*
X1675817Y117261D03*
X1664887Y117557D03*
X1667811Y103621D03*
X1671002Y112083D03*
X1664887Y122513D03*
Y131731D03*
X1662986Y146461D03*
X1664887Y136687D03*
X1661888Y152367D03*
X1673945Y152562D03*
X1663588Y180572D03*
X1668271Y180527D03*
X1669352Y171523D03*
X1671994Y192421D03*
X1663588Y185165D03*
X1668226Y185121D03*
X1675623Y186629D03*
X1667318Y198828D03*
X1664840Y192300D03*
X1662837Y206767D03*
X1667837D03*
X1665337D03*
X1667967Y221708D03*
X1665467D03*
X1664082Y228221D03*
X1672317Y221642D03*
X1662967Y221708D03*
X1662382Y224421D03*
X1669633Y236189D03*
X1667133D03*
X1664633D03*
X1667074Y248765D03*
X1664574D03*
X1669574D03*
X1661780Y279208D03*
X1676231Y265897D03*
X1673731D03*
X1670071Y268195D03*
Y270695D03*
X1667271Y268195D03*
X1664771D03*
Y270695D03*
X1667271D03*
X1670374Y290845D03*
Y288345D03*
X1667874Y290845D03*
Y288345D03*
X1670374Y293645D03*
X1667874D03*
X1674226Y324139D03*
X1673203Y328867D03*
Y332017D03*
X1666860Y353661D03*
X1663650Y353283D03*
X1673723Y353881D03*
X1670323Y353534D03*
X1663780Y384410D03*
X1663760Y410394D03*
Y403307D03*
X1663713Y440869D03*
Y438269D03*
X1666513Y433069D03*
Y430469D03*
Y435669D03*
Y440869D03*
Y438269D03*
X1663713Y433069D03*
Y430469D03*
Y435669D03*
X1663576Y458406D03*
X1669767Y445908D03*
X1673717Y445787D03*
X1664567Y451677D03*
X1667067D03*
X1664567Y454177D03*
X1667067D03*
X1663576Y465492D03*
Y472579D03*
X1666271Y460218D03*
Y463618D03*
X1663576Y479665D03*
Y486752D03*
Y493839D03*
Y523799D03*
Y516713D03*
Y509626D03*
Y537973D03*
Y530886D03*
Y559665D03*
Y566752D03*
Y580925D03*
Y588012D03*
Y573839D03*
Y602185D03*
Y595099D03*
Y616358D03*
Y609272D03*
X1666645Y1465913D03*
Y1456451D03*
Y1461182D03*
X1675306Y1465513D03*
Y1460782D03*
X1666645Y1471805D03*
Y1476536D03*
Y1481267D03*
X1675306Y1476136D03*
Y1470244D03*
Y1480867D03*
X1666645Y1487159D03*
Y1491890D03*
Y1496621D03*
X1675306Y1491490D03*
Y1485598D03*
Y1496221D03*
Y1511576D03*
X1666645Y1511976D03*
Y1507245D03*
Y1502514D03*
X1675306Y1506845D03*
Y1500952D03*
Y1516307D03*
X1666645Y1558813D03*
Y1563544D03*
X1675306Y1563144D03*
Y1578498D03*
Y1572606D03*
X1666645Y1568275D03*
X1675306Y1567875D03*
X1666645Y1574167D03*
Y1578898D03*
Y1583629D03*
X1675306Y1583229D03*
X1666645Y1589522D03*
Y1594253D03*
X1675306Y1593853D03*
Y1587960D03*
X1666645Y1604876D03*
Y1598984D03*
X1675306Y1609207D03*
Y1598584D03*
Y1603315D03*
X1666645Y1609607D03*
Y1614338D03*
X1675306Y1613938D03*
Y1618669D03*
X1672000Y1644980D03*
X1689319Y3001D03*
X1685184Y60922D03*
X1680020Y55513D03*
X1682330Y60438D03*
X1688011Y94374D03*
X1683152Y86046D03*
X1680155Y94351D03*
X1683348Y113394D03*
X1685997Y110784D03*
X1687566Y102249D03*
X1691566D03*
X1683348Y116594D03*
X1686171Y130898D03*
X1693591Y133298D03*
X1683348Y119594D03*
X1687738Y134579D03*
X1682189Y161306D03*
X1679440Y157370D03*
X1683524Y172665D03*
Y180665D03*
Y168665D03*
Y176665D03*
X1691366Y195176D03*
X1688866D03*
X1693485Y198883D03*
X1683524Y192665D03*
X1683637Y186778D03*
X1683556Y200864D03*
Y212864D03*
X1691226Y203393D03*
X1688726D03*
X1683556Y204864D03*
Y221864D03*
Y216864D03*
X1688605Y218085D03*
X1691405D03*
X1679197Y219379D03*
X1685313Y252371D03*
Y248371D03*
X1686115Y311740D03*
X1681273Y316731D03*
X1691117Y321649D03*
X1677810Y324466D03*
X1687164Y336324D03*
X1678072Y342319D03*
X1686408Y332584D03*
X1691743Y353506D03*
X1688593Y353470D03*
X1680518Y377912D03*
Y385912D03*
Y393924D03*
Y389912D03*
Y381912D03*
Y409924D03*
Y405924D03*
Y401924D03*
Y397912D03*
X1677933Y418838D03*
X1689757Y466528D03*
Y471484D03*
Y480701D03*
Y485657D03*
Y515617D03*
Y510661D03*
Y524835D03*
Y529791D03*
X1689920Y539315D03*
X1689236Y550137D03*
X1692028D03*
X1689757Y565657D03*
Y560701D03*
Y589047D03*
Y574874D03*
Y579830D03*
Y603221D03*
Y594003D03*
Y608177D03*
X1693000Y626912D03*
X1692379Y622912D03*
X1683968Y1465913D03*
Y1456451D03*
Y1461182D03*
X1692629Y1465513D03*
Y1460782D03*
X1683968Y1471805D03*
Y1476536D03*
Y1481267D03*
X1692629Y1476136D03*
Y1470244D03*
Y1480867D03*
X1683968Y1487159D03*
Y1491890D03*
Y1496621D03*
X1692629Y1491490D03*
Y1485598D03*
Y1496221D03*
X1683968Y1502514D03*
Y1511976D03*
X1692629Y1506845D03*
Y1500952D03*
Y1511576D03*
X1683968Y1507245D03*
X1692629Y1516307D03*
X1683968Y1558813D03*
Y1563544D03*
X1692629Y1563144D03*
Y1572606D03*
X1683968Y1568275D03*
Y1574167D03*
Y1578898D03*
X1692629Y1567875D03*
Y1578498D03*
X1683968Y1583629D03*
Y1589522D03*
Y1594253D03*
X1692629Y1583229D03*
Y1593853D03*
Y1587960D03*
X1683968Y1598984D03*
X1692629Y1609207D03*
Y1598584D03*
Y1603315D03*
X1683968Y1609607D03*
Y1604876D03*
Y1614338D03*
X1692629Y1613938D03*
Y1618669D03*
X1692000Y1644980D03*
X1705303Y4470D03*
X1706664Y24774D03*
Y44774D03*
X1709184Y95111D03*
X1698583Y109172D03*
X1701583D03*
X1700590Y106495D03*
X1709134Y116497D03*
X1704334D03*
X1695317Y116594D03*
X1700590Y102495D03*
X1709134Y123584D03*
Y130670D03*
X1704334Y123584D03*
Y130670D03*
X1695317Y119594D03*
X1700324Y146012D03*
X1702230Y141228D03*
X1709134Y137757D03*
X1704334D03*
X1700324Y142862D03*
X1705118Y150847D03*
X1693866Y195176D03*
X1708913D03*
X1706413D03*
X1703913D03*
X1707931Y199248D03*
X1697414Y206838D03*
X1694914D03*
X1707931Y201748D03*
X1706494Y210509D03*
X1703994D03*
X1705767Y206806D03*
X1708267D03*
X1697984Y226320D03*
X1695205Y216385D03*
X1697918Y216970D03*
Y219470D03*
Y221970D03*
X1707086Y247292D03*
X1699876Y236121D03*
X1696910Y238589D03*
X1706312Y238689D03*
X1704671Y242078D03*
X1699902Y232971D03*
X1699795Y253198D03*
X1701495Y289735D03*
X1700223Y292141D03*
X1703609Y287320D03*
X1695142Y303839D03*
X1698292Y303962D03*
X1694749Y466528D03*
Y471484D03*
X1700159Y473640D03*
X1705151D03*
Y487813D03*
X1700159D03*
X1705151Y478596D03*
X1694749Y480701D03*
X1700159Y478596D03*
X1694749Y485657D03*
X1700159Y492769D03*
X1705151D03*
Y517774D03*
Y522730D03*
X1694749Y510661D03*
Y515617D03*
X1700159Y517774D03*
Y522730D03*
Y536903D03*
X1705151D03*
Y531947D03*
X1694749Y524835D03*
Y529791D03*
X1700159Y531947D03*
X1705151Y572769D03*
X1700159D03*
X1705151Y567813D03*
X1698839Y564843D03*
X1700159Y567813D03*
X1694749Y565657D03*
Y560701D03*
Y579830D03*
X1705151Y586943D03*
Y581987D03*
X1694749Y589047D03*
X1700159Y586943D03*
Y581987D03*
X1694749Y574874D03*
Y603221D03*
X1700159Y601116D03*
X1705151D03*
Y596160D03*
X1700159D03*
X1694749Y594003D03*
X1705151Y615289D03*
X1700159Y610333D03*
X1694749Y608177D03*
X1700159Y615289D03*
X1705151Y610333D03*
X1708015Y1142700D03*
X1708889Y1189221D03*
X1703400Y1174400D03*
X1701290Y1465913D03*
Y1456451D03*
Y1461182D03*
Y1471805D03*
Y1476536D03*
Y1481267D03*
Y1487159D03*
Y1491890D03*
Y1496621D03*
Y1507245D03*
Y1502514D03*
Y1511976D03*
Y1558813D03*
Y1563544D03*
Y1568275D03*
Y1574167D03*
Y1578898D03*
Y1583629D03*
Y1589522D03*
Y1594253D03*
Y1609607D03*
Y1604876D03*
Y1598984D03*
Y1614338D03*
X1713985Y53598D03*
X1724796Y82984D03*
Y77784D03*
Y80384D03*
Y75184D03*
Y85584D03*
X1724334Y95236D03*
X1716334Y116496D03*
Y109410D03*
Y102323D03*
X1711634Y116497D03*
Y109410D03*
X1724334Y102323D03*
X1724586Y109410D03*
Y116496D03*
X1713553Y106561D03*
X1724758Y124576D03*
X1725811Y130670D03*
X1716334D03*
Y123583D03*
X1711634D03*
Y130670D03*
X1725806Y137756D03*
X1716334D03*
X1711413Y195176D03*
X1712866Y213539D03*
X1710931Y202048D03*
X1714547Y238714D03*
X1710547D03*
X1710028Y246874D03*
X1712248Y244297D03*
X1715705Y328692D03*
X1716755Y326179D03*
X1712734Y340534D03*
X1712226Y344028D03*
X1715930Y340969D03*
X1715590Y331719D03*
X1725746Y377173D03*
X1723964Y370935D03*
X1721746Y377173D03*
X1715228Y387966D03*
X1718851Y391533D03*
X1725415Y416289D03*
Y418889D03*
Y421489D03*
X1721423Y412106D03*
X1718710Y447486D03*
X1716310Y458334D03*
Y454334D03*
X1724930Y473571D03*
Y491118D03*
Y488618D03*
Y476071D03*
Y478571D03*
Y481071D03*
Y493618D03*
Y496118D03*
X1710174Y553101D03*
X1717626Y1134729D03*
X1710511Y1138130D03*
X1721008Y1134729D03*
X1725008Y1134636D03*
X1720960Y1148000D03*
X1723796Y1160168D03*
X1712526Y1171950D03*
X1725660Y1193019D03*
X1721660D03*
X1711783Y1193848D03*
X1721662Y1201043D03*
X1725658D03*
X1718625Y1199814D03*
X1712542Y1196600D03*
X1720536Y1217228D03*
X1723200Y1219895D03*
X1710825Y1231688D03*
X1709952Y1465513D03*
Y1460782D03*
X1718613Y1465914D03*
Y1456452D03*
Y1461183D03*
Y1476537D03*
Y1471806D03*
Y1481268D03*
X1709952Y1476136D03*
Y1470244D03*
Y1480867D03*
Y1491490D03*
Y1485598D03*
Y1496221D03*
X1718613Y1491891D03*
Y1487160D03*
Y1496622D03*
Y1502515D03*
Y1511977D03*
X1709952Y1506845D03*
Y1500952D03*
Y1511576D03*
X1718613Y1507246D03*
X1709952Y1516307D03*
Y1563144D03*
X1718613Y1563544D03*
Y1558813D03*
X1709952Y1567875D03*
X1718613Y1568275D03*
X1709952Y1578498D03*
Y1572606D03*
X1718613Y1578898D03*
Y1574167D03*
Y1589522D03*
X1709952Y1583229D03*
X1718613Y1583629D03*
X1709952Y1593853D03*
Y1587960D03*
X1718613Y1594253D03*
Y1609607D03*
Y1598984D03*
Y1604876D03*
X1709952Y1609207D03*
Y1598584D03*
Y1603315D03*
Y1618669D03*
X1718613Y1614338D03*
X1709952Y1613938D03*
X1712000Y1644980D03*
X1742336Y-87777D03*
X1739311Y-86371D03*
X1733909Y-83456D03*
Y-78500D03*
X1736405Y-79278D03*
Y-82678D03*
X1742336Y-74565D03*
Y-64265D03*
X1739311Y-65585D03*
Y-75885D03*
X1733909Y-68500D03*
Y-73456D03*
X1733985Y53598D03*
X1727350Y92849D03*
X1734267Y95236D03*
X1734310Y103037D03*
X1734444Y116496D03*
Y109410D03*
Y130670D03*
Y123583D03*
X1730647Y137756D03*
X1742224Y162368D03*
X1733079Y207978D03*
Y210478D03*
Y215478D03*
Y212978D03*
Y223726D03*
Y226226D03*
Y231226D03*
Y228726D03*
X1736408Y264180D03*
X1738908D03*
X1736333Y258880D03*
X1739125Y293796D03*
X1736625D03*
X1734826Y376499D03*
X1741746Y377173D03*
X1737786D03*
X1729751D03*
X1733027Y392228D03*
X1728433Y392183D03*
X1733746Y385123D03*
X1735811Y409032D03*
X1732494Y402867D03*
X1728478Y396866D03*
X1733071D03*
X1739847Y401066D03*
X1729508Y403300D03*
X1728915Y405889D03*
Y408489D03*
Y413689D03*
Y411089D03*
Y416289D03*
Y421489D03*
Y418889D03*
Y424089D03*
X1729302Y439718D03*
Y442518D03*
Y432718D03*
Y435518D03*
X1739179Y439318D03*
X1728915Y426689D03*
X1739179Y442118D03*
Y449118D03*
Y446318D03*
X1738824Y452740D03*
X1736214Y450091D03*
X1733014D03*
X1730014D03*
X1727404Y447209D03*
X1730404D03*
X1737703Y472189D03*
X1740542Y468088D03*
Y465288D03*
X1733014Y462060D03*
X1730014D03*
X1736592Y487570D03*
Y490070D03*
X1734952Y479217D03*
X1737646Y477213D03*
Y479713D03*
X1729002Y477053D03*
X1731502D03*
X1734952Y476717D03*
X1728038Y491870D03*
X1730538D03*
X1733147Y493758D03*
Y496258D03*
X1741800Y917900D03*
X1742029Y1116251D03*
X1730675Y1132361D03*
X1726963Y1132319D03*
X1739508Y1137129D03*
X1729008Y1134729D03*
X1732881D03*
X1739917Y1150087D03*
X1729207Y1159455D03*
X1737393Y1162817D03*
Y1170767D03*
X1728333Y1178240D03*
X1733660Y1193019D03*
X1729660D03*
X1737660D03*
X1733662Y1201039D03*
X1729628Y1201043D03*
X1737662Y1200969D03*
X1733695Y1212164D03*
X1735989Y1214458D03*
X1740785Y1219254D03*
X1737781Y1208993D03*
X1726475Y1223170D03*
X1731533Y1228226D03*
X1729322Y1226016D03*
X1732000Y1644980D03*
X1742351Y-77080D03*
X1745592Y-79984D03*
X1745604Y-77094D03*
X1745589Y-87777D03*
X1742351Y-85262D03*
X1745604D03*
X1745592Y-82584D03*
Y-71970D03*
X1745589Y-74579D03*
Y-64265D03*
X1745592Y-69470D03*
X1742351Y-66780D03*
X1745604D03*
X1752778Y5374D03*
X1752091Y24773D03*
Y44773D03*
X1743131Y85539D03*
Y82939D03*
Y75139D03*
Y80339D03*
Y77739D03*
X1755727Y94017D03*
X1751456Y101701D03*
X1747727Y94017D03*
X1751727D03*
X1751456Y98551D03*
X1742444Y102323D03*
Y116496D03*
Y109410D03*
X1751855Y110445D03*
Y115401D03*
X1756847D03*
Y110445D03*
X1755006Y103783D03*
X1745202Y104249D03*
Y107649D03*
X1742444Y130670D03*
Y123583D03*
X1751855Y129574D03*
Y124618D03*
X1756847D03*
Y129574D03*
X1742444Y137756D03*
X1744824Y162368D03*
X1751924Y162793D03*
Y165393D03*
Y167993D03*
Y170493D03*
X1756927Y181009D03*
X1750921Y181426D03*
X1754132Y181366D03*
X1753418Y191941D03*
X1751129Y184221D03*
X1753746Y184012D03*
X1747607Y211695D03*
X1755165Y211359D03*
Y213859D03*
X1750107Y211695D03*
X1747607Y208695D03*
X1743535Y208213D03*
Y213213D03*
Y210713D03*
Y226461D03*
X1747242Y226141D03*
X1755197Y224712D03*
X1743535Y228961D03*
Y231461D03*
X1751504Y229286D03*
X1755197Y222212D03*
X1743535Y215713D03*
X1752485Y236611D03*
X1749985D03*
X1751504Y231786D03*
X1747485Y236611D03*
X1747187Y248891D03*
X1749687D03*
X1752187D03*
X1755112Y256535D03*
X1750602Y267526D03*
X1745302D03*
X1748102D03*
X1745302Y270026D03*
X1748102D03*
X1750602D03*
X1749939Y288190D03*
X1747139D03*
X1744639D03*
X1749939Y285690D03*
X1744639D03*
X1747139D03*
X1758165Y290755D03*
X1754165D03*
X1744524Y370010D03*
X1756497Y370976D03*
X1748497Y371060D03*
X1747561Y385161D03*
X1744180Y383966D03*
X1748252Y395248D03*
X1750187Y409539D03*
X1753187D03*
Y407039D03*
X1752851Y401981D03*
X1755351D03*
X1757124Y398278D03*
X1754624D03*
X1749470Y424067D03*
X1751970D03*
X1756970D03*
X1754470D03*
X1749705Y413611D03*
X1752205D03*
X1757205D03*
X1754705D03*
X1756844Y438293D03*
X1747179Y439318D03*
X1756844Y441093D03*
X1747179Y442118D03*
X1756844Y450041D03*
Y452841D03*
Y455641D03*
X1747179Y449118D03*
Y446318D03*
X1747359Y454309D03*
Y458309D03*
X1756844Y443893D03*
X1747359Y462309D03*
X1747306Y470001D03*
X1744806D03*
X1745231Y489036D03*
X1743092Y485580D03*
X1745592D03*
X1748092D03*
X1758401Y484882D03*
X1747467Y492836D03*
Y495636D03*
X1753474Y542699D03*
X1756089Y542952D03*
X1750879Y541940D03*
X1757402Y825111D03*
Y820155D03*
X1754906Y824333D03*
Y820737D03*
X1746897Y879199D03*
X1746884Y884649D03*
X1744937Y912517D03*
X1747937D03*
X1750751Y910785D03*
X1747900Y900160D03*
X1744900D03*
X1750915Y902055D03*
X1749267Y918413D03*
X1751200Y931100D03*
X1746600Y935100D03*
X1748081Y984379D03*
X1751854Y991297D03*
X1749314Y987904D03*
X1748677Y993986D03*
X1756192Y996132D03*
X1753860Y997271D03*
X1743224Y1119055D03*
X1744529Y1116251D03*
X1758390Y1577905D03*
X1758583Y1581027D03*
X1750685Y1621654D03*
X1756422Y1640303D03*
X1752000Y1644980D03*
X1765559Y3001D03*
X1764804Y84140D03*
Y76140D03*
Y80140D03*
X1767552Y76587D03*
Y72615D03*
X1759736Y94017D03*
X1767249Y117557D03*
X1770173Y103621D03*
X1759006Y103783D03*
X1762257Y117557D03*
X1761941Y106186D03*
X1773364Y112083D03*
X1762257Y122513D03*
Y131731D03*
X1767249Y122513D03*
Y131731D03*
X1762257Y136687D03*
X1767249D03*
X1765950Y180572D03*
X1770633Y180527D03*
X1771714Y171523D03*
X1762102Y168697D03*
X1774356Y192421D03*
X1759918Y184619D03*
X1770588Y185121D03*
X1765950Y185165D03*
X1763190Y191941D03*
X1767202Y192300D03*
X1761898Y206760D03*
X1765199Y206767D03*
X1770199D03*
X1767699D03*
X1758868Y213132D03*
X1765329Y221708D03*
X1770329D03*
X1767829D03*
X1764744Y224421D03*
X1766444Y231021D03*
Y228221D03*
X1774679Y221642D03*
X1758868Y215632D03*
X1771995Y236189D03*
X1769495D03*
X1766995D03*
X1763112Y256535D03*
X1771936Y248765D03*
X1769436D03*
X1766936D03*
X1759112Y256303D03*
X1764142Y279208D03*
X1767133Y270695D03*
X1769633D03*
X1772433Y268195D03*
Y270695D03*
X1769633Y268195D03*
X1767133D03*
X1772736Y293645D03*
X1770236D03*
Y290845D03*
Y288345D03*
X1772736Y290845D03*
Y288345D03*
X1760497Y371070D03*
X1765497Y370899D03*
X1762997Y377581D03*
X1772513Y387702D03*
X1769713D03*
X1765913Y389402D03*
X1763200Y388817D03*
Y383817D03*
Y386317D03*
X1766204Y398949D03*
X1770778Y402642D03*
X1773278D03*
X1767633Y409904D03*
X1763704Y401949D03*
X1767953Y413611D03*
X1770453D03*
X1772953D03*
X1772893Y423944D03*
X1770393D03*
X1767893D03*
X1766837Y438293D03*
Y441093D03*
Y450041D03*
Y452841D03*
Y455641D03*
Y443893D03*
X1765097Y466409D03*
X1768586Y467560D03*
X1764903Y470382D03*
X1765083Y487382D03*
X1764912Y482382D03*
X1768575Y479560D03*
X1765006Y478382D03*
X1768575Y475560D03*
X1770135Y490711D03*
X1758957Y543036D03*
X1761953Y706827D03*
X1772768Y818696D03*
X1761953Y865160D03*
X1773600Y888100D03*
X1773614Y895275D03*
X1773600Y902800D03*
X1770680Y926322D03*
X1763818Y926241D03*
X1773789Y927663D03*
X1765664Y923724D03*
X1769064D03*
X1773789Y930663D03*
X1772599Y993053D03*
X1762898Y992883D03*
X1774476Y995049D03*
X1773810Y990821D03*
X1762486Y990260D03*
X1760201Y992475D03*
X1758881Y995633D03*
X1769004Y1019395D03*
X1768844Y1027248D03*
X1771773Y1028829D03*
X1764744Y1101930D03*
Y1097879D03*
X1766899Y1121122D03*
X1769499D03*
X1772099D03*
X1774799D03*
X1766999Y1130822D03*
X1772199D03*
X1769599D03*
X1774339Y1437975D03*
X1774216Y1470165D03*
X1765294Y1575434D03*
X1759092Y1588137D03*
X1767142Y1588219D03*
X1760422Y1640303D03*
X1768422D03*
X1772422D03*
X1772000Y1644980D03*
X1788884Y59871D03*
X1782382Y55513D03*
X1779232D03*
X1775457Y68581D03*
X1785246Y60660D03*
X1775470Y80581D03*
X1790664Y71908D03*
X1779575Y91951D03*
X1779600Y88801D03*
X1790373Y94663D03*
X1786466Y85923D03*
X1782517Y94351D03*
X1778179Y117261D03*
X1777653Y103621D03*
X1785886Y172665D03*
Y180665D03*
Y168665D03*
Y176665D03*
X1777985Y186629D03*
X1785779Y192665D03*
X1785886Y196665D03*
X1785999Y186778D03*
X1785918Y200864D03*
Y212864D03*
Y204864D03*
Y216864D03*
Y221864D03*
X1778593Y265897D03*
X1776093D03*
X1790533Y303750D03*
X1787674Y303130D03*
X1777681Y387151D03*
Y382151D03*
Y384651D03*
X1790136Y399161D03*
Y401661D03*
Y396661D03*
X1778103Y399161D03*
Y401661D03*
Y396661D03*
X1783028Y408240D03*
X1785528D03*
X1780528D03*
X1783107Y424240D03*
X1780646Y420393D03*
X1785646D03*
X1783146D03*
X1783107Y426740D03*
X1786184Y435321D03*
Y438121D03*
X1783384Y435321D03*
Y438121D03*
X1786184Y440921D03*
X1783384D03*
X1786713Y455039D03*
X1786184Y443721D03*
X1783384D03*
X1790014Y468607D03*
X1783014Y474513D03*
X1786693Y459170D03*
X1784602Y564092D03*
X1791041Y818795D03*
X1778801Y836469D03*
X1782600Y874500D03*
X1780016Y874400D03*
X1788400Y888100D03*
X1781000Y888087D03*
X1788396Y895066D03*
X1788300Y902800D03*
X1780665Y902796D03*
X1786256Y927626D03*
X1784306Y924601D03*
X1775904Y924546D03*
X1778047Y916120D03*
X1786256Y930626D03*
X1789537Y930498D03*
X1780158Y953295D03*
X1785758Y956095D03*
Y953295D03*
X1782958D03*
Y956095D03*
X1780158D03*
X1784763Y964660D03*
X1789363Y969160D03*
X1782563Y979660D03*
X1785663D03*
X1779363D03*
X1779143Y995203D03*
X1786740Y1019237D03*
X1780802Y1019474D03*
X1774863Y1019237D03*
X1774844Y1023694D03*
X1783844D03*
X1786844Y1027248D03*
X1780844D03*
X1774844D03*
X1789844Y1023694D03*
X1775998Y1074707D03*
Y1072207D03*
X1781198Y1074707D03*
X1778598D03*
X1783798D03*
Y1072207D03*
X1778598D03*
X1781198D03*
X1790736Y1072090D03*
Y1074590D03*
X1780326Y1089851D03*
X1777726D03*
X1782926D03*
Y1092351D03*
X1777726D03*
X1780326D03*
X1775126Y1089851D03*
Y1092351D03*
X1790639Y1082585D03*
X1790572Y1085152D03*
X1780662Y1108413D03*
X1783262D03*
X1778062D03*
X1775462D03*
X1785321Y1121122D03*
X1787921D03*
X1790521D03*
X1780566Y1111038D03*
X1783166D03*
X1777966D03*
X1775366D03*
X1774899Y1130822D03*
Y1139822D03*
X1777399D03*
X1790521Y1130822D03*
X1781874Y1139822D03*
X1787921Y1130822D03*
X1785321D03*
X1784374Y1139822D03*
X1777399Y1147822D03*
X1774899D03*
X1781802D03*
X1784302D03*
X1779581Y1222200D03*
Y1219400D03*
Y1216600D03*
Y1213800D03*
X1782581Y1222200D03*
Y1219400D03*
Y1216600D03*
Y1213800D03*
X1780397Y1237469D03*
Y1230569D03*
Y1228069D03*
X1779581Y1225000D03*
X1782581D03*
X1785961Y1224892D03*
X1780397Y1234969D03*
Y1241869D03*
Y1244369D03*
Y1248769D03*
Y1251269D03*
X1779868Y1446668D03*
X1778227Y1438099D03*
X1786091Y1443715D03*
X1783178Y1437550D03*
X1786564Y1478858D03*
X1778104Y1470289D03*
X1776422Y1640303D03*
X1804667Y-47581D03*
X1799265Y-44666D03*
X1804667Y-37095D03*
X1799265Y-39710D03*
Y-29710D03*
Y-34666D03*
X1801761Y-43888D03*
Y-40488D03*
X1804667Y-26795D03*
X1791570Y74535D03*
X1791088Y77296D03*
X1804758Y294429D03*
X1804993Y297591D03*
X1793524Y303343D03*
X1805196Y300952D03*
X1799897Y408104D03*
X1802697D03*
X1805497D03*
X1793475Y424939D03*
X1799614Y420375D03*
X1802414D03*
X1805214D03*
X1804984Y433975D03*
X1803570Y436164D03*
X1793475Y427439D03*
X1804933Y461607D03*
X1796933D03*
X1796136Y471334D03*
X1800933Y461607D03*
X1793149Y662810D03*
X1798705Y718793D03*
X1791302Y829031D03*
X1802000Y892447D03*
X1797365Y930761D03*
X1793474Y930374D03*
X1794163Y968760D03*
X1797963D03*
X1792263Y962960D03*
X1805463Y969260D03*
X1801963Y969160D03*
X1798163Y982360D03*
X1793563D03*
X1805863Y980760D03*
X1803351Y1027471D03*
X1805188Y1019078D03*
X1799646Y1018999D03*
X1793470Y1018762D03*
X1801844Y1023694D03*
X1795844D03*
X1798844Y1027248D03*
X1792844D03*
X1795936Y1072090D03*
X1793336D03*
X1798536D03*
Y1074590D03*
X1793336D03*
X1795936D03*
X1805013Y1091877D03*
X1792847Y1099210D03*
X1799012Y1095893D03*
X1805013Y1096470D03*
X1792863Y1103246D03*
X1800813D03*
X1806206Y1114589D03*
X1803506D03*
X1800906D03*
X1798306D03*
X1798702Y1124328D03*
X1801302D03*
X1803902D03*
X1806602D03*
X1793221Y1121122D03*
Y1130822D03*
X1804532Y1133356D03*
X1807232D03*
X1807035Y1136912D03*
Y1144912D03*
X1801285Y1213373D03*
X1801147Y1208555D03*
X1802844Y1227695D03*
X1799845Y1261044D03*
X1794845D03*
X1797345D03*
X1799845Y1263544D03*
X1797345D03*
X1794845D03*
X1793976Y1440762D03*
X1803885Y1435046D03*
X1806428Y1444543D03*
X1807270Y1468535D03*
X1793879Y1472952D03*
X1803762Y1467236D03*
X1792000Y1644980D03*
X1809078Y2165771D03*
X1806706Y2180760D03*
X1807692Y-49001D03*
X1810945Y-48987D03*
X1807707Y-46486D03*
X1810960Y-46472D03*
X1810948Y-33180D03*
X1807692Y-35775D03*
X1810945Y-35789D03*
X1810948Y-30680D03*
X1807707Y-38290D03*
X1810948Y-41194D03*
X1810960Y-38304D03*
X1810948Y-43794D03*
X1807692Y-25475D03*
X1810945D03*
X1807707Y-27990D03*
X1810960D03*
X1822983Y346053D03*
Y366053D03*
Y386053D03*
Y406053D03*
Y426053D03*
Y446053D03*
Y466053D03*
Y486053D03*
Y506053D03*
Y526053D03*
Y546053D03*
Y566053D03*
Y586053D03*
Y606053D03*
Y626053D03*
Y646053D03*
Y666053D03*
Y686053D03*
Y706053D03*
Y726053D03*
Y746053D03*
Y766053D03*
Y786053D03*
Y806053D03*
Y826053D03*
Y846053D03*
Y866053D03*
Y886053D03*
Y906053D03*
X1819900Y906900D03*
X1822983Y926053D03*
Y946053D03*
X1816322Y977215D03*
X1807663Y966660D03*
Y963860D03*
X1823074Y992833D03*
X1808014Y984832D03*
X1812538Y1026859D03*
X1811468Y1021084D03*
X1807844Y1023694D03*
Y1027248D03*
X1810349Y1031264D03*
X1812296Y1075688D03*
X1809696Y1091832D03*
X1809651Y1096426D03*
X1816756Y1097145D03*
X1823028Y1124289D03*
X1817728D03*
X1815128D03*
X1820328D03*
X1822928Y1114589D03*
X1820228D03*
X1815028D03*
X1817628D03*
X1816385Y1136912D03*
X1813885D03*
X1815865Y1133356D03*
X1809535Y1136912D03*
X1813885Y1144912D03*
X1816385D03*
X1809535D03*
X1822594Y1211054D03*
Y1215324D03*
X1809897Y1237285D03*
Y1230385D03*
Y1232885D03*
X1811482Y1226423D03*
X1809897Y1239785D03*
Y1244185D03*
Y1246685D03*
X1810018Y1295944D03*
X1812818D03*
X1815618Y1298744D03*
Y1295944D03*
X1812818Y1298744D03*
X1810018D03*
X1807393Y1436345D03*
X1809342Y1476733D03*
X1812000Y1644980D03*
X1812366Y2063809D03*
X1822066Y2054109D03*
X1812366D03*
X1813087Y2087512D03*
X1825427Y2104853D03*
X1817378Y2165771D03*
X1815006Y2180760D03*
X1825559Y3001D03*
X1836543Y4470D03*
X1837904Y24774D03*
Y44774D03*
Y64774D03*
Y84774D03*
Y104774D03*
Y124774D03*
Y144774D03*
Y164774D03*
Y184774D03*
Y204774D03*
Y224774D03*
Y244774D03*
Y264774D03*
Y284774D03*
Y304774D03*
X1837728Y324733D03*
X1830094Y333210D03*
X1830472Y960970D03*
X1837937Y973244D03*
X1831511Y978888D03*
X1837937Y993244D03*
X1831914Y992877D03*
X1837937Y1013244D03*
Y1033244D03*
Y1053244D03*
Y1073244D03*
X1824706Y1081145D03*
Y1089145D03*
Y1085145D03*
X1824949Y1077145D03*
X1824733Y1102830D03*
X1837937Y1093244D03*
X1825832Y1097589D03*
X1824706Y1100185D03*
Y1106145D03*
X1828272Y1095968D03*
X1824706Y1093150D03*
X1837937Y1113244D03*
X1830915Y1109146D03*
X1837937Y1133244D03*
Y1153244D03*
Y1173244D03*
Y1193244D03*
Y1213244D03*
X1834665Y1213239D03*
X1837937Y1253244D03*
Y1273244D03*
Y1293244D03*
Y1313244D03*
Y1333244D03*
Y1353244D03*
Y1373244D03*
Y1393244D03*
Y1433244D03*
Y1453244D03*
Y1473244D03*
Y1493244D03*
Y1513244D03*
Y1533244D03*
Y1553244D03*
Y1573244D03*
X1837933Y1636171D03*
X1832000Y1644980D03*
X1841295Y2065122D03*
X1832995D03*
X1833649Y2057507D03*
X1830872Y2083503D03*
X1840875Y2083215D03*
X1837649Y2072324D03*
X1829349D03*
X1833727Y2104853D03*
X1835862Y2121040D03*
X1833506Y2185252D03*
X1852032Y2052576D03*
X1854559Y2077931D03*
X1851762Y2121040D03*
X1854796Y2170548D03*
X1846496D03*
X1855978Y2185118D03*
X1847678D03*
X1859032Y2052576D03*
X1870505Y2064156D03*
X1860338Y2071384D03*
X1874505Y2078973D03*
X1860234Y2157701D03*
X1867072Y2174962D03*
X1864547Y2185020D03*
X1890039Y2066092D03*
X1878805Y2064156D03*
X1886128Y2075919D03*
X1882805Y2078973D03*
X1876497Y2070684D03*
X1884535Y2155415D03*
X1882972Y2174962D03*
X1882111Y2179074D03*
X1874932Y2180585D03*
X1881852Y2196600D03*
X1886699Y2183170D03*
X1876697D03*
X1905939Y2066092D03*
X1893118Y2054585D03*
X1905944Y2055424D03*
X1898342Y2062143D03*
X1901295Y2072745D03*
X1892835Y2155415D03*
X1902872Y2178531D03*
X1894572D03*
X1893087Y2168011D03*
X1896403Y2185019D03*
X1917195Y2072745D03*
X1917550Y2158451D03*
X1909250D03*
X1922010Y2151829D03*
X1913710D03*
X1921855Y2172152D03*
X1936295Y2074343D03*
X1935195Y2155918D03*
X1936377Y2163810D03*
X1924735Y2178131D03*
X1936212Y2173508D03*
X1930155Y2172152D03*
X1931738Y2182647D03*
X1923438D03*
X1941040Y2070124D03*
X1951095Y2155918D03*
X1946077Y2163810D03*
X1969128Y2161283D03*
X1959428D03*
X1969128Y2151583D03*
X1959428D03*
G54D113*
G01X45274Y843218D02*
Y838493D01*
G01X49049Y845293D02*
X51383Y847627D01*
X60565D01*
G01X45274Y843218D02*
X47349Y845293D01*
X49049D01*
G01X45274Y838493D02*
X46049Y837718D01*
G01X69049Y847718D02*
X65957D01*
X65866Y847627D01*
X63715D01*
G01X292814Y1189271D02*
X291444Y1187901D01*
Y1187106D01*
G01X417305Y1362459D02*
Y1359169D01*
G01Y1368259D02*
X418610Y1369564D01*
Y1371590D01*
G01X435198Y1314391D02*
X433893Y1315696D01*
X431867D01*
G01X440998Y1314391D02*
X444288D01*
G01X454591Y1007191D02*
Y1006299D01*
X456210Y1004680D01*
G01X450591Y1007191D02*
Y1004766D01*
G01Y1017341D02*
X452226D01*
X453710Y1018825D01*
G01X443591Y1017341D02*
Y1019766D01*
G01X447091Y1017341D02*
Y1019766D01*
G01X459360Y1002180D02*
Y1004680D01*
G01D02*
X459310Y1004730D01*
Y1007325D01*
G01X464795Y1000647D02*
X472307D01*
X476542Y996412D01*
X486353D01*
X493569Y1003628D01*
Y1016282D01*
X496509Y1019222D01*
Y1024165D01*
G01X506461Y712755D02*
X507918D01*
X512239Y708434D01*
G01X496497Y1028165D02*
X499098Y1030766D01*
X506566D01*
G01X515381Y688961D02*
Y692323D01*
X515573Y692515D01*
G01X512239Y708434D02*
X514285Y706388D01*
X515649D01*
G01X525241Y793574D02*
X522316D01*
G01X525241Y796724D02*
X523083D01*
X522705Y797102D01*
X522697D01*
G01X529469Y706230D02*
X530723D01*
X533204Y708711D01*
G01X534241Y822574D02*
X531432D01*
X531313Y822693D01*
G01X534241Y825724D02*
X532219D01*
X531313Y826630D01*
G01X583501Y800831D02*
Y797111D01*
G01X586103Y961807D02*
X583129D01*
X583126Y961804D01*
X580975D01*
G01X748031Y1191141D02*
X748531Y1190641D01*
Y1187106D01*
G01X886476Y571532D02*
Y569528D01*
X887417Y568587D01*
Y566713D01*
G01X900030Y559623D02*
X898815Y560838D01*
G01D02*
Y564626D01*
G01X971443Y938828D02*
X966953Y943318D01*
X954728D01*
X947565Y936155D01*
Y925756D01*
X944622Y922813D01*
Y907198D01*
X941592Y904168D01*
Y900908D01*
G01X1007683Y339880D02*
Y342399D01*
X1009770Y344486D01*
G01X1003076Y332496D02*
X1003303D01*
X1003895Y333088D01*
G01D02*
X1007683D01*
G01X1027719Y958822D02*
Y956537D01*
X1027220Y956038D01*
Y954222D01*
G01X1055521Y1438500D02*
X1055387Y1438634D01*
X1054004D01*
X1053367Y1437997D01*
X1050944D01*
G01D02*
Y1439703D01*
X1051527Y1440286D01*
Y1442436D01*
G01X1160913Y782873D02*
Y786870D01*
G01X1206987Y1189271D02*
X1205617Y1187901D01*
Y1187106D01*
G01X1346083Y1125826D02*
Y1127115D01*
X1347300Y1128332D01*
G01X1342218Y1125863D02*
Y1127231D01*
X1343725Y1128738D01*
G01X1364765Y1007191D02*
Y1004766D01*
G01Y1017341D02*
X1366400D01*
X1367884Y1018825D01*
G01X1357765Y1017341D02*
Y1019766D01*
G01X1361265Y1017341D02*
Y1019766D01*
G01X1368765Y1007191D02*
Y1006299D01*
X1370384Y1004680D01*
G01X1373534Y1002180D02*
Y1004680D01*
G01D02*
X1373484Y1004730D01*
Y1007325D01*
G01X1378938Y1000586D02*
X1389287D01*
X1393211Y996662D01*
X1395517D01*
X1401405Y1002550D01*
Y1010476D01*
X1410581Y1019652D01*
Y1024254D01*
G01X1490000Y920925D02*
X1487075D01*
G01X1490000Y924075D02*
X1487618D01*
X1487240Y924453D01*
G01X1499000Y949925D02*
X1496191D01*
X1496072Y950044D01*
G01X1499000Y953075D02*
X1496978D01*
X1496072Y953981D01*
G01X1514500Y876339D02*
X1519063D01*
G01X1664074Y1189271D02*
X1662704Y1187901D01*
Y1187106D01*
G01X1779363Y979660D02*
X1782249Y982546D01*
X1785879D01*
X1787196Y982284D01*
X1789487D01*
X1790355Y983152D01*
Y985254D01*
X1792549Y987448D01*
Y989590D01*
G01D02*
X1796377D01*
X1799355Y992568D01*
X1803251D01*
X1805168Y990651D01*
Y987540D01*
X1805014Y987386D01*
Y985060D01*
G01X1802363Y989660D02*
Y987375D01*
X1801864Y986876D01*
Y985060D01*
G54D20*
X18037Y1512511D03*
X21537D03*
X63981Y1212146D03*
X96443Y890391D03*
X156299Y1135426D03*
X160039D03*
X220500Y536517D03*
X221263Y632670D03*
X223952Y1213969D03*
X246695Y633206D03*
X291444Y1184048D03*
X408523Y1327161D03*
X404657Y1327185D03*
X395959Y1355068D03*
X400879Y1400335D03*
X395111Y1490998D03*
X409981Y1534003D03*
X404157D03*
X424016Y328157D03*
X425773Y1265489D03*
X418735Y1282581D03*
X414735D03*
X416357Y1398966D03*
X410152Y1405470D03*
X430959Y328106D03*
X431822Y1122849D03*
X427997Y1122834D03*
X441078Y1263727D03*
X436325D03*
X431661Y1265489D03*
X432485Y1319311D03*
X450591Y1007283D03*
Y1014283D03*
X456377Y1023716D03*
X456472Y1263834D03*
X451377Y1263814D03*
X446246Y1263759D03*
X460377Y1023716D03*
X464385Y1023697D03*
X461677Y1263856D03*
X466975D03*
X472592Y1263824D03*
X489121D03*
X478101D03*
X483503D03*
X505791Y717433D03*
X497357Y1122954D03*
X493532Y1122929D03*
X494901Y1265498D03*
X505728D03*
X500302D03*
X522939Y1265583D03*
X519131Y1265582D03*
X537023Y715259D03*
X528741Y812666D03*
X530453Y1265649D03*
X526725Y1265623D03*
X545741Y798666D03*
X552665Y844835D03*
X553383Y890391D03*
X570241Y803166D03*
Y824666D03*
X562231Y844813D03*
X577501Y816565D03*
X588001D03*
X577501Y823565D03*
X588001D03*
X613386Y1135426D03*
X617126D03*
X677586Y536517D03*
X681039Y1213969D03*
X748531Y1184048D03*
X780631Y1450177D03*
X787631Y1019429D03*
X791686D03*
X801082Y1451083D03*
X801998Y1471083D03*
X829852Y887022D03*
X829995Y920093D03*
X829494Y969724D03*
X835000Y756017D03*
X839000Y763017D03*
X835000Y774017D03*
X839000Y781017D03*
X835000Y792017D03*
X839000Y799017D03*
X835000Y810017D03*
X839000Y817017D03*
X836644Y858029D03*
X840381Y920586D03*
X844381D03*
X833898Y1448935D03*
X880054Y758201D03*
X874851D03*
X880054Y777215D03*
X874851Y777225D03*
X875916Y803407D03*
Y813557D03*
X879286Y908854D03*
X875286D03*
X894449Y600880D03*
X886610Y758200D03*
X885110Y777210D03*
X891916Y813557D03*
X895866Y820507D03*
X883866D03*
X888016D03*
X891916D03*
X883286Y908854D03*
X891286D03*
X887286D03*
X904393Y564718D03*
X908517D03*
X898815D03*
X909416Y813557D03*
X899916Y803407D03*
X899286Y908854D03*
X924143Y354908D03*
X918948Y354837D03*
X921790Y813557D03*
X913716Y803407D03*
X927286Y908854D03*
X923286D03*
X919286D03*
X915286D03*
X935124Y834473D03*
X941987Y854149D03*
X934944Y882078D03*
X931286Y908854D03*
X935286D03*
X952957Y919999D03*
X971648Y1221149D03*
X992000Y783517D03*
X985324Y1358823D03*
X999678Y327924D03*
X1021451Y317421D03*
X1025920Y317345D03*
X1013902Y890347D03*
X1029673Y317421D03*
X1051527Y1442528D03*
X1059448Y1435443D03*
X1074212Y1135426D03*
X1070472D03*
X1134673Y536517D03*
X1138125Y1213969D03*
X1160197Y794427D03*
X1173697D03*
X1187431Y878830D03*
Y871330D03*
X1183431D03*
X1187151Y923551D03*
Y930551D03*
X1205617Y1184048D03*
X1314604Y1270782D03*
X1326601Y331249D03*
X1333725Y331198D03*
X1319999Y1270782D03*
X1335936D03*
X1325478D03*
X1330582D03*
X1338500Y918017D03*
X1346083Y1122768D03*
X1342218Y1122805D03*
X1346362Y1270782D03*
X1351673D03*
X1341226D03*
X1364500Y816517D03*
X1360000D03*
X1355500D03*
X1364765Y1007283D03*
Y1014283D03*
X1356856Y1270782D03*
X1367828D03*
X1362308D03*
X1382667Y816388D03*
X1378000Y816517D03*
X1369000D03*
X1374500Y918017D03*
X1374551Y1023716D03*
X1370551D03*
X1378559Y1023697D03*
X1372152Y1270749D03*
X1380936Y1262872D03*
X1386122Y1262928D03*
X1391272Y1262894D03*
X1396296Y1262892D03*
X1407954Y1122979D03*
X1411829Y1122956D03*
X1411184Y1265627D03*
X1401428Y1262892D03*
X1415181Y1265627D03*
X1406916D03*
X1419451Y1265571D03*
X1440411Y1265627D03*
X1444381D03*
X1436439Y1265652D03*
X1467556Y890391D03*
X1493500Y940017D03*
X1510500Y926017D03*
X1528357Y971608D03*
X1517424Y972186D03*
X1527559Y1135426D03*
X1535000Y930517D03*
Y952017D03*
X1531299Y1135426D03*
X1591760Y536517D03*
X1595212Y1213969D03*
X1662704Y1184048D03*
X1817766Y1202417D03*
G54D11*
X13780Y1226024D03*
X79331Y1186654D03*
X390354Y1141024D03*
X536418Y1086654D03*
X854291Y1225118D03*
X993504Y1170748D03*
X1304528Y1141024D03*
X1450591Y1086654D03*
X1761614Y1215000D03*
X1827165Y1235630D03*
G54D104*
X1236871Y1715189D03*
Y1744208D03*
X1236864Y1773377D03*
X1235371Y1802909D03*
X1250055Y1710189D03*
Y1720189D03*
Y1739208D03*
Y1749208D03*
X1250048Y1768377D03*
Y1778377D03*
X1248555Y1797909D03*
Y1807909D03*
X1734069Y1710189D03*
Y1720189D03*
Y1739208D03*
Y1749208D03*
X1734062Y1768377D03*
Y1778377D03*
X1734069Y1797909D03*
Y1807909D03*
X1747253Y1715189D03*
Y1744208D03*
X1747246Y1773377D03*
X1747253Y1802909D03*
G54D114*
G01X-20602Y-468335D02*
Y-543335D01*
X479398D01*
Y-468335D01*
X-20602D01*
G01X-8602Y-533335D02*
Y-538335D01*
G01X-10059Y-533335D02*
X-7145D01*
G01X-2235Y-538335D02*
X-4769D01*
Y-533335D01*
X-2235D01*
G01X-3249Y-535752D02*
X-4769D01*
G01X331Y-533335D02*
Y-538335D01*
X2865D01*
G01X6698Y-538502D02*
X6571Y-538418D01*
Y-538252D01*
X6698Y-538168D01*
X6825Y-538252D01*
Y-538418D01*
X6698Y-538502D01*
G01Y-536252D02*
X6571Y-536168D01*
Y-536002D01*
X6698Y-535918D01*
X6825Y-536002D01*
Y-536168D01*
X6698Y-536252D01*
G01X11481Y-540002D02*
X10848Y-539168D01*
X10531Y-538335D01*
Y-535002D01*
X10848Y-534168D01*
X11481Y-533335D01*
G01X16898D02*
X16391Y-533502D01*
X16011Y-533918D01*
X15758Y-534418D01*
X15568Y-535085D01*
X15505Y-535835D01*
X15568Y-536585D01*
X15758Y-537252D01*
X16011Y-537752D01*
X16391Y-538168D01*
X16898Y-538335D01*
X17405Y-538168D01*
X17785Y-537752D01*
X18038Y-537252D01*
X18228Y-536585D01*
X18291Y-535835D01*
X18228Y-535085D01*
X18038Y-534418D01*
X17785Y-533918D01*
X17405Y-533502D01*
X16898Y-533335D01*
G01X20605Y-537335D02*
X20985Y-537918D01*
X21491Y-538252D01*
X22061Y-538335D01*
X22568Y-538252D01*
X23075Y-537835D01*
X23391Y-537335D01*
X23455Y-536835D01*
X23328Y-536252D01*
X22885Y-535835D01*
X22441Y-535668D01*
X21871D01*
G01X22441D02*
X22821Y-535418D01*
X23138Y-535002D01*
X23265Y-534502D01*
X23138Y-534002D01*
X22821Y-533585D01*
X22251Y-533335D01*
X21681Y-533418D01*
X21111Y-533752D01*
G01X27415Y-540002D02*
X28048Y-539168D01*
X28365Y-538335D01*
Y-535002D01*
X28048Y-534168D01*
X27415Y-533335D01*
G01X30805Y-537335D02*
X31185Y-537918D01*
X31691Y-538252D01*
X32261Y-538335D01*
X32768Y-538252D01*
X33275Y-537835D01*
X33591Y-537335D01*
X33655Y-536835D01*
X33528Y-536252D01*
X33085Y-535835D01*
X32641Y-535668D01*
X32071D01*
G01X32641D02*
X33021Y-535418D01*
X33338Y-535002D01*
X33465Y-534502D01*
X33338Y-534002D01*
X33021Y-533585D01*
X32451Y-533335D01*
X31881Y-533418D01*
X31311Y-533752D01*
G01X36095Y-534168D02*
X36475Y-533668D01*
X36918Y-533418D01*
X37425Y-533335D01*
X38058Y-533502D01*
X38501Y-533918D01*
X38628Y-534418D01*
X38565Y-534918D01*
X38311Y-535335D01*
X37045Y-536168D01*
X36475Y-536752D01*
X36095Y-537585D01*
X35968Y-538335D01*
X38628D01*
G01X42271D02*
X42398Y-537252D01*
X42588Y-536335D01*
X42841Y-535502D01*
X43158Y-534585D01*
X43665Y-533335D01*
X41131D01*
G01X46675Y-536668D02*
X48321D01*
G01X51395Y-534168D02*
X51775Y-533668D01*
X52218Y-533418D01*
X52725Y-533335D01*
X53358Y-533502D01*
X53801Y-533918D01*
X53928Y-534418D01*
X53865Y-534918D01*
X53611Y-535335D01*
X52345Y-536168D01*
X51775Y-536752D01*
X51395Y-537585D01*
X51268Y-538335D01*
X53928D01*
G01X56305Y-537335D02*
X56685Y-537918D01*
X57191Y-538252D01*
X57761Y-538335D01*
X58268Y-538252D01*
X58775Y-537835D01*
X59091Y-537335D01*
X59155Y-536835D01*
X59028Y-536252D01*
X58585Y-535835D01*
X58141Y-535668D01*
X57571D01*
G01X58141D02*
X58521Y-535418D01*
X58838Y-535002D01*
X58965Y-534502D01*
X58838Y-534002D01*
X58521Y-533585D01*
X57951Y-533335D01*
X57381Y-533418D01*
X56811Y-533752D01*
G01X63558Y-538335D02*
Y-533335D01*
X61215Y-536918D01*
X64381D01*
G01X66505Y-537585D02*
X66885Y-538002D01*
X67328Y-538252D01*
X67898Y-538335D01*
X68468Y-538168D01*
X68911Y-537835D01*
X69228Y-537252D01*
X69291Y-536585D01*
X69165Y-535918D01*
X68848Y-535502D01*
X68405Y-535168D01*
X67961Y-535085D01*
X67518Y-535168D01*
X66948Y-535502D01*
X67138Y-533335D01*
X68848D01*
G01X76895Y-538335D02*
Y-533335D01*
X79301D01*
G01X78415Y-535752D02*
X76895D01*
G01X81615Y-538335D02*
X83198Y-533335D01*
X84781Y-538335D01*
G01X84211Y-536585D02*
X82185D01*
G01X86968Y-538335D02*
X89628Y-533335D01*
G01X86968D02*
X89628Y-538335D01*
G01X93398Y-538502D02*
X93271Y-538418D01*
Y-538252D01*
X93398Y-538168D01*
X93525Y-538252D01*
Y-538418D01*
X93398Y-538502D01*
G01Y-536252D02*
X93271Y-536168D01*
Y-536002D01*
X93398Y-535918D01*
X93525Y-536002D01*
Y-536168D01*
X93398Y-536252D01*
G01X98181Y-540002D02*
X97548Y-539168D01*
X97231Y-538335D01*
Y-535002D01*
X97548Y-534168D01*
X98181Y-533335D01*
G01X103598D02*
X103091Y-533502D01*
X102711Y-533918D01*
X102458Y-534418D01*
X102268Y-535085D01*
X102205Y-535835D01*
X102268Y-536585D01*
X102458Y-537252D01*
X102711Y-537752D01*
X103091Y-538168D01*
X103598Y-538335D01*
X104105Y-538168D01*
X104485Y-537752D01*
X104738Y-537252D01*
X104928Y-536585D01*
X104991Y-535835D01*
X104928Y-535085D01*
X104738Y-534418D01*
X104485Y-533918D01*
X104105Y-533502D01*
X103598Y-533335D01*
G01X107305Y-537335D02*
X107685Y-537918D01*
X108191Y-538252D01*
X108761Y-538335D01*
X109268Y-538252D01*
X109775Y-537835D01*
X110091Y-537335D01*
X110155Y-536835D01*
X110028Y-536252D01*
X109585Y-535835D01*
X109141Y-535668D01*
X108571D01*
G01X109141D02*
X109521Y-535418D01*
X109838Y-535002D01*
X109965Y-534502D01*
X109838Y-534002D01*
X109521Y-533585D01*
X108951Y-533335D01*
X108381Y-533418D01*
X107811Y-533752D01*
G01X114115Y-540002D02*
X114748Y-539168D01*
X115065Y-538335D01*
Y-535002D01*
X114748Y-534168D01*
X114115Y-533335D01*
G01X117505Y-537335D02*
X117885Y-537918D01*
X118391Y-538252D01*
X118961Y-538335D01*
X119468Y-538252D01*
X119975Y-537835D01*
X120291Y-537335D01*
X120355Y-536835D01*
X120228Y-536252D01*
X119785Y-535835D01*
X119341Y-535668D01*
X118771D01*
G01X119341D02*
X119721Y-535418D01*
X120038Y-535002D01*
X120165Y-534502D01*
X120038Y-534002D01*
X119721Y-533585D01*
X119151Y-533335D01*
X118581Y-533418D01*
X118011Y-533752D01*
G01X122921Y-537752D02*
X123365Y-538168D01*
X123871Y-538335D01*
X124378Y-538168D01*
X124821Y-537668D01*
X125138Y-536918D01*
X125265Y-536168D01*
Y-535252D01*
X125138Y-534502D01*
X124821Y-533835D01*
X124441Y-533502D01*
X123998Y-533335D01*
X123491Y-533502D01*
X123111Y-533835D01*
X122858Y-534335D01*
X122731Y-535002D01*
X122858Y-535585D01*
X123175Y-536168D01*
X123555Y-536502D01*
X123998Y-536585D01*
X124505Y-536418D01*
X124885Y-536002D01*
X125265Y-535252D01*
G01X128971Y-538335D02*
X129098Y-537252D01*
X129288Y-536335D01*
X129541Y-535502D01*
X129858Y-534585D01*
X130365Y-533335D01*
X127831D01*
G01X133375Y-536668D02*
X135021D01*
G01X137905Y-537335D02*
X138285Y-537918D01*
X138791Y-538252D01*
X139361Y-538335D01*
X139868Y-538252D01*
X140375Y-537835D01*
X140691Y-537335D01*
X140755Y-536835D01*
X140628Y-536252D01*
X140185Y-535835D01*
X139741Y-535668D01*
X139171D01*
G01X139741D02*
X140121Y-535418D01*
X140438Y-535002D01*
X140565Y-534502D01*
X140438Y-534002D01*
X140121Y-533585D01*
X139551Y-533335D01*
X138981Y-533418D01*
X138411Y-533752D01*
G01X143195Y-536252D02*
X143638Y-535668D01*
X144018Y-535335D01*
X144525Y-535168D01*
X144968Y-535335D01*
X145285Y-535668D01*
X145538Y-536168D01*
X145601Y-536752D01*
X145538Y-537252D01*
X145285Y-537752D01*
X144905Y-538168D01*
X144461Y-538335D01*
X143955Y-538168D01*
X143511Y-537668D01*
X143258Y-536918D01*
X143195Y-536085D01*
X143321Y-535002D01*
X143511Y-534418D01*
X143828Y-533835D01*
X144271Y-533418D01*
X144715Y-533335D01*
X145158Y-533502D01*
X145475Y-533918D01*
G01X149498Y-538335D02*
Y-533335D01*
X148738Y-534335D01*
G01Y-538335D02*
X150258D01*
G01X155358D02*
Y-533335D01*
X153015Y-536918D01*
X156181D01*
G01X174398Y-468335D02*
Y-543335D01*
G01Y-518335D02*
X277398D01*
Y-493335D01*
G01X174398D02*
X277398D01*
G01Y-468335D02*
Y-543335D01*
G01X279398Y-468335D02*
Y-543335D01*
G01X284905Y-528335D02*
Y-523335D01*
X286171D01*
X286678Y-523585D01*
X287058Y-523918D01*
X287375Y-524418D01*
X287628Y-525002D01*
X287691Y-525835D01*
X287628Y-526668D01*
X287375Y-527252D01*
X287058Y-527752D01*
X286678Y-528085D01*
X286171Y-528335D01*
X284905D01*
G01X289815D02*
X291398Y-523335D01*
X292981Y-528335D01*
G01X292411Y-526585D02*
X290385D01*
G01X296498Y-523335D02*
Y-528335D01*
G01X295041Y-523335D02*
X297955D01*
G01X302865Y-528335D02*
X300331D01*
Y-523335D01*
X302865D01*
G01X301851Y-525752D02*
X300331D01*
G01X306698Y-528502D02*
X306571Y-528418D01*
Y-528252D01*
X306698Y-528168D01*
X306825Y-528252D01*
Y-528418D01*
X306698Y-528502D01*
G01Y-526252D02*
X306571Y-526168D01*
Y-526002D01*
X306698Y-525918D01*
X306825Y-526002D01*
Y-526168D01*
X306698Y-526252D01*
G01X279398Y-518335D02*
X479398D01*
G01X285031Y-503335D02*
Y-498335D01*
X286551D01*
X287058Y-498585D01*
X287438Y-499168D01*
X287565Y-499835D01*
X287438Y-500502D01*
X287121Y-501002D01*
X286551Y-501252D01*
X285031D01*
G01X290258Y-503502D02*
X292538Y-498335D01*
G01X295041Y-503335D02*
Y-498335D01*
X297955Y-503335D01*
Y-498335D01*
G01X301598Y-503502D02*
X301471Y-503418D01*
Y-503252D01*
X301598Y-503168D01*
X301725Y-503252D01*
Y-503418D01*
X301598Y-503502D01*
G01Y-501252D02*
X301471Y-501168D01*
Y-501002D01*
X301598Y-500918D01*
X301725Y-501002D01*
Y-501168D01*
X301598Y-501252D01*
G01X279398Y-493335D02*
X479398D01*
G01X285031Y-478335D02*
Y-473335D01*
X286551D01*
X287058Y-473585D01*
X287438Y-474168D01*
X287565Y-474835D01*
X287438Y-475502D01*
X287121Y-476002D01*
X286551Y-476252D01*
X285031D01*
G01X290131Y-478335D02*
Y-473335D01*
X291715D01*
X292221Y-473585D01*
X292538Y-473918D01*
X292665Y-474585D01*
X292538Y-475252D01*
X292158Y-475668D01*
X291715Y-475918D01*
X290131D01*
G01X291715D02*
X292665Y-478335D01*
G01X296498D02*
X295991Y-478252D01*
X295548Y-477918D01*
X295168Y-477418D01*
X294915Y-476835D01*
X294788Y-476168D01*
Y-475502D01*
X294915Y-474835D01*
X295168Y-474252D01*
X295548Y-473752D01*
X295991Y-473418D01*
X296498Y-473335D01*
X297005Y-473418D01*
X297448Y-473752D01*
X297828Y-474252D01*
X298081Y-474835D01*
X298208Y-475502D01*
Y-476168D01*
X298081Y-476835D01*
X297828Y-477418D01*
X297448Y-477918D01*
X297005Y-478252D01*
X296498Y-478335D01*
G01X300331Y-477335D02*
X300648Y-477835D01*
X301028Y-478168D01*
X301471Y-478335D01*
X301978Y-478168D01*
X302358Y-477835D01*
X302738Y-477335D01*
X302865Y-476668D01*
Y-473335D01*
G01X307965Y-478335D02*
X305431D01*
Y-473335D01*
X307965D01*
G01X306951Y-475752D02*
X305431D01*
G01X313191Y-473752D02*
X312811Y-473502D01*
X312368Y-473335D01*
X311861D01*
X311291Y-473585D01*
X310848Y-474002D01*
X310531Y-474502D01*
X310278Y-475335D01*
X310215Y-476085D01*
X310341Y-476835D01*
X310531Y-477335D01*
X310911Y-477835D01*
X311355Y-478168D01*
X311798Y-478335D01*
X312241D01*
X312685Y-478168D01*
X313065Y-477918D01*
X313381Y-477585D01*
G01X316898Y-473335D02*
Y-478335D01*
G01X315441Y-473335D02*
X318355D01*
G01X321998Y-478502D02*
X321871Y-478418D01*
Y-478252D01*
X321998Y-478168D01*
X322125Y-478252D01*
Y-478418D01*
X321998Y-478502D01*
G01Y-476252D02*
X321871Y-476168D01*
Y-476002D01*
X321998Y-475918D01*
X322125Y-476002D01*
Y-476168D01*
X321998Y-476252D01*
G01X394258Y-543563D02*
Y-518563D01*
G01X397031Y-520835D02*
Y-525835D01*
X399565D01*
G01X402638Y-520835D02*
X404158D01*
G01X403398D02*
Y-525835D01*
G01X402638D02*
X404158D01*
G01X409005Y-523168D02*
X409258Y-522918D01*
X409448Y-522502D01*
X409575Y-521918D01*
X409448Y-521418D01*
X409195Y-521085D01*
X408751Y-520835D01*
X407041D01*
Y-525835D01*
X409131D01*
X409575Y-525502D01*
X409828Y-525002D01*
X409955Y-524418D01*
X409828Y-523835D01*
X409448Y-523335D01*
X409005Y-523168D01*
X407041D01*
G01X413598Y-526002D02*
X413471Y-525918D01*
Y-525752D01*
X413598Y-525668D01*
X413725Y-525752D01*
Y-525918D01*
X413598Y-526002D01*
G01Y-523752D02*
X413471Y-523668D01*
Y-523502D01*
X413598Y-523418D01*
X413725Y-523502D01*
Y-523668D01*
X413598Y-523752D01*
G01X437258Y-518563D02*
Y-543563D01*
G01X437398Y-518335D02*
Y-543335D01*
G01X441298Y-520835D02*
Y-525835D01*
G01X439841Y-520835D02*
X442755D01*
G01X446398Y-525835D02*
X446018Y-525752D01*
X445638Y-525418D01*
X445385Y-524835D01*
X445258Y-524168D01*
X445385Y-523502D01*
X445638Y-522918D01*
X446018Y-522585D01*
X446398Y-522502D01*
X446778Y-522585D01*
X447158Y-522918D01*
X447411Y-523502D01*
X447475Y-524168D01*
X447411Y-524835D01*
X447158Y-525418D01*
X446778Y-525752D01*
X446398Y-525835D01*
G01X451498D02*
X451118Y-525752D01*
X450738Y-525418D01*
X450485Y-524835D01*
X450358Y-524168D01*
X450485Y-523502D01*
X450738Y-522918D01*
X451118Y-522585D01*
X451498Y-522502D01*
X451878Y-522585D01*
X452258Y-522918D01*
X452511Y-523502D01*
X452575Y-524168D01*
X452511Y-524835D01*
X452258Y-525418D01*
X451878Y-525752D01*
X451498Y-525835D01*
G01X456598D02*
Y-520835D01*
G01X461698Y-526002D02*
X461571Y-525918D01*
Y-525752D01*
X461698Y-525668D01*
X461825Y-525752D01*
Y-525918D01*
X461698Y-526002D01*
G01Y-523752D02*
X461571Y-523668D01*
Y-523502D01*
X461698Y-523418D01*
X461825Y-523502D01*
Y-523668D01*
X461698Y-523752D01*
G01X437398Y-493335D02*
Y-518335D01*
G01X440031Y-500835D02*
Y-495835D01*
X441615D01*
X442121Y-496085D01*
X442438Y-496418D01*
X442565Y-497085D01*
X442438Y-497752D01*
X442058Y-498168D01*
X441615Y-498418D01*
X440031D01*
G01X441615D02*
X442565Y-500835D01*
G01X447665D02*
X445131D01*
Y-495835D01*
X447665D01*
G01X446651Y-498252D02*
X445131D01*
G01X449915Y-495835D02*
X451498Y-500835D01*
X453081Y-495835D01*
G01X456598Y-501002D02*
X456471Y-500918D01*
Y-500752D01*
X456598Y-500668D01*
X456725Y-500752D01*
Y-500918D01*
X456598Y-501002D01*
G01Y-498752D02*
X456471Y-498668D01*
Y-498502D01*
X456598Y-498418D01*
X456725Y-498502D01*
Y-498668D01*
X456598Y-498752D01*
G01X445411Y-546502D02*
X445518Y-546377D01*
X445598Y-546168D01*
X445651Y-545877D01*
X445598Y-545627D01*
X445491Y-545460D01*
X445305Y-545335D01*
X444585D01*
Y-547835D01*
X445465D01*
X445651Y-547668D01*
X445758Y-547418D01*
X445811Y-547127D01*
X445758Y-546835D01*
X445598Y-546585D01*
X445411Y-546502D01*
X444585D01*
G01X447878Y-547835D02*
Y-546168D01*
G01Y-546460D02*
X447771Y-546293D01*
X447611Y-546210D01*
X447425Y-546168D01*
X447238Y-546252D01*
X447078Y-546418D01*
X446971Y-546668D01*
X446918Y-547002D01*
X446971Y-547335D01*
X447078Y-547585D01*
X447238Y-547752D01*
X447425Y-547835D01*
X447611Y-547793D01*
X447771Y-547668D01*
X447878Y-547502D01*
G01X449198Y-547543D02*
X449331Y-547710D01*
X449518Y-547835D01*
X449678D01*
X449838Y-547752D01*
X449945Y-547627D01*
X449998Y-547460D01*
X449971Y-547210D01*
X449865Y-547085D01*
X449385Y-546835D01*
X449278Y-546543D01*
X449331Y-546335D01*
X449438Y-546210D01*
X449598Y-546168D01*
X449758Y-546210D01*
X449918Y-546335D01*
G01X451398Y-546710D02*
X452251D01*
X452171Y-546418D01*
X452038Y-546252D01*
X451851Y-546168D01*
X451665Y-546210D01*
X451505Y-546335D01*
X451398Y-546627D01*
X451345Y-546877D01*
Y-547127D01*
X451398Y-547377D01*
X451531Y-547627D01*
X451691Y-547793D01*
X451878Y-547835D01*
X452065Y-547752D01*
X452251Y-547502D01*
G01X453518Y-547835D02*
Y-545335D01*
G01Y-546585D02*
X453651Y-546335D01*
X453811Y-546210D01*
X453971Y-546168D01*
X454211Y-546252D01*
X454371Y-546418D01*
X454478Y-546710D01*
Y-547043D01*
X454425Y-547377D01*
X454318Y-547627D01*
X454131Y-547793D01*
X453971Y-547835D01*
X453811Y-547793D01*
X453651Y-547668D01*
X453518Y-547460D01*
G01X456198Y-547835D02*
X456038Y-547793D01*
X455878Y-547627D01*
X455771Y-547335D01*
X455718Y-547002D01*
X455771Y-546668D01*
X455878Y-546377D01*
X456038Y-546210D01*
X456198Y-546168D01*
X456358Y-546210D01*
X456518Y-546377D01*
X456625Y-546668D01*
X456651Y-547002D01*
X456625Y-547335D01*
X456518Y-547627D01*
X456358Y-547793D01*
X456198Y-547835D01*
G01X458878D02*
Y-546168D01*
G01Y-546460D02*
X458771Y-546293D01*
X458611Y-546210D01*
X458425Y-546168D01*
X458238Y-546252D01*
X458078Y-546418D01*
X457971Y-546668D01*
X457918Y-547002D01*
X457971Y-547335D01*
X458078Y-547585D01*
X458238Y-547752D01*
X458425Y-547835D01*
X458611Y-547793D01*
X458771Y-547668D01*
X458878Y-547502D01*
G01X460225Y-547835D02*
Y-546168D01*
G01Y-546502D02*
X460358Y-546335D01*
X460491Y-546210D01*
X460678Y-546168D01*
X460811Y-546210D01*
X460971Y-546335D01*
G01X463278Y-545335D02*
Y-547835D01*
G01Y-547460D02*
X463171Y-547668D01*
X463011Y-547793D01*
X462825Y-547835D01*
X462611Y-547752D01*
X462451Y-547543D01*
X462345Y-547293D01*
X462318Y-547002D01*
X462345Y-546710D01*
X462451Y-546460D01*
X462611Y-546252D01*
X462825Y-546168D01*
X463011Y-546210D01*
X463145Y-546293D01*
X463278Y-546460D01*
G01X466665Y-547835D02*
Y-545335D01*
X467331D01*
X467545Y-545460D01*
X467678Y-545627D01*
X467731Y-545960D01*
X467678Y-546293D01*
X467518Y-546502D01*
X467331Y-546627D01*
X466665D01*
G01X467331D02*
X467731Y-547835D01*
G01X468998Y-546710D02*
X469851D01*
X469771Y-546418D01*
X469638Y-546252D01*
X469451Y-546168D01*
X469265Y-546210D01*
X469105Y-546335D01*
X468998Y-546627D01*
X468945Y-546877D01*
Y-547127D01*
X468998Y-547377D01*
X469131Y-547627D01*
X469291Y-547793D01*
X469478Y-547835D01*
X469665Y-547752D01*
X469851Y-547502D01*
G01X471118Y-546168D02*
X471598Y-547835D01*
X472078Y-546168D01*
G01X473798Y-547918D02*
X473745Y-547877D01*
Y-547793D01*
X473798Y-547752D01*
X473851Y-547793D01*
Y-547877D01*
X473798Y-547918D01*
G01X475545Y-547543D02*
X475731Y-547752D01*
X475945Y-547835D01*
X476158Y-547752D01*
X476345Y-547502D01*
X476478Y-547127D01*
X476531Y-546752D01*
Y-546293D01*
X476478Y-545918D01*
X476345Y-545585D01*
X476185Y-545418D01*
X475998Y-545335D01*
X475785Y-545418D01*
X475625Y-545585D01*
X475518Y-545835D01*
X475465Y-546168D01*
X475518Y-546460D01*
X475651Y-546752D01*
X475811Y-546918D01*
X475998Y-546960D01*
X476211Y-546877D01*
X476371Y-546668D01*
X476531Y-546293D01*
G01X478411Y-546502D02*
X478518Y-546377D01*
X478598Y-546168D01*
X478651Y-545877D01*
X478598Y-545627D01*
X478491Y-545460D01*
X478305Y-545335D01*
X477585D01*
Y-547835D01*
X478465D01*
X478651Y-547668D01*
X478758Y-547418D01*
X478811Y-547127D01*
X478758Y-546835D01*
X478598Y-546585D01*
X478411Y-546502D01*
X477585D01*
G01X-1490433Y-1677216D02*
Y3837819D01*
X4496476D01*
Y-1677216D01*
X-1490433D01*
G01X-7782Y-515685D02*
X-6215D01*
Y-517575D01*
X-6685Y-518205D01*
X-7234Y-518625D01*
X-8017Y-518835D01*
X-8800Y-518625D01*
X-9349Y-518205D01*
X-9819Y-517575D01*
X-10132Y-516840D01*
X-10289Y-516000D01*
Y-515265D01*
X-10132Y-514635D01*
X-9819Y-513900D01*
X-9349Y-513270D01*
X-8879Y-512850D01*
X-8252Y-512535D01*
X-7704D01*
X-7077Y-512745D01*
X-6607Y-513165D01*
G01X-3675Y-512535D02*
Y-517050D01*
X-3362Y-517995D01*
X-2735Y-518625D01*
X-1952Y-518835D01*
X-1169Y-518625D01*
X-542Y-517995D01*
X-229Y-517050D01*
Y-512535D01*
G01X3408D02*
X5288D01*
G01X4348D02*
Y-518835D01*
G01X3408D02*
X5288D01*
G01X9003Y-517995D02*
X9630Y-518520D01*
X10335Y-518835D01*
X10961D01*
X11588Y-518520D01*
X12058Y-517995D01*
X12293Y-517260D01*
X12136Y-516525D01*
X11745Y-515895D01*
X11040Y-515475D01*
X10100Y-515265D01*
X9551Y-514845D01*
X9316Y-514110D01*
X9473Y-513375D01*
X9865Y-512850D01*
X10413Y-512535D01*
X10961D01*
X11510Y-512745D01*
X11980Y-513270D01*
G01X15303Y-518835D02*
Y-512535D01*
G01X18593D02*
Y-518835D01*
G01Y-515685D02*
X15303D01*
G01X21290Y-518835D02*
X23248Y-512535D01*
X25206Y-518835D01*
G01X24501Y-516630D02*
X21995D01*
G01X27746Y-518835D02*
Y-512535D01*
X31350Y-518835D01*
Y-512535D01*
G01X40425Y-518835D02*
Y-512535D01*
X41991D01*
X42618Y-512850D01*
X43088Y-513270D01*
X43480Y-513900D01*
X43793Y-514635D01*
X43871Y-515685D01*
X43793Y-516735D01*
X43480Y-517470D01*
X43088Y-518100D01*
X42618Y-518520D01*
X41991Y-518835D01*
X40425D01*
G01X47508Y-512535D02*
X49388D01*
G01X48448D02*
Y-518835D01*
G01X47508D02*
X49388D01*
G01X53103Y-517995D02*
X53730Y-518520D01*
X54435Y-518835D01*
X55061D01*
X55688Y-518520D01*
X56158Y-517995D01*
X56393Y-517260D01*
X56236Y-516525D01*
X55845Y-515895D01*
X55140Y-515475D01*
X54200Y-515265D01*
X53651Y-514845D01*
X53416Y-514110D01*
X53573Y-513375D01*
X53965Y-512850D01*
X54513Y-512535D01*
X55061D01*
X55610Y-512745D01*
X56080Y-513270D01*
G01X61048Y-512535D02*
Y-518835D01*
G01X59246Y-512535D02*
X62850D01*
G01X67348Y-519045D02*
X67191Y-518940D01*
Y-518730D01*
X67348Y-518625D01*
X67505Y-518730D01*
Y-518940D01*
X67348Y-519045D01*
G01X73491Y-519990D02*
X73805Y-518625D01*
G01X79948Y-512535D02*
Y-518835D01*
G01X78146Y-512535D02*
X81750D01*
G01X84290Y-518835D02*
X86248Y-512535D01*
X88206Y-518835D01*
G01X87501Y-516630D02*
X84995D01*
G01X92548Y-518835D02*
X91921Y-518730D01*
X91373Y-518310D01*
X90903Y-517680D01*
X90590Y-516945D01*
X90433Y-516105D01*
Y-515265D01*
X90590Y-514425D01*
X90903Y-513690D01*
X91373Y-513060D01*
X91921Y-512640D01*
X92548Y-512535D01*
X93175Y-512640D01*
X93723Y-513060D01*
X94193Y-513690D01*
X94506Y-514425D01*
X94663Y-515265D01*
Y-516105D01*
X94506Y-516945D01*
X94193Y-517680D01*
X93723Y-518310D01*
X93175Y-518730D01*
X92548Y-518835D01*
G01X98848D02*
Y-516000D01*
X97281Y-512535D01*
G01X100415D02*
X98848Y-516000D01*
G01X103425Y-512535D02*
Y-517050D01*
X103738Y-517995D01*
X104365Y-518625D01*
X105148Y-518835D01*
X105931Y-518625D01*
X106558Y-517995D01*
X106871Y-517050D01*
Y-512535D01*
G01X109490Y-518835D02*
X111448Y-512535D01*
X113406Y-518835D01*
G01X112701Y-516630D02*
X110195D01*
G01X115946Y-518835D02*
Y-512535D01*
X119550Y-518835D01*
Y-512535D01*
G01X-6529Y-523060D02*
X-6999Y-522745D01*
X-7547Y-522535D01*
X-8174D01*
X-8879Y-522850D01*
X-9427Y-523375D01*
X-9819Y-524005D01*
X-10132Y-525055D01*
X-10210Y-526000D01*
X-10054Y-526945D01*
X-9819Y-527575D01*
X-9349Y-528205D01*
X-8800Y-528625D01*
X-8252Y-528835D01*
X-7704D01*
X-7155Y-528625D01*
X-6685Y-528310D01*
X-6294Y-527890D01*
G01X-2892Y-522535D02*
X-1012D01*
G01X-1952D02*
Y-528835D01*
G01X-2892D02*
X-1012D01*
G01X4348Y-522535D02*
Y-528835D01*
G01X2546Y-522535D02*
X6150D01*
G01X10648Y-528835D02*
Y-526000D01*
X9081Y-522535D01*
G01X12215D02*
X10648Y-526000D01*
G01X21525Y-527575D02*
X21995Y-528310D01*
X22621Y-528730D01*
X23326Y-528835D01*
X23953Y-528730D01*
X24580Y-528205D01*
X24971Y-527575D01*
X25050Y-526945D01*
X24893Y-526210D01*
X24345Y-525685D01*
X23796Y-525475D01*
X23091D01*
G01X23796D02*
X24266Y-525160D01*
X24658Y-524635D01*
X24815Y-524005D01*
X24658Y-523375D01*
X24266Y-522850D01*
X23561Y-522535D01*
X22856Y-522640D01*
X22151Y-523060D01*
G01X27825Y-527575D02*
X28295Y-528310D01*
X28921Y-528730D01*
X29626Y-528835D01*
X30253Y-528730D01*
X30880Y-528205D01*
X31271Y-527575D01*
X31350Y-526945D01*
X31193Y-526210D01*
X30645Y-525685D01*
X30096Y-525475D01*
X29391D01*
G01X30096D02*
X30566Y-525160D01*
X30958Y-524635D01*
X31115Y-524005D01*
X30958Y-523375D01*
X30566Y-522850D01*
X29861Y-522535D01*
X29156Y-522640D01*
X28451Y-523060D01*
G01X34125Y-527575D02*
X34595Y-528310D01*
X35221Y-528730D01*
X35926Y-528835D01*
X36553Y-528730D01*
X37180Y-528205D01*
X37571Y-527575D01*
X37650Y-526945D01*
X37493Y-526210D01*
X36945Y-525685D01*
X36396Y-525475D01*
X35691D01*
G01X36396D02*
X36866Y-525160D01*
X37258Y-524635D01*
X37415Y-524005D01*
X37258Y-523375D01*
X36866Y-522850D01*
X36161Y-522535D01*
X35456Y-522640D01*
X34751Y-523060D01*
G01X41991Y-528835D02*
X42148Y-527470D01*
X42383Y-526315D01*
X42696Y-525265D01*
X43088Y-524110D01*
X43715Y-522535D01*
X40581D01*
G01X48291Y-528835D02*
X48448Y-527470D01*
X48683Y-526315D01*
X48996Y-525265D01*
X49388Y-524110D01*
X50015Y-522535D01*
X46881D01*
G01X54591Y-529990D02*
X54905Y-528625D01*
G01X61048Y-522535D02*
Y-528835D01*
G01X59246Y-522535D02*
X62850D01*
G01X65390Y-528835D02*
X67348Y-522535D01*
X69306Y-528835D01*
G01X68601Y-526630D02*
X66095D01*
G01X72708Y-522535D02*
X74588D01*
G01X73648D02*
Y-528835D01*
G01X72708D02*
X74588D01*
G01X77598Y-522535D02*
X78695Y-528835D01*
X79948Y-522535D01*
X81201Y-528835D01*
X82298Y-522535D01*
G01X84290Y-528835D02*
X86248Y-522535D01*
X88206Y-528835D01*
G01X87501Y-526630D02*
X84995D01*
G01X90746Y-528835D02*
Y-522535D01*
X94350Y-528835D01*
Y-522535D01*
G01X104756Y-530935D02*
X103973Y-529885D01*
X103581Y-528835D01*
Y-524635D01*
X103973Y-523585D01*
X104756Y-522535D01*
G01X116181Y-528835D02*
Y-522535D01*
X118140D01*
X118766Y-522850D01*
X119158Y-523270D01*
X119315Y-524110D01*
X119158Y-524950D01*
X118688Y-525475D01*
X118140Y-525790D01*
X116181D01*
G01X118140D02*
X119315Y-528835D01*
G01X124048Y-529045D02*
X123891Y-528940D01*
Y-528730D01*
X124048Y-528625D01*
X124205Y-528730D01*
Y-528940D01*
X124048Y-529045D01*
G01X130348Y-528835D02*
X129721Y-528730D01*
X129173Y-528310D01*
X128703Y-527680D01*
X128390Y-526945D01*
X128233Y-526105D01*
Y-525265D01*
X128390Y-524425D01*
X128703Y-523690D01*
X129173Y-523060D01*
X129721Y-522640D01*
X130348Y-522535D01*
X130975Y-522640D01*
X131523Y-523060D01*
X131993Y-523690D01*
X132306Y-524425D01*
X132463Y-525265D01*
Y-526105D01*
X132306Y-526945D01*
X131993Y-527680D01*
X131523Y-528310D01*
X130975Y-528730D01*
X130348Y-528835D01*
G01X136648Y-529045D02*
X136491Y-528940D01*
Y-528730D01*
X136648Y-528625D01*
X136805Y-528730D01*
Y-528940D01*
X136648Y-529045D01*
G01X144671Y-523060D02*
X144201Y-522745D01*
X143653Y-522535D01*
X143026D01*
X142321Y-522850D01*
X141773Y-523375D01*
X141381Y-524005D01*
X141068Y-525055D01*
X140990Y-526000D01*
X141146Y-526945D01*
X141381Y-527575D01*
X141851Y-528205D01*
X142400Y-528625D01*
X142948Y-528835D01*
X143496D01*
X144045Y-528625D01*
X144515Y-528310D01*
X144906Y-527890D01*
G01X149248Y-529045D02*
X149091Y-528940D01*
Y-528730D01*
X149248Y-528625D01*
X149405Y-528730D01*
Y-528940D01*
X149248Y-529045D01*
G01X155940Y-530935D02*
X156723Y-529885D01*
X157115Y-528835D01*
Y-524635D01*
X156723Y-523585D01*
X155940Y-522535D01*
G01X-10054Y-508835D02*
Y-502535D01*
X-6450Y-508835D01*
Y-502535D01*
G01X-1952Y-508835D02*
X-2579Y-508730D01*
X-3127Y-508310D01*
X-3597Y-507680D01*
X-3910Y-506945D01*
X-4067Y-506105D01*
Y-505265D01*
X-3910Y-504425D01*
X-3597Y-503690D01*
X-3127Y-503060D01*
X-2579Y-502640D01*
X-1952Y-502535D01*
X-1325Y-502640D01*
X-777Y-503060D01*
X-307Y-503690D01*
X6Y-504425D01*
X163Y-505265D01*
Y-506105D01*
X6Y-506945D01*
X-307Y-507680D01*
X-777Y-508310D01*
X-1325Y-508730D01*
X-1952Y-508835D01*
G01X4348Y-509045D02*
X4191Y-508940D01*
Y-508730D01*
X4348Y-508625D01*
X4505Y-508730D01*
Y-508940D01*
X4348Y-509045D01*
G01X9160Y-503585D02*
X9630Y-502955D01*
X10178Y-502640D01*
X10805Y-502535D01*
X11588Y-502745D01*
X12136Y-503270D01*
X12293Y-503900D01*
X12215Y-504530D01*
X11901Y-505055D01*
X10335Y-506105D01*
X9630Y-506840D01*
X9160Y-507890D01*
X9003Y-508835D01*
X12293D01*
G01X16948D02*
Y-502535D01*
X16008Y-503795D01*
G01Y-508835D02*
X17888D01*
G01X23248D02*
Y-502535D01*
X22308Y-503795D01*
G01Y-508835D02*
X24188D01*
G01X29391Y-509990D02*
X29705Y-508625D01*
G01X33498Y-502535D02*
X34595Y-508835D01*
X35848Y-502535D01*
X37101Y-508835D01*
X38198Y-502535D01*
G01X43715Y-508835D02*
X40581D01*
Y-502535D01*
X43715D01*
G01X42461Y-505580D02*
X40581D01*
G01X46646Y-508835D02*
Y-502535D01*
X50250Y-508835D01*
Y-502535D01*
G01X53103Y-508835D02*
Y-502535D01*
G01X56393D02*
Y-508835D01*
G01Y-505685D02*
X53103D01*
G01X59325Y-502535D02*
Y-507050D01*
X59638Y-507995D01*
X60265Y-508625D01*
X61048Y-508835D01*
X61831Y-508625D01*
X62458Y-507995D01*
X62771Y-507050D01*
Y-502535D01*
G01X65390Y-508835D02*
X67348Y-502535D01*
X69306Y-508835D01*
G01X68601Y-506630D02*
X66095D01*
G01X78460Y-503585D02*
X78930Y-502955D01*
X79478Y-502640D01*
X80105Y-502535D01*
X80888Y-502745D01*
X81436Y-503270D01*
X81593Y-503900D01*
X81515Y-504530D01*
X81201Y-505055D01*
X79635Y-506105D01*
X78930Y-506840D01*
X78460Y-507890D01*
X78303Y-508835D01*
X81593D01*
G01X84446D02*
Y-502535D01*
X88050Y-508835D01*
Y-502535D01*
G01X90825Y-508835D02*
Y-502535D01*
X92391D01*
X93018Y-502850D01*
X93488Y-503270D01*
X93880Y-503900D01*
X94193Y-504635D01*
X94271Y-505685D01*
X94193Y-506735D01*
X93880Y-507470D01*
X93488Y-508100D01*
X93018Y-508520D01*
X92391Y-508835D01*
X90825D01*
G01X103581D02*
Y-502535D01*
X105540D01*
X106166Y-502850D01*
X106558Y-503270D01*
X106715Y-504110D01*
X106558Y-504950D01*
X106088Y-505475D01*
X105540Y-505790D01*
X103581D01*
G01X105540D02*
X106715Y-508835D01*
G01X109725D02*
Y-502535D01*
X111291D01*
X111918Y-502850D01*
X112388Y-503270D01*
X112780Y-503900D01*
X113093Y-504635D01*
X113171Y-505685D01*
X113093Y-506735D01*
X112780Y-507470D01*
X112388Y-508100D01*
X111918Y-508520D01*
X111291Y-508835D01*
X109725D01*
G01X117748Y-509045D02*
X117591Y-508940D01*
Y-508730D01*
X117748Y-508625D01*
X117905Y-508730D01*
Y-508940D01*
X117748Y-509045D01*
G01X14048Y-498135D02*
X11528Y-497718D01*
X9323Y-496052D01*
X7433Y-493552D01*
X6173Y-490635D01*
X5543Y-487302D01*
Y-483968D01*
X6173Y-480635D01*
X7433Y-477718D01*
X9323Y-475219D01*
X11528Y-473552D01*
X14048Y-473135D01*
X16568Y-473552D01*
X18773Y-475219D01*
X20663Y-477718D01*
X21923Y-480635D01*
X22553Y-483968D01*
Y-487302D01*
X21923Y-490635D01*
X20663Y-493552D01*
X18773Y-496052D01*
X16568Y-497718D01*
X14048Y-498135D01*
G01X16568Y-491468D02*
X20348Y-498135D01*
G01X33893Y-481469D02*
Y-493135D01*
X35153Y-496052D01*
X37043Y-497718D01*
X39248Y-498135D01*
X41453Y-497718D01*
X43343Y-496052D01*
X44603Y-493135D01*
G01Y-498135D02*
Y-481469D01*
G01X70118Y-498135D02*
Y-481469D01*
G01Y-484385D02*
X68858Y-482719D01*
X66968Y-481885D01*
X64763Y-481469D01*
X62558Y-482302D01*
X60668Y-483968D01*
X59408Y-486469D01*
X58778Y-489802D01*
X59408Y-493135D01*
X60668Y-495636D01*
X62558Y-497302D01*
X64763Y-498135D01*
X66968Y-497718D01*
X68858Y-496469D01*
X70118Y-494802D01*
G01X84293Y-498135D02*
Y-481469D01*
G01Y-485635D02*
X85553Y-483552D01*
X87443Y-481885D01*
X89963Y-481469D01*
X92168Y-481885D01*
X94058Y-483552D01*
X95003Y-486469D01*
Y-498135D01*
G01X114848Y-473135D02*
Y-498135D01*
G01X110438Y-481469D02*
X119258D01*
G01X145718Y-498135D02*
Y-481469D01*
G01Y-484385D02*
X144458Y-482719D01*
X142568Y-481885D01*
X140363Y-481469D01*
X138158Y-482302D01*
X136268Y-483968D01*
X135008Y-486469D01*
X134378Y-489802D01*
X135008Y-493135D01*
X136268Y-495636D01*
X138158Y-497302D01*
X140363Y-498135D01*
X142568Y-497718D01*
X144458Y-496469D01*
X145718Y-494802D01*
G01X185398Y-477835D02*
Y-485835D01*
X189398D01*
G01X197198D02*
Y-480502D01*
G01Y-481435D02*
X196798Y-480902D01*
X196198Y-480635D01*
X195498Y-480502D01*
X194798Y-480768D01*
X194198Y-481302D01*
X193798Y-482102D01*
X193598Y-483168D01*
X193798Y-484235D01*
X194198Y-485035D01*
X194798Y-485568D01*
X195498Y-485835D01*
X196198Y-485702D01*
X196798Y-485302D01*
X197198Y-484769D01*
G01X201298Y-488235D02*
X201898Y-488502D01*
X202698Y-488235D01*
X203198Y-487702D01*
X203598Y-487035D01*
X204198Y-484902D01*
X205498Y-480502D01*
G01X202298D02*
X204198Y-484902D01*
G01X209898Y-482235D02*
X213098D01*
X212798Y-481302D01*
X212298Y-480768D01*
X211598Y-480502D01*
X210898Y-480635D01*
X210298Y-481035D01*
X209898Y-481968D01*
X209698Y-482769D01*
Y-483568D01*
X209898Y-484368D01*
X210398Y-485168D01*
X210998Y-485702D01*
X211698Y-485835D01*
X212398Y-485568D01*
X213098Y-484769D01*
G01X217998Y-485835D02*
Y-480502D01*
G01Y-481568D02*
X218498Y-481035D01*
X218998Y-480635D01*
X219698Y-480502D01*
X220198Y-480635D01*
X220798Y-481035D01*
G01X211398Y-535835D02*
Y-532235D01*
X209398Y-527835D01*
G01X213398D02*
X211398Y-532235D01*
G01X217698Y-530502D02*
Y-534235D01*
X218098Y-535168D01*
X218698Y-535702D01*
X219398Y-535835D01*
X220098Y-535702D01*
X220698Y-535168D01*
X221098Y-534235D01*
G01Y-535835D02*
Y-530502D01*
G01X225698Y-535835D02*
Y-530502D01*
G01Y-531835D02*
X226098Y-531168D01*
X226698Y-530635D01*
X227498Y-530502D01*
X228198Y-530635D01*
X228798Y-531168D01*
X229098Y-532102D01*
Y-535835D01*
G01X237198D02*
Y-530502D01*
G01Y-531435D02*
X236798Y-530902D01*
X236198Y-530635D01*
X235498Y-530502D01*
X234798Y-530768D01*
X234198Y-531302D01*
X233798Y-532102D01*
X233598Y-533168D01*
X233798Y-534235D01*
X234198Y-535035D01*
X234798Y-535568D01*
X235498Y-535835D01*
X236198Y-535702D01*
X236798Y-535302D01*
X237198Y-534769D01*
G01X209698Y-506568D02*
X210098Y-506168D01*
X210398Y-505502D01*
X210598Y-504568D01*
X210398Y-503768D01*
X209998Y-503235D01*
X209298Y-502835D01*
X206598D01*
Y-510835D01*
X209898D01*
X210598Y-510302D01*
X210998Y-509502D01*
X211198Y-508568D01*
X210998Y-507635D01*
X210398Y-506835D01*
X209698Y-506568D01*
X206598D01*
G01X216898Y-510835D02*
X216098Y-510702D01*
X215398Y-510168D01*
X214798Y-509368D01*
X214398Y-508435D01*
X214198Y-507368D01*
Y-506302D01*
X214398Y-505235D01*
X214798Y-504302D01*
X215398Y-503502D01*
X216098Y-502968D01*
X216898Y-502835D01*
X217698Y-502968D01*
X218398Y-503502D01*
X218998Y-504302D01*
X219398Y-505235D01*
X219598Y-506302D01*
Y-507368D01*
X219398Y-508435D01*
X218998Y-509368D01*
X218398Y-510168D01*
X217698Y-510702D01*
X216898Y-510835D01*
G01X224898Y-502835D02*
Y-510835D01*
G01X222598Y-502835D02*
X227198D01*
G01X232898D02*
Y-510835D01*
G01X230598Y-502835D02*
X235198D01*
G01X240898Y-510835D02*
X240098Y-510702D01*
X239398Y-510168D01*
X238798Y-509368D01*
X238398Y-508435D01*
X238198Y-507368D01*
Y-506302D01*
X238398Y-505235D01*
X238798Y-504302D01*
X239398Y-503502D01*
X240098Y-502968D01*
X240898Y-502835D01*
X241698Y-502968D01*
X242398Y-503502D01*
X242998Y-504302D01*
X243398Y-505235D01*
X243598Y-506302D01*
Y-507368D01*
X243398Y-508435D01*
X242998Y-509368D01*
X242398Y-510168D01*
X241698Y-510702D01*
X240898Y-510835D01*
G01X246298D02*
Y-502835D01*
X248898Y-509502D01*
X251498Y-502835D01*
Y-510835D01*
G01X233898Y-485835D02*
Y-477835D01*
X232698Y-479435D01*
G01Y-485835D02*
X235098D01*
G01X241898D02*
X242598Y-485702D01*
X243398Y-485302D01*
X243898Y-484635D01*
X244098Y-483702D01*
X243898Y-482769D01*
X243298Y-481968D01*
X242398Y-481568D01*
X241398D01*
X240798Y-481302D01*
X240298Y-480635D01*
X240098Y-479702D01*
X240398Y-478768D01*
X241098Y-478102D01*
X241898Y-477835D01*
X242698Y-478102D01*
X243398Y-478768D01*
X243698Y-479702D01*
X243498Y-480635D01*
X242998Y-481302D01*
X242398Y-481568D01*
X241398D01*
X240498Y-481968D01*
X239898Y-482769D01*
X239698Y-483702D01*
X239898Y-484635D01*
X240398Y-485302D01*
X241198Y-485702D01*
X241898Y-485835D01*
G01X311998Y-529168D02*
X312598Y-528368D01*
X313298Y-527968D01*
X314098Y-527835D01*
X315098Y-528102D01*
X315798Y-528768D01*
X315998Y-529568D01*
X315898Y-530369D01*
X315498Y-531035D01*
X313498Y-532368D01*
X312598Y-533302D01*
X311998Y-534635D01*
X311798Y-535835D01*
X315998D01*
G01X321898Y-527835D02*
X321098Y-528102D01*
X320498Y-528768D01*
X320098Y-529568D01*
X319798Y-530635D01*
X319698Y-531835D01*
X319798Y-533035D01*
X320098Y-534102D01*
X320498Y-534902D01*
X321098Y-535568D01*
X321898Y-535835D01*
X322698Y-535568D01*
X323298Y-534902D01*
X323698Y-534102D01*
X323998Y-533035D01*
X324098Y-531835D01*
X323998Y-530635D01*
X323698Y-529568D01*
X323298Y-528768D01*
X322698Y-528102D01*
X321898Y-527835D01*
G01X327998Y-529168D02*
X328598Y-528368D01*
X329298Y-527968D01*
X330098Y-527835D01*
X331098Y-528102D01*
X331798Y-528768D01*
X331998Y-529568D01*
X331898Y-530369D01*
X331498Y-531035D01*
X329498Y-532368D01*
X328598Y-533302D01*
X327998Y-534635D01*
X327798Y-535835D01*
X331998D01*
G01X335698Y-534235D02*
X336298Y-535168D01*
X337098Y-535702D01*
X337998Y-535835D01*
X338798Y-535702D01*
X339598Y-535035D01*
X340098Y-534235D01*
X340198Y-533435D01*
X339998Y-532502D01*
X339298Y-531835D01*
X338598Y-531568D01*
X337698D01*
G01X338598D02*
X339198Y-531168D01*
X339698Y-530502D01*
X339898Y-529702D01*
X339698Y-528902D01*
X339198Y-528235D01*
X338298Y-527835D01*
X337398Y-527968D01*
X336498Y-528502D01*
G01X344098Y-536102D02*
X347698Y-527835D01*
G01X353898D02*
X353098Y-528102D01*
X352498Y-528768D01*
X352098Y-529568D01*
X351798Y-530635D01*
X351698Y-531835D01*
X351798Y-533035D01*
X352098Y-534102D01*
X352498Y-534902D01*
X353098Y-535568D01*
X353898Y-535835D01*
X354698Y-535568D01*
X355298Y-534902D01*
X355698Y-534102D01*
X355998Y-533035D01*
X356098Y-531835D01*
X355998Y-530635D01*
X355698Y-529568D01*
X355298Y-528768D01*
X354698Y-528102D01*
X353898Y-527835D01*
G01X361898Y-535835D02*
Y-527835D01*
X360698Y-529435D01*
G01Y-535835D02*
X363098D01*
G01X368098Y-536102D02*
X371698Y-527835D01*
G01X377898D02*
X377098Y-528102D01*
X376498Y-528768D01*
X376098Y-529568D01*
X375798Y-530635D01*
X375698Y-531835D01*
X375798Y-533035D01*
X376098Y-534102D01*
X376498Y-534902D01*
X377098Y-535568D01*
X377898Y-535835D01*
X378698Y-535568D01*
X379298Y-534902D01*
X379698Y-534102D01*
X379998Y-533035D01*
X380098Y-531835D01*
X379998Y-530635D01*
X379698Y-529568D01*
X379298Y-528768D01*
X378698Y-528102D01*
X377898Y-527835D01*
G01X384198Y-534902D02*
X384898Y-535568D01*
X385698Y-535835D01*
X386498Y-535568D01*
X387198Y-534769D01*
X387698Y-533568D01*
X387898Y-532368D01*
Y-530902D01*
X387698Y-529702D01*
X387198Y-528635D01*
X386598Y-528102D01*
X385898Y-527835D01*
X385098Y-528102D01*
X384498Y-528635D01*
X384098Y-529435D01*
X383898Y-530502D01*
X384098Y-531435D01*
X384598Y-532368D01*
X385198Y-532902D01*
X385898Y-533035D01*
X386698Y-532769D01*
X387298Y-532102D01*
X387898Y-530902D01*
G01X311698Y-510835D02*
Y-502835D01*
X313698D01*
X314498Y-503235D01*
X315098Y-503768D01*
X315598Y-504568D01*
X315998Y-505502D01*
X316098Y-506835D01*
X315998Y-508168D01*
X315598Y-509102D01*
X315098Y-509902D01*
X314498Y-510435D01*
X313698Y-510835D01*
X311698D01*
G01X319398D02*
X321898Y-502835D01*
X324398Y-510835D01*
G01X323498Y-508035D02*
X320298D01*
G01X329898Y-502835D02*
X329098Y-503102D01*
X328498Y-503768D01*
X328098Y-504568D01*
X327798Y-505635D01*
X327698Y-506835D01*
X327798Y-508035D01*
X328098Y-509102D01*
X328498Y-509902D01*
X329098Y-510568D01*
X329898Y-510835D01*
X330698Y-510568D01*
X331298Y-509902D01*
X331698Y-509102D01*
X331998Y-508035D01*
X332098Y-506835D01*
X331998Y-505635D01*
X331698Y-504568D01*
X331298Y-503768D01*
X330698Y-503102D01*
X329898Y-502835D01*
G01X335998Y-510835D02*
Y-502835D01*
X339798D01*
G01X338398Y-506702D02*
X335998D01*
G01X345898Y-502835D02*
X345098Y-503102D01*
X344498Y-503768D01*
X344098Y-504568D01*
X343798Y-505635D01*
X343698Y-506835D01*
X343798Y-508035D01*
X344098Y-509102D01*
X344498Y-509902D01*
X345098Y-510568D01*
X345898Y-510835D01*
X346698Y-510568D01*
X347298Y-509902D01*
X347698Y-509102D01*
X347998Y-508035D01*
X348098Y-506835D01*
X347998Y-505635D01*
X347698Y-504568D01*
X347298Y-503768D01*
X346698Y-503102D01*
X345898Y-502835D01*
G01X353898D02*
Y-510835D01*
G01X351598Y-502835D02*
X356198D01*
G01X363898Y-510835D02*
X359898D01*
Y-502835D01*
X363898D01*
G01X362298Y-506702D02*
X359898D01*
G01X370698Y-506568D02*
X371098Y-506168D01*
X371398Y-505502D01*
X371598Y-504568D01*
X371398Y-503768D01*
X370998Y-503235D01*
X370298Y-502835D01*
X367598D01*
Y-510835D01*
X370898D01*
X371598Y-510302D01*
X371998Y-509502D01*
X372198Y-508568D01*
X371998Y-507635D01*
X371398Y-506835D01*
X370698Y-506568D01*
X367598D01*
G01X376698Y-502835D02*
X379098D01*
G01X377898D02*
Y-510835D01*
G01X376698D02*
X379098D01*
G01X383998D02*
Y-502835D01*
X387798D01*
G01X386398Y-506702D02*
X383998D01*
G01X393898Y-502835D02*
X393098Y-503102D01*
X392498Y-503768D01*
X392098Y-504568D01*
X391798Y-505635D01*
X391698Y-506835D01*
X391798Y-508035D01*
X392098Y-509102D01*
X392498Y-509902D01*
X393098Y-510568D01*
X393898Y-510835D01*
X394698Y-510568D01*
X395298Y-509902D01*
X395698Y-509102D01*
X395998Y-508035D01*
X396098Y-506835D01*
X395998Y-505635D01*
X395698Y-504568D01*
X395298Y-503768D01*
X394698Y-503102D01*
X393898Y-502835D01*
G01X329498Y-485835D02*
Y-477835D01*
X333298D01*
G01X331898Y-481702D02*
X329498D01*
G01X339398Y-477835D02*
X338598Y-478102D01*
X337998Y-478768D01*
X337598Y-479568D01*
X337298Y-480635D01*
X337198Y-481835D01*
X337298Y-483035D01*
X337598Y-484102D01*
X337998Y-484902D01*
X338598Y-485568D01*
X339398Y-485835D01*
X340198Y-485568D01*
X340798Y-484902D01*
X341198Y-484102D01*
X341498Y-483035D01*
X341598Y-481835D01*
X341498Y-480635D01*
X341198Y-479568D01*
X340798Y-478768D01*
X340198Y-478102D01*
X339398Y-477835D01*
G01X347398D02*
Y-485835D01*
G01X345098Y-477835D02*
X349698D01*
G01X352398Y-488502D02*
X358398D01*
G01X361898Y-482235D02*
X365098D01*
X364798Y-481302D01*
X364298Y-480768D01*
X363598Y-480502D01*
X362898Y-480635D01*
X362298Y-481035D01*
X361898Y-481968D01*
X361698Y-482769D01*
Y-483568D01*
X361898Y-484368D01*
X362398Y-485168D01*
X362998Y-485702D01*
X363698Y-485835D01*
X364398Y-485568D01*
X365098Y-484769D01*
G01X369898Y-480502D02*
X372898Y-485835D01*
G01Y-480502D02*
X369898Y-485835D01*
G01X377598Y-488502D02*
Y-480502D01*
G01Y-481702D02*
X378098Y-481035D01*
X378598Y-480635D01*
X379398Y-480502D01*
X380098Y-480635D01*
X380798Y-481302D01*
X381098Y-482235D01*
X381198Y-483168D01*
X381098Y-484102D01*
X380798Y-485035D01*
X380198Y-485568D01*
X379398Y-485835D01*
X378698Y-485702D01*
X377998Y-485302D01*
X377598Y-484769D01*
G01X389198Y-485835D02*
Y-480502D01*
G01Y-481435D02*
X388798Y-480902D01*
X388198Y-480635D01*
X387498Y-480502D01*
X386798Y-480768D01*
X386198Y-481302D01*
X385798Y-482102D01*
X385598Y-483168D01*
X385798Y-484235D01*
X386198Y-485035D01*
X386798Y-485568D01*
X387498Y-485835D01*
X388198Y-485702D01*
X388798Y-485302D01*
X389198Y-484769D01*
G01X393698Y-485835D02*
Y-480502D01*
G01Y-481835D02*
X394098Y-481168D01*
X394698Y-480635D01*
X395498Y-480502D01*
X396198Y-480635D01*
X396798Y-481168D01*
X397098Y-482102D01*
Y-485835D01*
G01X405198Y-477835D02*
Y-485835D01*
G01Y-484635D02*
X404798Y-485302D01*
X404198Y-485702D01*
X403498Y-485835D01*
X402698Y-485568D01*
X402098Y-484902D01*
X401698Y-484102D01*
X401598Y-483168D01*
X401698Y-482235D01*
X402098Y-481435D01*
X402698Y-480768D01*
X403498Y-480502D01*
X404198Y-480635D01*
X404698Y-480902D01*
X405198Y-481435D01*
G01X409898Y-482235D02*
X413098D01*
X412798Y-481302D01*
X412298Y-480768D01*
X411598Y-480502D01*
X410898Y-480635D01*
X410298Y-481035D01*
X409898Y-481968D01*
X409698Y-482769D01*
Y-483568D01*
X409898Y-484368D01*
X410398Y-485168D01*
X410998Y-485702D01*
X411698Y-485835D01*
X412398Y-485568D01*
X413098Y-484769D01*
G01X417998Y-485835D02*
Y-480502D01*
G01Y-481568D02*
X418498Y-481035D01*
X418998Y-480635D01*
X419698Y-480502D01*
X420198Y-480635D01*
X420798Y-481035D01*
G01X424398Y-488502D02*
X430398D01*
G01X433598Y-485835D02*
Y-477835D01*
G01Y-481835D02*
X434098Y-481035D01*
X434698Y-480635D01*
X435298Y-480502D01*
X436198Y-480768D01*
X436798Y-481302D01*
X437198Y-482235D01*
Y-483302D01*
X436998Y-484368D01*
X436598Y-485168D01*
X435898Y-485702D01*
X435298Y-485835D01*
X434698Y-485702D01*
X434098Y-485302D01*
X433598Y-484635D01*
G01X445198Y-477835D02*
Y-485835D01*
G01Y-484635D02*
X444798Y-485302D01*
X444198Y-485702D01*
X443498Y-485835D01*
X442698Y-485568D01*
X442098Y-484902D01*
X441698Y-484102D01*
X441598Y-483168D01*
X441698Y-482235D01*
X442098Y-481435D01*
X442698Y-480768D01*
X443498Y-480502D01*
X444198Y-480635D01*
X444698Y-480902D01*
X445198Y-481435D01*
G01X400398Y-538835D02*
Y-530835D01*
X399198Y-532435D01*
G01Y-538835D02*
X401598D01*
G01X406498Y-535502D02*
X407198Y-534568D01*
X407798Y-534035D01*
X408598Y-533768D01*
X409298Y-534035D01*
X409798Y-534568D01*
X410198Y-535368D01*
X410298Y-536302D01*
X410198Y-537102D01*
X409798Y-537902D01*
X409198Y-538568D01*
X408498Y-538835D01*
X407698Y-538568D01*
X406998Y-537769D01*
X406598Y-536568D01*
X406498Y-535235D01*
X406698Y-533502D01*
X406998Y-532568D01*
X407498Y-531635D01*
X408198Y-530968D01*
X408898Y-530835D01*
X409598Y-531102D01*
X410098Y-531768D01*
G01X416398Y-539102D02*
X416198Y-538968D01*
Y-538702D01*
X416398Y-538568D01*
X416598Y-538702D01*
Y-538968D01*
X416398Y-539102D01*
G01X422498Y-535502D02*
X423198Y-534568D01*
X423798Y-534035D01*
X424598Y-533768D01*
X425298Y-534035D01*
X425798Y-534568D01*
X426198Y-535368D01*
X426298Y-536302D01*
X426198Y-537102D01*
X425798Y-537902D01*
X425198Y-538568D01*
X424498Y-538835D01*
X423698Y-538568D01*
X422998Y-537769D01*
X422598Y-536568D01*
X422498Y-535235D01*
X422698Y-533502D01*
X422998Y-532568D01*
X423498Y-531635D01*
X424198Y-530968D01*
X424898Y-530835D01*
X425598Y-531102D01*
X426098Y-531768D01*
G01X445398Y-538835D02*
Y-530835D01*
X444198Y-532435D01*
G01Y-538835D02*
X446598D01*
G01X453198D02*
X453398Y-537102D01*
X453698Y-535635D01*
X454098Y-534302D01*
X454598Y-532835D01*
X455398Y-530835D01*
X451398D01*
G01X461398Y-539102D02*
X461198Y-538968D01*
Y-538702D01*
X461398Y-538568D01*
X461598Y-538702D01*
Y-538968D01*
X461398Y-539102D01*
G01X467498Y-532168D02*
X468098Y-531368D01*
X468798Y-530968D01*
X469598Y-530835D01*
X470598Y-531102D01*
X471298Y-531768D01*
X471498Y-532568D01*
X471398Y-533369D01*
X470998Y-534035D01*
X468998Y-535368D01*
X468098Y-536302D01*
X467498Y-537635D01*
X467298Y-538835D01*
X471498D01*
G01X465498Y-513835D02*
Y-505835D01*
X469298D01*
G01X467898Y-509702D02*
X465498D01*
G54D21*
X18037Y1515478D03*
X21537D03*
X63981Y1215113D03*
X96443Y893358D03*
X156299Y1138393D03*
X160039D03*
X220500Y539484D03*
X221263Y635637D03*
X223952Y1216936D03*
X246695Y636173D03*
X291444Y1187015D03*
X408523Y1330128D03*
X404657Y1330152D03*
X395959Y1358035D03*
X400879Y1403302D03*
X395111Y1493965D03*
X409981Y1536970D03*
X404157D03*
X424016Y331124D03*
X425773Y1268456D03*
X418735Y1285548D03*
X414735D03*
X410152Y1408437D03*
X416357Y1401933D03*
X430959Y331073D03*
X431822Y1125816D03*
X427997Y1125801D03*
X441078Y1266694D03*
X436325D03*
X431661Y1268456D03*
X432485Y1322278D03*
X450591Y1010250D03*
Y1017250D03*
X456377Y1026683D03*
X456472Y1266801D03*
X451377Y1266781D03*
X446246Y1266726D03*
X460377Y1026683D03*
X464385Y1026664D03*
X461677Y1266823D03*
X466975D03*
X472592Y1266791D03*
X489121D03*
X478101D03*
X483503D03*
X505791Y720400D03*
X497357Y1125921D03*
X493532Y1125896D03*
X494901Y1268465D03*
X505728D03*
X500302D03*
X522939Y1268550D03*
X519131Y1268549D03*
X537023Y718226D03*
X528741Y815633D03*
X530453Y1268616D03*
X526725Y1268590D03*
X545741Y801633D03*
X552665Y847802D03*
X553383Y893358D03*
X570241Y806133D03*
Y827633D03*
X562231Y847780D03*
X577501Y819532D03*
X588001D03*
X577501Y826532D03*
X588001D03*
X613386Y1138393D03*
X617126D03*
X677586Y539484D03*
X681039Y1216936D03*
X748531Y1187015D03*
X780631Y1453144D03*
X787631Y1022396D03*
X791686D03*
X801082Y1454050D03*
X801998Y1474050D03*
X829852Y889989D03*
X829995Y923060D03*
X829494Y972691D03*
X835000Y758984D03*
X839000Y765984D03*
X835000Y776984D03*
Y794984D03*
X839000Y783984D03*
X835000Y812984D03*
X839000Y801984D03*
Y819984D03*
X836644Y860996D03*
X840381Y923553D03*
X844381D03*
X833898Y1451902D03*
X880054Y761168D03*
X874851D03*
X880054Y780182D03*
X874851Y780192D03*
X875916Y806374D03*
Y816524D03*
X879286Y911821D03*
X875286D03*
X894449Y603847D03*
X886610Y761167D03*
X885110Y780177D03*
X891916Y816524D03*
X895866Y823474D03*
X883866D03*
X888016D03*
X891916D03*
X883286Y911821D03*
X891286D03*
X887286D03*
X904393Y567685D03*
X908517D03*
X898815D03*
X899916Y806374D03*
X909416Y816524D03*
X899286Y911821D03*
X924143Y357875D03*
X918948Y357804D03*
X913716Y806374D03*
X921790Y816524D03*
X927286Y911821D03*
X923286D03*
X919286D03*
X915286D03*
X935124Y837440D03*
X941987Y857116D03*
X934944Y885045D03*
X931286Y911821D03*
X935286D03*
X952957Y922966D03*
X971648Y1224116D03*
X992000Y786484D03*
X985324Y1361790D03*
X999678Y330891D03*
X1021451Y320388D03*
X1025920Y320312D03*
X1013902Y893314D03*
X1029673Y320388D03*
X1051527Y1445495D03*
X1059448Y1438410D03*
X1074212Y1138393D03*
X1070472D03*
X1134673Y539484D03*
X1138125Y1216936D03*
X1160197Y797394D03*
X1173697D03*
X1187431Y874297D03*
X1183431D03*
X1187431Y881797D03*
X1187151Y926518D03*
Y933518D03*
X1205617Y1187015D03*
X1314604Y1273749D03*
X1326601Y334216D03*
X1333725Y334165D03*
X1319999Y1273749D03*
X1335936D03*
X1325478D03*
X1330582D03*
X1338500Y920984D03*
X1346083Y1125735D03*
X1342218Y1125772D03*
X1346362Y1273749D03*
X1351673D03*
X1341226D03*
X1364500Y819484D03*
X1360000D03*
X1355500D03*
X1364765Y1010250D03*
Y1017250D03*
X1356856Y1273749D03*
X1367828D03*
X1362308D03*
X1382667Y819355D03*
X1378000Y819484D03*
X1369000D03*
X1374500Y920984D03*
X1374551Y1026683D03*
X1370551D03*
X1378559Y1026664D03*
X1380936Y1265839D03*
X1372152Y1273716D03*
X1386122Y1265895D03*
X1391272Y1265861D03*
X1396296Y1265859D03*
X1407954Y1125946D03*
X1411829Y1125923D03*
X1411184Y1268594D03*
X1401428Y1265859D03*
X1415181Y1268594D03*
X1406916D03*
X1419451Y1268538D03*
X1440411Y1268594D03*
X1444381D03*
X1436439Y1268619D03*
X1467556Y893358D03*
X1493500Y942984D03*
X1510500Y928984D03*
X1528357Y974575D03*
X1517424Y975153D03*
X1527559Y1138393D03*
X1535000Y933484D03*
Y954984D03*
X1531299Y1138393D03*
X1591760Y539484D03*
X1595212Y1216936D03*
X1662704Y1187015D03*
X1817766Y1205384D03*
G54D30*
X25807Y1529931D03*
Y1522774D03*
X60657Y847627D03*
X56904Y897500D03*
X59010Y1511735D03*
X60496Y1525714D03*
X60520Y1518596D03*
X60470Y1531804D03*
X87130Y681800D03*
X95806Y875194D03*
Y879194D03*
X115610Y892845D03*
Y884845D03*
Y888845D03*
X156222Y1148530D03*
X156681Y1164560D03*
X156466Y1160650D03*
X156681Y1169100D03*
X180117Y550400D03*
Y554400D03*
X197903Y544967D03*
X190903D03*
X193617Y618400D03*
X258661Y438323D03*
X248058Y427017D03*
X248026Y435029D03*
Y431029D03*
X279189Y467367D03*
X281017Y384500D03*
X303800Y377912D03*
Y389912D03*
Y381912D03*
Y385912D03*
Y393924D03*
Y397912D03*
Y401924D03*
Y405924D03*
Y409924D03*
X392828Y1299275D03*
Y1303275D03*
X389672Y1311289D03*
Y1315289D03*
X385495Y1384722D03*
Y1388722D03*
X397034Y1540700D03*
Y1535200D03*
Y1547200D03*
X417666Y343005D03*
X418087Y334523D03*
X418597Y1111226D03*
X422524Y1288843D03*
X425470Y1320684D03*
X422225Y1370972D03*
X428210Y349696D03*
X435340Y1309865D03*
X430099Y1398800D03*
X430075Y1394934D03*
X456302Y1002180D03*
X450618Y1111226D03*
X455715Y1193471D03*
X445423Y1301545D03*
Y1297045D03*
Y1305545D03*
X459402Y1007325D03*
X464608Y1014566D03*
X468389Y1197471D03*
X488010Y795025D03*
X484069Y1111177D03*
X503403Y704755D03*
X506258Y796149D03*
X497124Y790275D03*
X523046Y713581D03*
X512453Y799973D03*
Y811973D03*
Y803973D03*
Y807973D03*
X522221Y831027D03*
X522258Y840649D03*
Y836149D03*
X521901Y849830D03*
X513844Y897500D03*
X516327Y1111272D03*
X533296Y708711D03*
X529221Y831027D03*
X529258Y836149D03*
Y840649D03*
X528901Y849830D03*
X552221Y796389D03*
X552746Y879194D03*
Y875194D03*
X572550Y888845D03*
Y884845D03*
Y892845D03*
X577917Y961804D03*
X613309Y1148530D03*
X613553Y1160650D03*
X613768Y1169100D03*
Y1164560D03*
X637203Y550400D03*
Y554400D03*
X647989Y544967D03*
X650703Y618400D03*
X654989Y544967D03*
X697036Y762971D03*
Y756971D03*
X697022Y780659D03*
Y775159D03*
X715747Y438323D03*
X725966Y442606D03*
Y446606D03*
X738103Y384500D03*
X736275Y467367D03*
X760886Y377912D03*
Y389912D03*
Y381912D03*
Y385912D03*
Y393924D03*
Y397912D03*
Y401924D03*
Y405924D03*
Y409924D03*
X799361Y1460979D03*
X813911Y872812D03*
Y876605D03*
X803136Y1425152D03*
X803361Y1436240D03*
X828241Y859484D03*
X831404Y1463690D03*
X842826Y835459D03*
Y839459D03*
X840781Y843490D03*
X840378Y855397D03*
X842826Y851459D03*
X842740Y875476D03*
X839975Y879459D03*
Y883459D03*
X839881Y891503D03*
X839882Y887490D03*
X861908Y388245D03*
X853776Y847459D03*
Y835459D03*
Y839459D03*
Y843459D03*
Y855459D03*
X853823Y851924D03*
X886568Y571532D03*
X887719Y577288D03*
X887776Y585773D03*
X883748Y1460847D03*
X912167Y360583D03*
X912398Y365893D03*
X900663Y888478D03*
X916990Y312228D03*
X923635Y1379411D03*
X923662Y1383264D03*
X923688Y1387039D03*
X923716Y1390841D03*
X933988Y1371951D03*
X934062Y1375878D03*
X939030Y1443901D03*
X971350Y897500D03*
X965075Y1444474D03*
X990717Y1369200D03*
Y1373400D03*
Y1385200D03*
Y1394200D03*
Y1389200D03*
X990688Y1398271D03*
X987260Y1444240D03*
X1007775Y327510D03*
Y323386D03*
Y333088D03*
Y339880D03*
X1002518Y801475D03*
X1006522Y816957D03*
X1009832Y875194D03*
Y879194D03*
X1011371Y1444512D03*
X1029636Y892845D03*
Y884845D03*
Y888845D03*
X1037037Y1444596D03*
X1043937Y337454D03*
X1070395Y1148530D03*
X1070854Y1164560D03*
Y1169100D03*
X1070639Y1160650D03*
X1088807Y1533457D03*
X1094290Y550400D03*
Y554400D03*
X1105076Y544967D03*
X1107790Y618400D03*
X1112076Y544967D03*
X1152534Y788431D03*
X1146002Y797142D03*
Y810142D03*
X1162231Y427017D03*
X1162199Y431029D03*
Y435029D03*
X1172834Y438323D03*
X1183053Y442606D03*
Y446606D03*
X1176669Y888899D03*
X1195190Y384500D03*
X1193362Y467367D03*
X1217973Y377912D03*
Y389912D03*
Y381912D03*
Y385912D03*
Y393924D03*
Y397912D03*
Y401924D03*
Y405924D03*
Y409924D03*
X1260747Y327257D03*
X1267654D03*
X1276517Y330500D03*
Y334500D03*
X1296517Y871800D03*
Y875800D03*
Y891800D03*
X1287981Y881802D03*
X1320672Y337615D03*
X1320287Y346026D03*
X1330795Y352788D03*
X1332547Y1111198D03*
X1364758D03*
X1382950Y569000D03*
Y565000D03*
Y615500D03*
Y611500D03*
X1373576Y1007325D03*
X1370476Y1002180D03*
X1378782Y1014566D03*
X1382563Y1197471D03*
X1369889Y1193471D03*
X1394534Y984037D03*
X1398205Y1111258D03*
X1408832Y992861D03*
X1407917Y1423700D03*
X1428017Y897500D03*
X1430448Y1111197D03*
X1440517Y927000D03*
X1466919Y879194D03*
Y875194D03*
X1471017Y923500D03*
X1477212Y927324D03*
Y931324D03*
Y939324D03*
Y935324D03*
X1497580Y876339D03*
X1487353Y891615D03*
X1493980Y958378D03*
X1486980D03*
X1494017Y963500D03*
X1487017D03*
X1494017Y968000D03*
X1487017D03*
X1486660Y977181D03*
X1493660D03*
X1516980Y923740D03*
X1523017Y943000D03*
X1516017D03*
X1527482Y1148530D03*
X1527726Y1160650D03*
X1527941Y1169100D03*
Y1164560D03*
X1551377Y550400D03*
Y554400D03*
X1562163Y544967D03*
X1548240Y1418847D03*
X1557239Y1418806D03*
X1569163Y544967D03*
X1564877Y618400D03*
X1585527Y341787D03*
Y337787D03*
X1619318Y427017D03*
X1619286Y431029D03*
Y435029D03*
X1629921Y438323D03*
X1652277Y384500D03*
X1650449Y467367D03*
X1675060Y377912D03*
Y389912D03*
Y381912D03*
Y385912D03*
Y393924D03*
Y397912D03*
Y401924D03*
Y405924D03*
Y409924D03*
G54D12*
X19685Y-83298D03*
X26789Y1373669D03*
X19685Y1801195D03*
X184851Y334492D03*
X235433Y1580079D03*
Y1626339D03*
X581890Y1580079D03*
Y1626339D03*
X1259055Y1580079D03*
Y1626339D03*
X1605512Y1580079D03*
Y1626339D03*
X1796847Y1517889D03*
X1809883Y120792D03*
X1821260Y-83298D03*
Y1801195D03*
G54D105*
X1269749Y937697D03*
X1276049Y935138D03*
Y940256D03*
G54D115*
G01X10131Y115473D02*
Y117161D01*
X11857Y118887D01*
Y129481D01*
X9570Y131768D01*
Y133511D01*
X13140Y137081D01*
Y140198D01*
X11999Y141339D01*
Y141415D01*
G01X15143Y115581D02*
Y117213D01*
X13761Y118595D01*
Y128373D01*
X17083Y131695D01*
Y134943D01*
X14969Y137057D01*
Y140288D01*
X15948Y141267D01*
G01X93496Y1547768D02*
X77959Y1563305D01*
X39687D01*
X32576Y1556194D01*
X17460D01*
X16371Y1555105D01*
Y1547967D01*
X6951Y1538547D01*
G01X62224Y473045D02*
Y466711D01*
X66925Y462010D01*
Y457410D01*
X71599Y452736D01*
X145755D01*
X148940Y455921D01*
G01X59104Y874177D02*
Y880162D01*
G01D02*
Y889620D01*
X63784Y894300D01*
X82299D01*
X84028Y896029D01*
Y904833D01*
G01X59104Y871027D02*
X62417D01*
X63969Y869475D01*
G01X75890Y874859D02*
Y873715D01*
X72962Y870787D01*
X67837D01*
X63930Y874694D01*
G01X71528Y883233D02*
Y886835D01*
X70600Y887763D01*
X63745D01*
G01D02*
Y883217D01*
G01X69028Y904833D02*
Y909194D01*
X68100Y910122D01*
G01X59962Y905500D02*
Y910251D01*
G01X56812Y905500D02*
X56607Y905295D01*
X52077D01*
G01X56812Y897500D02*
Y901500D01*
G01D02*
Y905500D01*
G01X64007Y1219504D02*
Y1215230D01*
X63981Y1215204D01*
G01X53479Y1216256D02*
X54531Y1215204D01*
X63981D01*
G01X68245Y1212054D02*
X68620Y1212429D01*
Y1221004D01*
X66970Y1222654D01*
X64007D01*
G01X87038Y681800D02*
X85620D01*
X83994Y683426D01*
X78735D01*
G01X84367Y878286D02*
Y879522D01*
X84028Y879861D01*
Y883233D01*
G01X76528D02*
Y878533D01*
G01X79040Y874859D02*
X86061D01*
G01X74028Y883233D02*
Y889065D01*
G01X81528Y883233D02*
Y886964D01*
X83079Y888515D01*
G01X79028Y883233D02*
Y888501D01*
X82123Y891596D01*
X90052D01*
X91278Y892822D01*
G01X72035Y898346D02*
Y900412D01*
X74028Y902405D01*
Y904833D01*
G01X76528D02*
Y908750D01*
X77028Y909250D01*
X92550D01*
X96395Y905405D01*
G01X81528Y904833D02*
Y901152D01*
X80339Y899963D01*
Y897943D01*
G01X71528Y913190D02*
Y904833D01*
G01X76203Y897910D02*
Y899574D01*
X79028Y902399D01*
Y904833D01*
G01X95539Y664443D02*
X88756D01*
G01X111993Y710102D02*
Y703605D01*
X90188Y681800D01*
G01X86061Y874859D02*
X87418Y876216D01*
Y879788D01*
X86528Y880678D01*
Y883233D01*
G01X90000Y871389D02*
X94962D01*
G01Y868239D02*
X99022D01*
X99055Y868206D01*
G01D02*
X103770D01*
G01X91278Y892822D02*
X91387Y892931D01*
Y897425D01*
G01X96443Y893449D02*
Y894928D01*
X95352Y896019D01*
Y897425D01*
G01X96395Y905405D02*
X95352Y904362D01*
Y900575D01*
G01Y897425D02*
X100822D01*
X103692Y900295D01*
G01X91387Y900575D02*
Y905295D01*
G01X103836Y988813D02*
Y986667D01*
X103306Y986137D01*
X99176D01*
X98051Y987262D01*
Y990686D01*
X97058Y991679D01*
X93934D01*
X92778Y990523D01*
Y986651D01*
X97101Y982328D01*
X106730D01*
X108827Y980231D01*
Y975764D01*
X135191Y949400D01*
X269984D01*
X396519Y822865D01*
X447314D01*
X476524Y852075D01*
X489711D01*
X492000Y854364D01*
X668772D01*
X704578Y818558D01*
Y795904D01*
X709670Y790812D01*
X713222D01*
G01X100200Y988800D02*
X99836Y989164D01*
Y993245D01*
X97800Y995281D01*
Y1009115D01*
X107806Y1019121D01*
X124520D01*
X127200Y1021801D01*
Y1026201D01*
X133599Y1032600D01*
X194754D01*
X225001Y1062847D01*
G01X247933Y1118208D02*
X249737Y1120012D01*
Y1122878D01*
X250459Y1123600D01*
X278400D01*
X279476Y1122524D01*
Y1114106D01*
X280698Y1112884D01*
X282349D01*
X285454Y1109779D01*
Y1069880D01*
X207915Y992341D01*
X156084D01*
X154001Y990258D01*
Y987428D01*
X150618Y984045D01*
X97716D01*
X95836Y985925D01*
Y988813D01*
G01X255413Y1118208D02*
X253790Y1116585D01*
X247066D01*
X246220Y1117431D01*
Y1122423D01*
X245043Y1123600D01*
X236200D01*
X235200Y1122600D01*
Y1121300D01*
X234100Y1120200D01*
X225346D01*
X223622Y1118476D01*
Y1111778D01*
X225493Y1109907D01*
Y1067437D01*
X192356Y1034300D01*
X128600D01*
X115214Y1020914D01*
X106571D01*
X100316Y1014659D01*
X91580D01*
X88479Y1017760D01*
Y1023731D01*
G01X107540Y196665D02*
X112270Y191935D01*
X162906D01*
X169314Y198343D01*
X208224D01*
X209902Y196665D01*
G01X107540Y192665D02*
X109940Y190265D01*
X111507D01*
X111557Y190215D01*
X163619D01*
X170027Y196623D01*
X205944D01*
X209902Y192665D01*
G01X107653Y186778D02*
X109420Y188545D01*
X110794D01*
X110844Y188495D01*
X164332D01*
X170740Y194903D01*
X201890D01*
X210015Y186778D01*
G01X115518Y884845D02*
X114673Y884000D01*
X110887D01*
G01X115518Y884845D02*
Y888845D01*
G01D02*
Y892845D01*
G01X240452Y1114468D02*
Y1069236D01*
X232114Y1060898D01*
X231597D01*
X230863Y1060164D01*
Y1059647D01*
X226958Y1055742D01*
Y1055358D01*
X223992Y1052392D01*
X223608D01*
X199516Y1028300D01*
X136501D01*
X133350Y1025149D01*
Y1020549D01*
X124101Y1011300D01*
X119400D01*
X109900Y1001800D01*
Y990749D01*
X111836Y988813D01*
G01X236712Y1118208D02*
X232993Y1114489D01*
Y1067819D01*
X228587Y1063413D01*
Y1062787D01*
X225913Y1060113D01*
X225287D01*
X223787Y1058613D01*
X223113D01*
X219937Y1055437D01*
Y1054763D01*
X196274Y1031100D01*
X133800D01*
X128800Y1026100D01*
Y1021500D01*
X122100Y1014800D01*
X114201D01*
X113772Y1015229D01*
X109804D01*
X106200Y1011625D01*
Y1008445D01*
X101806Y1004051D01*
Y994827D01*
X103836Y992797D01*
Y988813D01*
G01X115836D02*
X113800Y990849D01*
Y999800D01*
X121300Y1007300D01*
X124999D01*
X140199Y1022500D01*
X196735D01*
X232998Y1058763D01*
G01X107836Y988813D02*
X105896Y990753D01*
Y1005263D01*
X108200Y1007567D01*
Y1011683D01*
X110314Y1013797D01*
X113500D01*
X113897Y1013400D01*
X122700D01*
X130450Y1021150D01*
Y1025950D01*
X134400Y1029900D01*
X198094D01*
X224169Y1055975D01*
G01X208661Y1217322D02*
Y1218900D01*
X209161Y1219400D01*
X213000D01*
X214000Y1220400D01*
Y1240500D01*
X212700Y1241800D01*
X141000D01*
X138600Y1239400D01*
Y1235000D01*
X136320Y1232720D01*
X125020D01*
X123800Y1231500D01*
Y1226124D01*
X112048Y1214372D01*
G01X189960Y1213582D02*
X189922Y1213620D01*
X188820D01*
X187100Y1211900D01*
X114300D01*
X113700Y1211300D01*
X109900D01*
X109000Y1212200D01*
Y1216972D01*
X107803Y1218169D01*
G01X118668Y892845D02*
X119513Y892000D01*
X123387D01*
G01X131836Y988813D02*
X129897Y990752D01*
Y1002031D01*
X132866Y1005000D01*
X136999D01*
X140599Y1008600D01*
X195873D01*
X240597Y1053324D01*
G01X244192Y1114468D02*
X247915Y1110745D01*
Y1070659D01*
X236228Y1058972D01*
Y1058428D01*
X233972Y1056172D01*
X233428D01*
X230678Y1053422D01*
X230022D01*
X227278Y1050678D01*
Y1050022D01*
X198456Y1021200D01*
X140500D01*
X117711Y998411D01*
Y990938D01*
X119836Y988813D01*
G01X123836D02*
X121965Y990684D01*
Y1000666D01*
X141199Y1019900D01*
X200176D01*
X230321Y1050045D01*
G01X251673Y1114468D02*
X255256Y1110885D01*
Y1071003D01*
X241776Y1057523D01*
X241424D01*
X236776Y1052875D01*
Y1052523D01*
X194153Y1009900D01*
X140201D01*
X136601Y1006300D01*
X130400D01*
X125972Y1001872D01*
Y990677D01*
X127836Y988813D01*
G01X133579Y1097469D02*
X127923Y1103125D01*
Y1146328D01*
X135721Y1154126D01*
Y1154483D01*
X144876Y1163638D01*
X146572D01*
X148908Y1165974D01*
Y1167503D01*
X149805Y1168400D01*
X151412D01*
X152600Y1169588D01*
Y1171719D01*
X153181Y1172300D01*
X167126D01*
X169400Y1174574D01*
Y1200000D01*
X169900Y1200500D01*
X183800D01*
X185662Y1202362D01*
X193122D01*
X193622Y1202862D01*
Y1205520D01*
X194264Y1206162D01*
X199763D01*
X201000Y1207399D01*
Y1209661D01*
X204921Y1213582D01*
G01X201181D02*
X201014Y1213749D01*
X198550D01*
X196601Y1211800D01*
X189300D01*
X188300Y1210800D01*
Y1208569D01*
X187431Y1207700D01*
X118570D01*
X118533Y1207737D01*
G01X129250Y1227650D02*
X129415Y1227485D01*
Y1221524D01*
X136104Y1214835D01*
G01X210531Y1215452D02*
X208148D01*
X207000Y1216600D01*
Y1236900D01*
X205700Y1238200D01*
X151700D01*
X151100Y1237600D01*
X142600D01*
X140100Y1235100D01*
Y1233500D01*
X138200Y1231600D01*
X127626D01*
X126433Y1230407D01*
G01X147836Y988813D02*
X145802Y990847D01*
Y999927D01*
X148675Y1002800D01*
X203925D01*
X265733Y1064608D01*
G01X259153Y1114468D02*
X262894Y1110727D01*
Y1071536D01*
X251229Y1059871D01*
X250471D01*
X246329Y1055729D01*
Y1054971D01*
X198658Y1007300D01*
X141101D01*
X133698Y999897D01*
Y990951D01*
X135836Y988813D01*
G01X139836D02*
X137829Y990820D01*
Y1000022D01*
X143407Y1005600D01*
X199978D01*
X250165Y1055787D01*
G01X259153Y1118208D02*
X261229Y1116132D01*
X263791D01*
X264834Y1115089D01*
Y1113584D01*
X265681Y1112737D01*
X267186D01*
X270217Y1109706D01*
Y1072112D01*
X265505Y1067400D01*
X264701D01*
X262002Y1064701D01*
Y1063897D01*
X202405Y1004300D01*
X146209D01*
X141918Y1000009D01*
Y990731D01*
X143836Y988813D01*
G01X144640Y1039439D02*
X136768Y1047311D01*
Y1131407D01*
X134917Y1133258D01*
Y1139726D01*
X136768Y1141577D01*
Y1151802D01*
X141754Y1156788D01*
X144523D01*
X145297Y1157562D01*
Y1160192D01*
X146671Y1161566D01*
X148180D01*
X152630Y1166016D01*
Y1167227D01*
X154103Y1168700D01*
X156189D01*
X156589Y1169100D01*
G01X150952Y1040115D02*
X148668D01*
X138900Y1049883D01*
Y1072263D01*
X138703Y1072460D01*
Y1132768D01*
X137302Y1134169D01*
Y1139208D01*
X138703Y1140609D01*
Y1150951D01*
X141887Y1154135D01*
X146831D01*
X150194Y1157498D01*
X151399D01*
X153075Y1159174D01*
Y1161046D01*
X156589Y1164560D01*
G01X146595Y1053457D02*
X141092Y1058960D01*
Y1148655D01*
X142303Y1149866D01*
X150967D01*
X152449Y1151348D01*
Y1152649D01*
X153540Y1153740D01*
X155040D01*
X156374Y1155074D01*
Y1160650D01*
G01X165649Y1155610D02*
Y1155383D01*
X163866Y1153600D01*
X157200D01*
X156200Y1152600D01*
Y1151500D01*
X152548Y1147848D01*
Y1147180D01*
X151392Y1146024D01*
X149893D01*
X148907Y1145038D01*
Y1136379D01*
X147827Y1135299D01*
X146168D01*
X145194Y1134325D01*
Y1058942D01*
X149797Y1054339D01*
Y1049695D01*
X153426Y1046066D01*
X158696D01*
X160807Y1043955D01*
G01X153693Y1051037D02*
Y1057404D01*
X148744Y1062353D01*
Y1133814D01*
X149941Y1135011D01*
X151189D01*
X152300Y1136122D01*
Y1142549D01*
X153303Y1143552D01*
Y1145703D01*
X156130Y1148530D01*
G01X186220Y1217322D02*
X184350Y1215452D01*
X139552D01*
X138935Y1214835D01*
X136104D01*
G01X189960Y1217322D02*
X187982Y1219300D01*
X137864D01*
X135757Y1221407D01*
G01X201181Y1217322D02*
X199311Y1219192D01*
Y1229288D01*
X198399Y1230200D01*
X140299D01*
X139501Y1229402D01*
X135448D01*
G01X218011Y1215452D02*
Y1218311D01*
X219100Y1219400D01*
X221000D01*
X221700Y1220100D01*
Y1248200D01*
X220800Y1249100D01*
X140600D01*
X135448Y1243948D01*
Y1234921D01*
G01X136432Y1224472D02*
X139862D01*
G01X197440Y1217322D02*
X195570Y1219192D01*
Y1222400D01*
X195070Y1222900D01*
X141434D01*
X139862Y1224472D01*
G01X250790Y1539759D02*
Y1544311D01*
X247782Y1547319D01*
X206643D01*
X203726Y1550236D01*
Y1628090D01*
X198509Y1633307D01*
X182245D01*
X177951Y1629013D01*
X151139D01*
X144528Y1622402D01*
G01X149469Y634190D02*
Y637469D01*
X200240Y688240D01*
Y690910D01*
X203046Y693716D01*
G01X152658Y645389D02*
X152458D01*
X151958Y645889D01*
Y647899D01*
X199640Y695581D01*
X201115D01*
G01X159836Y988813D02*
Y977000D01*
X186036Y950800D01*
X270284D01*
X397099Y823985D01*
X446850D01*
X476065Y853200D01*
X489200D01*
X491484Y855484D01*
X669236D01*
X705698Y819022D01*
Y796368D01*
X708754Y793312D01*
X713222D01*
G01X270373Y1114468D02*
X271541D01*
X273446Y1112563D01*
X274737D01*
X277874Y1109426D01*
Y1071534D01*
X207245Y1000905D01*
X150598D01*
X149974Y1000281D01*
Y990675D01*
X151836Y988813D01*
G01X285334Y1114468D02*
X289085Y1110717D01*
Y1070619D01*
X207279Y988813D01*
X159836D01*
G01X251673Y1118208D02*
X253470Y1120005D01*
X274737D01*
X276082Y1118660D01*
Y1113630D01*
X277242Y1112470D01*
X278629D01*
X281545Y1109554D01*
Y1069766D01*
X207759Y995980D01*
X157716D01*
X155836Y997860D01*
G01X160733Y1056594D02*
X163125D01*
X168346Y1061815D01*
Y1069738D01*
X167519Y1070565D01*
Y1097140D01*
X169679Y1099300D01*
X184000D01*
X184500Y1099800D01*
Y1110100D01*
X185600Y1111200D01*
X189460D01*
X189960Y1111700D01*
Y1138779D01*
X191830Y1140649D01*
G01X156299Y1135334D02*
Y1132023D01*
X155455Y1131179D01*
X153482D01*
X152238Y1129935D01*
Y1064698D01*
X157446Y1059490D01*
Y1052384D01*
X160547Y1049283D01*
G01X160627Y1053561D02*
X163608D01*
X171259Y1061212D01*
Y1070000D01*
X173300Y1072041D01*
Y1091200D01*
X174300Y1092200D01*
X190600D01*
X191800Y1093400D01*
Y1110600D01*
X193700Y1112500D01*
Y1130201D01*
X194741Y1131242D01*
X196341D01*
X197200Y1132101D01*
Y1139019D01*
X195570Y1140649D01*
G01X159228Y1065613D02*
X156250Y1068591D01*
Y1122650D01*
X157145Y1123545D01*
X159025D01*
X160039Y1124559D01*
Y1135334D01*
G01Y1138484D02*
X163539D01*
G01D02*
X166172D01*
X167507Y1139819D01*
Y1146271D01*
G01X156299Y1143390D02*
Y1138484D01*
G01X165649Y1151870D02*
X164249D01*
X162379Y1150000D01*
X160750D01*
X159280Y1148530D01*
G01X169389Y1151870D02*
X167301Y1149782D01*
X164825D01*
X163838Y1148795D01*
Y1147158D01*
X163089Y1146409D01*
X159318D01*
X156299Y1143390D01*
G01X159739Y1169100D02*
X160753D01*
X164893Y1164960D01*
X167519D01*
G01X165649Y1159350D02*
Y1161838D01*
X162927Y1164560D01*
X159739D01*
G01X169389Y1155610D02*
X167753Y1157246D01*
X161044D01*
X159524Y1158766D01*
Y1160650D01*
G01X244912Y1539389D02*
Y1543389D01*
X242712Y1545589D01*
X205926D01*
X201996Y1549519D01*
Y1627373D01*
X197792Y1631577D01*
X182962D01*
X178668Y1627283D01*
X166731D01*
X161850Y1622402D01*
G01X167507Y1146271D02*
X165649Y1148129D01*
G01X176049Y1172249D02*
X175300Y1171500D01*
Y1169600D01*
X174300Y1168600D01*
X170478D01*
X168986Y1170092D01*
G01X176049Y1174310D02*
Y1172249D01*
G01X167519Y1164960D02*
X169389Y1163090D01*
Y1159350D01*
G01X185328Y545528D02*
X186972D01*
X187533Y544967D01*
X190811D01*
G01D02*
Y542500D01*
X191311Y542000D01*
X209000D01*
X212460Y545460D01*
Y551894D01*
G01X193961Y544967D02*
X197811D01*
G01D02*
Y549911D01*
X198940Y551040D01*
G01X196675Y594400D02*
X198600D01*
X200244Y592756D01*
X205756D01*
X208500Y595500D01*
G01X196675Y602400D02*
X198971D01*
X203500Y606929D01*
G01X196675Y598400D02*
X204401D01*
X208000Y601999D01*
Y604567D01*
G01X196675Y618400D02*
X203460D01*
G01X196675Y610400D02*
X198281D01*
X200473Y612592D01*
X203741D01*
G01X196675Y614400D02*
Y610400D01*
G01Y606400D02*
X198900D01*
X202572Y610072D01*
X209158D01*
G01X193525Y618400D02*
Y617000D01*
X194025Y616500D01*
X199000D01*
X200216Y615284D01*
X208061D01*
X209094Y616317D01*
G01X186184Y1135040D02*
Y1135075D01*
X184350Y1136909D01*
G01X182478Y1194917D02*
X188783D01*
X190190Y1193510D01*
G01D02*
Y1193011D01*
G01X193700Y1217322D02*
X195570Y1215452D01*
G01X205848Y60513D02*
Y63613D01*
X211516Y69281D01*
Y89368D01*
X206533Y94351D01*
G01X208645Y60369D02*
Y62348D01*
X216675Y70378D01*
Y88086D01*
X210482Y94279D01*
G01X209902Y196665D02*
X214582Y191985D01*
X265247D01*
X271879Y198617D01*
X310312D01*
X312264Y196665D01*
G01X209902Y192665D02*
X212302Y190265D01*
X265960D01*
X272592Y196897D01*
X308032D01*
X312264Y192665D01*
G01X210015Y186778D02*
X211782Y188545D01*
X266673D01*
X273305Y195177D01*
X303978D01*
X312377Y186778D01*
G01X212460Y554847D02*
X215000D01*
X215500Y554347D01*
Y544000D01*
G01X198940Y551040D02*
X200495Y552595D01*
Y577937D01*
G01X237449Y619803D02*
X221480D01*
X220990Y620293D01*
X209838D01*
X208540Y621591D01*
G01X214271Y1211712D02*
X212401Y1209842D01*
G01X208661Y1213582D02*
X216141D01*
G01X204921Y1217322D02*
X203051Y1215452D01*
G01X212401Y1217322D02*
X214271Y1215452D01*
G01X220500Y536425D02*
Y535000D01*
X225500Y530000D01*
G01X215500Y544000D02*
Y541000D01*
X216925Y539575D01*
X220500D01*
G01X223500Y568000D02*
X219546Y564046D01*
Y557800D01*
G01X220333Y617930D02*
X232167D01*
X232976Y617121D01*
Y608605D01*
X233807Y607774D01*
X236686D01*
G01X228024Y605215D02*
X219805D01*
X218458Y606562D01*
Y608776D01*
G01D02*
Y611501D01*
X223020Y616063D01*
X227803D01*
G01X221263Y635728D02*
X221307Y635684D01*
X225825D01*
G01D02*
X230754D01*
G01Y638243D02*
X226850D01*
X225825Y637218D01*
Y635684D01*
G01X247933Y1114468D02*
X251664Y1110737D01*
Y1070364D01*
X249112Y1067812D01*
X248088D01*
X230321Y1050045D01*
G01X236712Y1114468D02*
Y1068518D01*
X224169Y1055975D01*
G01X240452Y1118208D02*
X238606Y1120054D01*
X235910D01*
X232304Y1116448D01*
X228848D01*
X227362Y1114962D01*
Y1111538D01*
X229046Y1109854D01*
Y1066892D01*
X225001Y1062847D01*
G01X216141Y1213582D02*
X223622D01*
X223917Y1213877D01*
X223952D01*
G01X244084Y435029D02*
X247934D01*
G01X247966Y427017D02*
X244096D01*
X244084Y427029D01*
G01X247934Y431029D02*
X244084D01*
G01X252688Y636364D02*
X252588Y636264D01*
X246695D01*
G01X237449Y623543D02*
X245982D01*
X246695Y624256D01*
Y626359D01*
G01X238234Y633125D02*
X246684D01*
X246695Y633114D01*
G01Y626359D02*
Y633114D01*
G01X240194Y643113D02*
X237384D01*
X236064Y641793D01*
Y636174D01*
X236554Y635684D01*
X238234D01*
G01X255413Y1114468D02*
X259204Y1110677D01*
Y1070303D01*
X256914Y1068013D01*
X255286D01*
X240597Y1053324D01*
G01X244192Y1118208D02*
X242322Y1116338D01*
Y1112878D01*
X244322Y1110878D01*
Y1070087D01*
X232998Y1058763D01*
G01X244192Y1215452D02*
X245358D01*
X248724Y1218818D01*
X250363D01*
X251625Y1220080D01*
Y1233930D01*
X252125Y1234430D01*
X332074D01*
X345307Y1221197D01*
G01X240452Y1215452D02*
Y1217670D01*
X242231Y1219449D01*
X243296D01*
X244243Y1220396D01*
Y1241153D01*
X244743Y1241653D01*
X339057D01*
X343175Y1237535D01*
G01X242322Y1217322D02*
X245292D01*
X247914Y1219944D01*
Y1237521D01*
X248414Y1238021D01*
X333814D01*
X337884Y1233951D01*
G01X236712Y1211712D02*
X238530Y1213530D01*
X286670D01*
X288150Y1212050D01*
Y1209650D01*
X289897Y1207903D01*
X333179D01*
X340769Y1202831D01*
X341971Y1201629D01*
Y1197745D01*
X344657Y1195059D01*
G01X308588Y1263349D02*
X241151D01*
X236712Y1258910D01*
Y1215452D01*
G01X238582Y1217322D02*
X240533Y1219273D01*
Y1259034D01*
X242299Y1260800D01*
X323278D01*
X355318Y1228760D01*
G01X244600Y1531700D02*
X246700Y1529600D01*
X252600D01*
X264181Y1541181D01*
Y1623900D01*
X277137Y1636856D01*
X360943D01*
X364292Y1633507D01*
Y1589017D01*
X361063Y1585788D01*
G01X278784Y435158D02*
X269599Y425973D01*
X261321D01*
X259959Y424611D01*
X248500D01*
X247966Y425145D01*
Y427017D01*
G01X261719Y438323D02*
Y439871D01*
X260111Y441479D01*
Y443585D01*
G01X257999Y433003D02*
X248786D01*
X247934Y433855D01*
Y435029D01*
G01X278827Y444841D02*
X277377Y443391D01*
X276536Y441362D01*
X269937Y434763D01*
Y429998D01*
X268167Y428228D01*
X264532D01*
X259757Y433003D01*
X257999D01*
G01X278529Y440489D02*
Y438873D01*
X271581Y431925D01*
Y429658D01*
X269031Y427108D01*
X261824D01*
X259954Y428978D01*
X248870D01*
X247934Y429914D01*
Y431029D01*
G01X258569Y438323D02*
X254512D01*
G01X260111Y443585D02*
Y445929D01*
X263086Y448904D01*
X271623D01*
X272635Y449916D01*
Y451628D01*
G01X252695Y442956D02*
X252916Y442735D01*
X256563D01*
X257525Y443697D01*
Y452895D01*
X258163Y453533D01*
X258332Y453701D01*
X258406Y453811D01*
X260566Y455971D01*
X269207D01*
X269682Y456446D01*
Y458714D01*
G01X344500Y746300D02*
X332500D01*
X263800Y815000D01*
X255600D01*
X250700Y819900D01*
G01X363100Y750000D02*
X338900D01*
X252100Y836800D01*
G01X262893Y1114468D02*
Y1113360D01*
X266506Y1109747D01*
Y1071006D01*
X265211Y1069711D01*
X264089D01*
X250165Y1055787D01*
G01X262893Y1118208D02*
X264085D01*
X265941Y1116352D01*
X267946D01*
X268522Y1115776D01*
Y1113497D01*
X269415Y1112604D01*
X271196D01*
X274184Y1109616D01*
Y1070183D01*
X270238Y1066237D01*
X267362D01*
X265733Y1064608D01*
G01X255413Y1215452D02*
X258900Y1218939D01*
Y1225534D01*
X259900Y1226534D01*
X332877D01*
X334899Y1224512D01*
G01X262893Y1215452D02*
Y1222560D01*
X263394Y1223061D01*
X306986D01*
X307854Y1222193D01*
Y1220041D01*
X308663Y1219232D01*
X329410D01*
X331240Y1221062D01*
G01X247932Y1215451D02*
X249755Y1217274D01*
X253100D01*
X255355Y1219529D01*
Y1229455D01*
X256363Y1230463D01*
X329195D01*
X331015Y1232283D01*
G01X250876Y1532782D02*
X262851Y1544757D01*
Y1624451D01*
X276586Y1638186D01*
X363214D01*
X365622Y1635778D01*
Y1585229D01*
X361063Y1580670D01*
G01X277575Y384500D02*
X280925D01*
G01X277575Y388000D02*
Y395084D01*
G01X280925Y388000D02*
X277575D01*
G01X274425Y384500D02*
Y381500D01*
G01X275588Y451628D02*
Y454128D01*
X280032Y458572D01*
X282230D01*
G01X268788Y442606D02*
X268669Y442487D01*
X265046D01*
X263301Y444232D01*
G01X268788Y446606D02*
X265022D01*
X265011Y446595D01*
G01X279097Y467367D02*
X276344D01*
G01X279080Y463235D02*
Y467350D01*
X279097Y467367D01*
G01X358696Y775504D02*
X281100Y853100D01*
X269700D01*
G01X279945Y859855D02*
X275400Y864400D01*
G01X278400Y890839D02*
X295261D01*
X297080Y889020D01*
X297089D01*
X362789Y823320D01*
X388989D01*
X388995Y823314D01*
X389023D01*
X416837Y795500D01*
X423700D01*
G01X434100Y797400D02*
Y792800D01*
X423800Y782500D01*
X405800D01*
X402995Y785305D01*
Y802405D01*
X386700Y818700D01*
X360100D01*
X298600Y880200D01*
X280800D01*
X271100Y889900D01*
Y912299D01*
X279261Y920460D01*
Y926339D01*
G01X275400Y899400D02*
Y894200D01*
G01D02*
Y890900D01*
X278700Y887600D01*
X296500D01*
X362200Y821900D01*
X388400D01*
X421200Y789100D01*
Y786400D01*
G01X430600Y797400D02*
Y792600D01*
X422099Y784099D01*
X416901D01*
X414200Y786800D01*
X405768D01*
X404624Y787944D01*
Y803039D01*
X387363Y820300D01*
X360763D01*
X299263Y881800D01*
X281463D01*
X272700Y890563D01*
Y908800D01*
X281800Y917900D01*
Y929400D01*
G01D02*
Y933378D01*
X278739Y936439D01*
G01X284075Y388000D02*
X288500D01*
G01D02*
X290000Y386500D01*
X290430D01*
X292520Y384410D01*
G01X280925Y384500D02*
Y381075D01*
X282500Y379500D01*
X293152D01*
X295699Y382047D01*
G01X303708Y401924D02*
X298925D01*
X295584Y398583D01*
X294000D01*
G01X303708Y389912D02*
X299762Y393858D01*
X292358D01*
G01X282230Y458572D02*
Y463235D01*
G01X365850Y773950D02*
X279945Y859855D01*
G01X281594Y1144389D02*
X283263Y1142720D01*
Y1135969D01*
X283960Y1135272D01*
X287929D01*
X290101Y1133100D01*
X292101D01*
X292993Y1132208D01*
Y1055405D01*
X347315Y1001083D01*
X378790D01*
G01X285334Y1144389D02*
X287185Y1142538D01*
Y1139670D01*
X289955Y1136900D01*
X295253D01*
X296555Y1135598D01*
Y1116000D01*
X298255Y1114300D01*
X298980D01*
X300295Y1112985D01*
Y1051635D01*
X333985Y1017945D01*
G01X285334Y1148129D02*
X287204Y1149999D01*
G01D02*
X294354D01*
X294649Y1149704D01*
X298125D01*
G01X289074Y1140649D02*
X290944Y1142519D01*
G01X298125Y1142224D02*
X296255D01*
X295960Y1142519D01*
X290944D01*
G01X291444Y1179625D02*
X295292D01*
X296450Y1178467D01*
G01X291444Y1183956D02*
X294454D01*
X296012Y1185514D01*
G01X333500Y1202200D02*
X332019Y1200719D01*
X289281D01*
X287190Y1202810D01*
Y1206116D01*
X285334Y1207972D01*
G01X281594D02*
X283400Y1206166D01*
Y1199100D01*
X284100Y1198400D01*
X286401D01*
X287901Y1196900D01*
X307900D01*
X310278Y1194522D01*
X335278D01*
X339776Y1190024D01*
Y1187962D01*
G01X344064Y1203115D02*
X342063Y1205116D01*
X341121Y1205744D01*
X340981Y1206446D01*
X342502Y1208722D01*
X342362Y1209424D01*
X341765Y1209824D01*
X341063Y1209684D01*
X339542Y1207408D01*
X338840Y1207268D01*
X338243Y1207668D01*
X338103Y1208370D01*
X339624Y1210646D01*
X339484Y1211348D01*
X338887Y1211748D01*
X338185Y1211608D01*
X336664Y1209332D01*
X335962Y1209192D01*
X335365Y1209592D01*
X335225Y1210294D01*
X336746Y1212570D01*
X336606Y1213272D01*
X336009Y1213672D01*
X335307Y1213532D01*
X333786Y1211256D01*
X333084Y1211116D01*
X331954Y1211871D01*
X294130D01*
X292600Y1213401D01*
Y1214301D01*
X291449Y1215452D01*
X285334D01*
G01X359197Y1197626D02*
X354203D01*
X352300Y1199529D01*
Y1202093D01*
X338993Y1215400D01*
X294201D01*
X292700Y1216901D01*
Y1218301D01*
X292101Y1218900D01*
X285042D01*
X281594Y1215452D01*
G01X312844Y94279D02*
X318961Y88162D01*
Y69720D01*
X310817Y61576D01*
Y60393D01*
G01X308895Y94351D02*
X313802Y89444D01*
Y67555D01*
X308932Y62685D01*
Y61545D01*
X307916Y60529D01*
G01X300814Y192859D02*
X303441D01*
X306913Y189387D01*
Y181986D01*
X303487Y178560D01*
G01X299000Y377912D02*
X303708D01*
G01Y381912D02*
X299120Y386500D01*
X299000D01*
G01X303708Y385912D02*
X298124Y391496D01*
X298000D01*
G01X303708Y405924D02*
X298424D01*
X296000Y403500D01*
G01X303708Y393924D02*
Y397912D01*
G01D02*
X299088D01*
G01X303708Y409924D02*
X300924D01*
X300000Y409000D01*
X298000D01*
G01X380280Y1006071D02*
X379040D01*
X376854Y1003885D01*
X358974D01*
X307795Y1055064D01*
Y1137129D01*
X309645Y1138979D01*
Y1142519D01*
G01X341077Y1018056D02*
X338856Y1020277D01*
X335012D01*
X304164Y1051125D01*
Y1135460D01*
X300550Y1139074D01*
X298125D01*
G01X309645Y1142519D02*
Y1145583D01*
X308674Y1146554D01*
X298125D01*
G01X360273Y1228226D02*
X355119Y1233380D01*
X352548D01*
X322579Y1263349D01*
X308588D01*
G01X312264Y196665D02*
X316994Y191935D01*
X367630D01*
X373849Y198154D01*
X413137D01*
X414626Y196665D01*
G01X312264Y192665D02*
X314714Y190215D01*
X368343D01*
X374562Y196434D01*
X410857D01*
X414626Y192665D01*
G01X312377Y186778D02*
X314094Y188495D01*
X369056D01*
X375275Y194714D01*
X406803D01*
X414739Y186778D01*
G01X335399Y544718D02*
X337078Y546397D01*
Y551381D01*
G01X366761Y934550D02*
X366361D01*
X357605Y943306D01*
Y975465D01*
X377723Y995583D01*
X383005D01*
X389953Y1002531D01*
Y1037301D01*
X386919Y1040335D01*
Y1086290D01*
X363493Y1109716D01*
Y1129432D01*
X364299Y1130238D01*
Y1131784D01*
X363493Y1132590D01*
Y1137257D01*
X355160Y1145590D01*
X346092D01*
X344182Y1147500D01*
X340500D01*
G01X368964Y937738D02*
X365879D01*
X359505Y944112D01*
Y974204D01*
X378301Y993000D01*
X383500D01*
X391800Y1001300D01*
Y1037999D01*
X388819Y1040980D01*
Y1090282D01*
X368000Y1111101D01*
Y1141070D01*
X363704Y1145366D01*
Y1158812D01*
X361814Y1160702D01*
Y1180060D01*
X359156Y1182718D01*
X345609D01*
X343121Y1185206D01*
Y1188412D01*
G01X339540Y1196894D02*
Y1201168D01*
X338508Y1202200D01*
X333500D01*
G01X346387Y1199256D02*
X345838Y1199805D01*
Y1201341D01*
X344064Y1203115D01*
G01X334899Y1224512D02*
X358368Y1201043D01*
G01X354398D02*
Y1202893D01*
X336229Y1221062D01*
X331240D01*
G01X362402Y1201039D02*
X360166Y1203275D01*
X360023D01*
X331015Y1232283D01*
G01X355215Y1223170D02*
Y1225495D01*
X343175Y1237535D01*
G01X337884Y1233951D02*
X351940Y1219895D01*
G01X372400Y746300D02*
X344500D01*
G01X358696Y775504D02*
X365910Y768290D01*
X368233D01*
X370415Y766108D01*
G01X361621Y1134729D02*
Y1108472D01*
X385189Y1084904D01*
Y1039618D01*
X388223Y1036584D01*
Y1003585D01*
X381951Y997313D01*
X377006D01*
X355875Y976182D01*
Y941766D01*
X366295Y931346D01*
X368626D01*
G01X349748Y1134729D02*
X351829Y1136810D01*
X358714D01*
X359690Y1135834D01*
Y1107548D01*
X360194Y1107044D01*
Y1107045D01*
X383459Y1083780D01*
Y1038901D01*
X386493Y1035867D01*
Y1004302D01*
X385898Y1003708D01*
X381234Y999043D01*
X376289D01*
X354145Y976899D01*
Y939058D01*
X368067Y925136D01*
G01X357748Y1134729D02*
X357929Y1134548D01*
Y1128704D01*
X357748Y1128523D01*
Y1106688D01*
X381651Y1082785D01*
Y1038262D01*
X384763Y1035150D01*
Y1008336D01*
X383710Y1007283D01*
G01X382465Y1012430D02*
Y1035001D01*
X379921Y1037545D01*
Y1081657D01*
X356319Y1105259D01*
Y1105260D01*
X353748Y1107831D01*
Y1134729D01*
G01X372858Y935136D02*
X372967D01*
X374081Y936250D01*
Y939240D01*
X372610Y940711D01*
X365991D01*
X361375Y945327D01*
Y972676D01*
X379599Y990900D01*
X385400D01*
X393800Y999300D01*
Y1038601D01*
X390889Y1041512D01*
Y1091806D01*
X369815Y1112880D01*
Y1141725D01*
X365631Y1145909D01*
Y1159575D01*
X363705Y1161501D01*
Y1182149D01*
X357796Y1188058D01*
G01X344657Y1195059D02*
X345086Y1194630D01*
X347819D01*
X350402Y1197213D01*
Y1201043D01*
G01X366402Y1200969D02*
Y1199592D01*
X364436Y1197626D01*
X359197D01*
G01X345307Y1221197D02*
X349276Y1217228D01*
G01X355318Y1228760D02*
X358062Y1226016D01*
G01X352401Y1489331D02*
X355800Y1485932D01*
X381399D01*
X383259Y1487792D01*
G01X390449Y1491362D02*
X356978D01*
X353891Y1494449D01*
X352401D01*
G01X359287Y1633665D02*
X357458Y1631836D01*
Y1581396D01*
X352401Y1576339D01*
G01X353242Y1634202D02*
X355220Y1632224D01*
Y1584276D01*
X352401Y1581457D01*
G01X366526Y377173D02*
X368324Y375375D01*
Y368275D01*
X374299Y362300D01*
X453299D01*
X458000Y367001D01*
Y369985D01*
X453940Y374045D01*
X452843D01*
X450852Y372054D01*
G01X455885Y367702D02*
X452583Y364400D01*
X374861D01*
X370486Y368775D01*
Y373903D01*
G01Y377173D02*
Y373903D01*
G01X372300Y750000D02*
X363100D01*
G01X451460Y974695D02*
X448095D01*
X433890Y988900D01*
X380499D01*
X364385Y972786D01*
Y951509D01*
X365855Y950039D01*
Y945325D01*
X367368Y943812D01*
X370214D01*
G01X458120Y974701D02*
X455848Y972429D01*
X446871D01*
X432203Y987097D01*
X389555D01*
X389085Y986627D01*
Y984175D01*
X388615Y983705D01*
X386085D01*
X385615Y984175D01*
Y986627D01*
X385145Y987097D01*
X381386D01*
X367213Y972924D01*
Y952873D01*
X370214Y949872D01*
Y947812D01*
G01X389466Y1497520D02*
X362323D01*
X361063Y1498780D01*
G01Y1493662D02*
X362385Y1494984D01*
X382896D01*
G01X388612Y31168D02*
X394454Y25326D01*
X417293D01*
X422450Y30483D01*
G01X387948Y27288D02*
X394769Y20467D01*
X416311D01*
X422378Y26534D01*
G01X376881Y518564D02*
X393136D01*
X406300Y505400D01*
Y496300D01*
X448202Y454398D01*
X482028D01*
X498746Y437680D01*
X541037D01*
X548946Y445589D01*
X563333D01*
X585648Y467904D01*
Y500203D01*
X590129Y504684D01*
X598462D01*
G01X395262Y1365545D02*
X395106D01*
X394062Y1364501D01*
X392234D01*
G01X399748Y1370813D02*
X393468D01*
X392234Y1369579D01*
G01X383259Y1487792D02*
Y1483891D01*
X384911Y1482239D01*
X387800D01*
G01X382896Y1494984D02*
X394183D01*
X395111Y1494056D01*
G01X390950Y1482239D02*
X392586D01*
X392602Y1482223D01*
X395199D01*
G01X395380Y1485778D02*
X391557D01*
G01X388407D02*
X390449Y1487820D01*
Y1491362D01*
G01X395403Y1497835D02*
X395088Y1497520D01*
X389466D01*
G01X405849Y178560D02*
X402245Y182164D01*
Y185997D01*
X395942Y192300D01*
G01X398456Y1324925D02*
Y1330464D01*
G01X399959Y1358126D02*
Y1362417D01*
X405294Y1367752D01*
G01X395959Y1358126D02*
X399959D01*
G01X405278Y1375546D02*
Y1371948D01*
X401202Y1367872D01*
Y1367267D01*
X399748Y1365813D01*
X395530D01*
X395262Y1365545D01*
G01X405294Y1367752D02*
X405462Y1367920D01*
X407247Y1372229D01*
Y1375546D01*
G01X399748Y1370813D02*
X401692D01*
X403310Y1372431D01*
Y1375546D01*
G01X393951Y1447455D02*
Y1445566D01*
X405468Y1434049D01*
X430127D01*
X446085Y1418091D01*
X743808D01*
X820022Y1341877D01*
X875947D01*
X882193Y1348123D01*
X992230D01*
X996633Y1352526D01*
X1027960D01*
X1049092Y1373658D01*
Y1396924D01*
X1065034Y1412866D01*
X1411418D01*
X1418820Y1420268D01*
Y1507056D01*
X1435219Y1523455D01*
Y1525541D01*
X1444563Y1534885D01*
X1580883D01*
X1593990Y1547992D01*
X1753608D01*
X1761072Y1555456D01*
Y1590719D01*
G01X407970Y1449751D02*
X410215Y1447506D01*
X428003D01*
X452373Y1423136D01*
X781950D01*
X783469Y1424655D01*
G01X404500Y1452500D02*
X404508Y1452492D01*
Y1448334D01*
X408243Y1444599D01*
X428314D01*
X451377Y1421536D01*
X788140D01*
X788648Y1422044D01*
G01X395888Y1450022D02*
X409361Y1436549D01*
X431163D01*
X447896Y1419816D01*
X744516D01*
X820735Y1343597D01*
X875234D01*
X881480Y1349843D01*
X991517D01*
X995920Y1354246D01*
X1027074D01*
X1047252Y1374424D01*
Y1398101D01*
X1065220Y1416069D01*
X1412188D01*
X1417100Y1420981D01*
Y1507769D01*
X1433105Y1523774D01*
Y1525860D01*
X1443850Y1536605D01*
X1580170D01*
X1593277Y1549712D01*
X1752439D01*
X1757289Y1554562D01*
Y1576804D01*
X1758390Y1577905D01*
G01X395111Y1490906D02*
X395624D01*
X401217Y1496499D01*
Y1498489D01*
X398747Y1500959D01*
G01X398553Y1497835D02*
X395370Y1501018D01*
Y1501022D01*
G01X414626Y196665D02*
X419356Y191935D01*
X517631D01*
X523812Y198116D01*
X563176D01*
X564627Y196665D01*
G01X414626Y192665D02*
X417026Y190265D01*
X418593D01*
X418643Y190215D01*
X518344D01*
X524525Y196396D01*
X560896D01*
X564627Y192665D01*
G01X414739Y186778D02*
X416506Y188545D01*
X417880D01*
X417930Y188495D01*
X519057D01*
X525238Y194676D01*
X556842D01*
X564740Y186778D01*
G01X421200Y786400D02*
X428400Y793600D01*
Y800700D01*
X442100Y814400D01*
X453800D01*
X478200Y838800D01*
X502500D01*
X505714Y835586D01*
X509141D01*
G01X418505Y1111226D02*
X418597Y1111134D01*
Y1106969D01*
G01D02*
X418495Y1106867D01*
G01X425433Y1109323D02*
X424172D01*
X422642Y1107793D01*
X419421D01*
X418597Y1106969D01*
G01X425451Y1314667D02*
Y1316708D01*
X425951Y1317208D01*
X430474D01*
X432485Y1319219D01*
G01X412663Y1321462D02*
Y1319763D01*
X413127Y1319299D01*
Y1318011D01*
G01X417305Y1359169D02*
Y1355108D01*
G01X422133Y1370972D02*
Y1366972D01*
G01D02*
Y1365427D01*
X422875Y1364685D01*
Y1362304D01*
G01X416029Y1371572D02*
X415121Y1372480D01*
Y1375546D01*
G01X417581Y1378006D02*
X419622D01*
X420122Y1377506D01*
Y1372983D01*
X422133Y1370972D01*
G01X424376Y1390794D02*
X422677D01*
X422213Y1390330D01*
X420925D01*
G01X411000Y1463500D02*
X411073Y1463427D01*
X425937D01*
X458228Y1431136D01*
X742647D01*
X755035Y1443524D01*
G01X411000Y1460500D02*
X411570Y1459930D01*
X426796D01*
X457190Y1429536D01*
X778584D01*
X782848Y1433800D01*
X786787D01*
G01X411000Y1457500D02*
X412831Y1455669D01*
X428418D01*
X456151Y1427936D01*
X779344D01*
X782057Y1430649D01*
X791975D01*
X793459Y1429165D01*
G01X411000Y1454500D02*
X413838Y1451662D01*
X429787D01*
X455113Y1426336D01*
X780165D01*
X782516Y1428687D01*
X788478D01*
X789647Y1427518D01*
G01X411000Y1451000D02*
Y1450023D01*
X411541Y1449482D01*
X429371D01*
X454117Y1424736D01*
X780867D01*
X783035Y1426904D01*
X784909D01*
X785820Y1425993D01*
G01X586060Y793145D02*
X585116Y792201D01*
Y787316D01*
X583500Y785700D01*
X579300D01*
X575000Y790000D01*
Y810800D01*
X570500Y815300D01*
X554300D01*
X546400Y807400D01*
X542848D01*
X528900Y821348D01*
Y825200D01*
X527200Y826900D01*
X520800D01*
X514800Y820900D01*
X492900D01*
X476500Y804500D01*
X441200D01*
X434100Y797400D01*
G01X426300D02*
Y803700D01*
X443800Y821200D01*
X448800D01*
X477600Y850000D01*
X490800D01*
X493100Y852300D01*
X503100D01*
X506011Y849389D01*
X507821D01*
G01X427911Y1302364D02*
X431509D01*
X435585Y1298288D01*
X436190D01*
X437644Y1296834D01*
G01D02*
Y1292616D01*
X437912Y1292348D01*
G01X427911Y1300396D02*
X431026D01*
X432644Y1298778D01*
Y1296834D01*
G01D02*
Y1291315D01*
X430527Y1289198D01*
G01X445331Y1297045D02*
X441040D01*
X435705Y1302380D01*
G01X427911Y1304333D02*
X431228D01*
X435537Y1302548D01*
X435705Y1302380D01*
G01X437912Y1289198D02*
X440906D01*
G01X431885Y1313115D02*
X430977Y1312207D01*
X427911D01*
G01X436485Y1319219D02*
X438030D01*
X438772Y1319961D01*
X441153D01*
G01X432485Y1319219D02*
X436485D01*
G01X446987Y643360D02*
X449220D01*
X454687Y648827D01*
X461626D01*
G01X450526Y1111226D02*
Y1106964D01*
X450623Y1106867D01*
G01X457577Y1109318D02*
X455735D01*
X455720Y1109303D01*
X455508D01*
X454400Y1108195D01*
X451951D01*
X450623Y1106867D01*
G01X445331Y1293045D02*
Y1297045D01*
G01X444288Y1314391D02*
X448349D01*
G01X461626Y644087D02*
Y648827D01*
G01X469300Y799500D02*
X479247Y789553D01*
X504196Y779218D01*
X508206Y775208D01*
Y763457D01*
X510313Y761350D01*
X516077D01*
X517719Y759708D01*
Y757012D01*
X518184Y756547D01*
X529107D01*
X531354Y754300D01*
X543084D01*
X555061Y742323D01*
X560477D01*
X563200Y739600D01*
G01X473954Y1027202D02*
X473838D01*
X471558Y1029482D01*
G01X478907Y1027202D02*
X473954D01*
G01X479735Y1032551D02*
X475238D01*
X473639Y1030952D01*
G01X507095Y814784D02*
X489995D01*
X480000Y804789D01*
Y794943D01*
X486543Y788400D01*
X498307D01*
X500182Y790275D01*
G01X490050Y800757D02*
X485069D01*
X482476Y798164D01*
G01D02*
X485615Y795025D01*
X487918D01*
G01Y791025D02*
Y795025D01*
G01X490050Y808237D02*
X493988D01*
X495539Y806686D01*
Y795000D01*
G01X479700Y847600D02*
X486600Y840700D01*
X500700D01*
X504271Y844271D01*
X507821D01*
G01X488041Y1020440D02*
Y1023328D01*
X488794Y1024081D01*
G01X493359Y1024165D02*
X488878D01*
X488794Y1024081D01*
G01X484115Y1027044D02*
Y1028171D01*
X479735Y1032551D01*
G01X491069Y1109331D02*
X490003D01*
X488588Y1107916D01*
X485131D01*
X484082Y1106867D01*
G01D02*
X483977Y1106972D01*
Y1111177D01*
G01X872600Y1300833D02*
X872533Y1300900D01*
X491300D01*
X490100Y1302100D01*
G01X872600Y1298333D02*
X490887D01*
X487600Y1301620D01*
Y1302100D01*
G01X505791Y717341D02*
X509791D01*
G01X506461Y708755D02*
Y704755D01*
G01X510654Y703806D02*
X509705Y704755D01*
X506461D01*
G01X491068Y791025D02*
X491818Y790275D01*
X497032D01*
G01D02*
Y793507D01*
X495539Y795000D01*
G01X501074Y808237D02*
X501338Y807973D01*
X507741D01*
G01X501074Y804497D02*
X503393D01*
X505741Y802149D01*
X507241D01*
G01X501267Y830468D02*
X494677D01*
G01X501267Y835586D02*
X495073D01*
G01X499947Y844271D02*
X495470D01*
G01X499947Y849389D02*
X495700D01*
G01X530473Y961728D02*
X506938D01*
X503144Y957934D01*
G01X493347Y1028165D02*
X493359Y1028153D01*
Y1024165D01*
G01X525908Y600790D02*
X524430D01*
X520770Y597130D01*
G01X522149Y671119D02*
Y668345D01*
X521868Y668064D01*
Y666577D01*
G01X518812Y662874D02*
X513775Y667911D01*
Y673380D01*
G01X525299Y671119D02*
Y674514D01*
X522200Y677613D01*
G01X518299Y692384D02*
Y688193D01*
X517571Y687465D01*
Y684311D01*
X514585Y681325D01*
G01D02*
Y679316D01*
X513775Y678506D01*
Y676530D01*
G01X520277Y682624D02*
X517775Y680122D01*
Y676530D01*
G01X520799Y692384D02*
Y688331D01*
X520019Y687551D01*
Y687480D01*
X519616Y687077D01*
Y685134D01*
X520277Y684473D01*
Y682624D01*
G01X517775Y673380D02*
X520036Y671119D01*
X522149D01*
G01X515504Y701351D02*
X513109D01*
X510654Y703806D01*
G01X509791Y717341D02*
Y716039D01*
X511677Y714153D01*
Y712798D01*
G01D02*
X511979D01*
X518389Y706388D01*
G01X515511Y799973D02*
X517378D01*
X519891Y797460D01*
Y795848D01*
G01X515511Y807973D02*
X517917D01*
X520741Y805149D01*
G01X512361Y811973D02*
Y807973D01*
G01X507741D02*
X512361D01*
G01Y799973D02*
Y803973D01*
G01X507241Y802149D02*
X508741D01*
X510565Y803973D01*
X512361D01*
G01X522129Y831027D02*
X517702Y826600D01*
G01D02*
X515400D01*
X511532Y830468D01*
X509141D01*
G01X507821Y844271D02*
X515329D01*
X518951Y840649D01*
X522166D01*
G01X509141Y835586D02*
X511586D01*
X513800Y837800D01*
X520515D01*
X522166Y836149D01*
G01X507821Y849389D02*
X521368D01*
X521809Y849830D01*
G01X532830Y874859D02*
Y873715D01*
X528615Y869500D01*
X526064D01*
X520870Y874694D01*
G01X516044Y871027D02*
X510540D01*
X508248Y873319D01*
G01X516044Y874177D02*
Y880162D01*
G01D02*
Y887246D01*
X518341Y890684D01*
X527634Y894533D01*
X538832D01*
X540968Y896669D01*
Y904833D01*
G01X520685Y883217D02*
Y887763D01*
G01D02*
X527696D01*
X528468Y886991D01*
Y883233D01*
G01X513752Y897500D02*
Y901500D01*
G01Y905500D02*
X513547Y905295D01*
X509017D01*
G01X513752Y901500D02*
Y905500D01*
G01X516902D02*
Y910251D01*
G01X516210Y1106867D02*
X516235Y1106892D01*
G01Y1111272D02*
Y1106892D01*
G01X523200Y1109343D02*
X522129D01*
X520532Y1107746D01*
X517089D01*
X516235Y1106892D01*
G01X534820Y596782D02*
X530812Y600790D01*
X529058D01*
G01X537023Y715167D02*
X533023D01*
G01D02*
Y713322D01*
X528653Y708952D01*
G01D02*
X526493D01*
X523929Y706388D01*
G01X529129Y831027D02*
Y829261D01*
X529741Y828649D01*
X535111D01*
X538241Y825519D01*
Y816149D01*
X544741Y809649D01*
G01X525279Y831027D02*
X529129D01*
G01X529166Y836149D02*
Y838149D01*
X529666Y838649D01*
X534241D01*
X534741Y838149D01*
Y831757D01*
X541741Y824757D01*
Y819446D01*
X544878Y816309D01*
G01X525316Y836149D02*
X529166D01*
G01X537300Y842900D02*
X540600D01*
X555682Y827818D01*
Y826212D01*
G01X529166Y840649D02*
Y843574D01*
X530741Y845149D01*
G01X525316Y840649D02*
X529166D01*
G01X524959Y849830D02*
Y845367D01*
X524741Y845149D01*
G01X528809Y849830D02*
X524959D01*
G01X533468Y883233D02*
Y878533D01*
G01X535980Y874859D02*
X543001D01*
G01X535968Y883233D02*
Y886783D01*
X535630Y887121D01*
Y889931D01*
X536906Y891207D01*
X543580D01*
X545342Y892969D01*
X547843D01*
G01X538468Y883233D02*
Y888033D01*
G01X530968Y883233D02*
Y888283D01*
G01X525159Y913818D02*
Y910003D01*
X525968Y909194D01*
Y904833D01*
G01X528975Y898346D02*
Y900412D01*
X530968Y902405D01*
Y904833D01*
G01X538468D02*
Y901152D01*
X537279Y899963D01*
Y897943D01*
G01X533143Y897910D02*
Y899574D01*
X535968Y902399D01*
Y904833D01*
G01X528468D02*
Y907350D01*
X531076Y909958D01*
Y913190D01*
G01X533468Y904833D02*
Y908750D01*
X536555Y911837D01*
X549927D01*
X553335Y908429D01*
Y905405D01*
G01X534292Y1580670D02*
X540330D01*
X543100Y1577900D01*
Y1538300D01*
X553249Y1528151D01*
X567324D01*
G01X545741Y798574D02*
Y795101D01*
X544515Y793875D01*
G01X552665Y844743D02*
Y840166D01*
X552711Y840120D01*
G01D02*
X555682Y837149D01*
Y834086D01*
G01X548665Y847893D02*
Y850399D01*
G01X552665Y847893D02*
X548665D01*
G01X540968Y883233D02*
Y878360D01*
G01X551902Y868239D02*
X555962D01*
X555995Y868206D01*
G01X543001Y874859D02*
X544358Y876216D01*
Y879788D01*
X543468Y880678D01*
Y883233D01*
G01X546940Y871389D02*
X551902D01*
G01X552292Y897425D02*
Y894540D01*
X553383Y893449D01*
G01X547843Y892969D02*
Y894934D01*
X548327Y895418D01*
Y897425D01*
G01Y900575D02*
Y905295D01*
G01X559214Y897425D02*
X552292D01*
G01X553335Y905405D02*
X552292Y904362D01*
Y900575D01*
G01X705020Y1118208D02*
X706824Y1120012D01*
Y1122878D01*
X707546Y1123600D01*
X735699D01*
X736563Y1122736D01*
Y1114106D01*
X737785Y1112884D01*
X739436D01*
X742541Y1109779D01*
Y1069880D01*
X665002Y992341D01*
X613171D01*
X611088Y990258D01*
Y987428D01*
X608642Y984982D01*
X554842D01*
X552923Y986901D01*
Y988813D01*
G01X682088Y1062847D02*
X681048D01*
X645401Y1027200D01*
X616300D01*
X612300Y1031200D01*
X586099D01*
X580699Y1025800D01*
X574099D01*
X569899Y1021600D01*
X564538D01*
X554800Y1011862D01*
Y994836D01*
X556923Y992713D01*
Y988813D01*
G01X712500Y1118208D02*
X710877Y1116585D01*
X704153D01*
X703307Y1117431D01*
Y1122423D01*
X702030Y1123700D01*
X693400D01*
X692200Y1122500D01*
Y1121301D01*
X691099Y1120200D01*
X682433D01*
X680709Y1118476D01*
Y1112392D01*
X682580Y1110521D01*
Y1069281D01*
X641699Y1028400D01*
X618400D01*
X614200Y1032600D01*
X585100D01*
X579600Y1027100D01*
X548935D01*
X545566Y1023731D01*
G01X560573Y60513D02*
X566392Y66332D01*
Y89217D01*
X561258Y94351D01*
G01X565207Y94279D02*
X571551Y87935D01*
Y68829D01*
X563433Y60711D01*
Y60438D01*
G01X564627Y196665D02*
X569357Y191935D01*
X619993D01*
X626212Y198154D01*
X665500D01*
X666989Y196665D01*
G01X564627Y192665D02*
X567077Y190215D01*
X620706D01*
X626925Y196434D01*
X663220D01*
X666989Y192665D01*
G01X564740Y186778D02*
X566457Y188495D01*
X621419D01*
X627638Y194714D01*
X659166D01*
X667102Y186778D01*
G01X562400Y818900D02*
Y823100D01*
X560800Y824700D01*
Y826212D01*
G01X562400Y818900D02*
X564300D01*
X565000Y819600D01*
Y828800D01*
X566700Y830500D01*
X572400D01*
X573300Y829600D01*
G01X572476Y845535D02*
X570140Y847871D01*
X566231D01*
G01X560800Y834086D02*
Y836708D01*
X561657Y837565D01*
X563888D01*
X564388Y838065D01*
Y839899D01*
G01D02*
Y842564D01*
X562231Y844721D01*
G01Y847871D02*
X566231D01*
G01X555995Y868206D02*
X560049D01*
X561134Y869291D01*
G01X567827Y884000D02*
X571613D01*
X572458Y884845D01*
G01X681256Y1055975D02*
X649881Y1024600D01*
X613801D01*
X609901Y1028500D01*
X592000D01*
X583100Y1019600D01*
X571699D01*
X565816Y1013717D01*
Y1007588D01*
X562983Y1004755D01*
Y990753D01*
X564923Y988813D01*
G01X693799Y1118208D02*
X690080Y1114489D01*
Y1067819D01*
X685980Y1063719D01*
Y1063379D01*
X682570Y1059969D01*
X680870D01*
X646801Y1025900D01*
X614399D01*
X610499Y1029800D01*
X586899D01*
X581399Y1024300D01*
X574700D01*
X563304Y1012904D01*
Y1007686D01*
X558893Y1003275D01*
Y994445D01*
X560923Y992415D01*
Y988813D01*
G01X568923D02*
X566800Y990936D01*
Y1001501D01*
X584799Y1019500D01*
X594600D01*
X596900Y1021800D01*
X650102D01*
X681051Y1052749D01*
X681349D01*
X684101Y1055501D01*
Y1056301D01*
X697539Y1069739D01*
Y1114468D01*
G01X690085Y1058763D02*
X649522Y1018200D01*
X592678D01*
X581778Y1007300D01*
X575699D01*
X570915Y1002516D01*
Y990821D01*
X572923Y988813D01*
G01X569135Y1214372D02*
X575961D01*
X582633Y1207700D01*
X637901D01*
X639908Y1209707D01*
X645788D01*
X646900Y1210819D01*
Y1212492D01*
X647661Y1213253D01*
X661679D01*
X663878Y1215452D01*
G01X645177D02*
Y1215331D01*
X643466Y1213620D01*
X641207D01*
X639487Y1211900D01*
X585834D01*
X579565Y1218169D01*
X564890D01*
G01X567324Y1528151D02*
X569575Y1525900D01*
X583500D01*
X587800Y1521600D01*
X598600D01*
X600300Y1523300D01*
X697497D01*
X719105Y1544908D01*
Y1634563D01*
X725506Y1640964D01*
X788541D01*
X793815Y1635690D01*
X933431D01*
X938933Y1630188D01*
Y1586675D01*
X946416Y1579192D01*
X958986D01*
X965412Y1572766D01*
Y1542975D01*
X968228Y1540159D01*
X1024654D01*
X1042834Y1521979D01*
X1065791D01*
X1086764Y1542952D01*
Y1556495D01*
X1091569Y1561300D01*
G01X565400Y1535100D02*
X566400Y1536100D01*
X585700D01*
X587100Y1534700D01*
Y1531800D01*
X585600Y1530300D01*
Y1527500D01*
X586900Y1526200D01*
X599600D01*
X601300Y1524500D01*
X696671D01*
X717908Y1545737D01*
Y1635069D01*
X724923Y1642084D01*
X789005D01*
X794279Y1636810D01*
X933895D01*
X940053Y1630652D01*
Y1587139D01*
X946880Y1580312D01*
X959450D01*
X966532Y1573230D01*
Y1543439D01*
X968536Y1541435D01*
X1025179D01*
X1043284Y1523330D01*
X1065041D01*
X1085635Y1543924D01*
Y1560075D01*
X1092228Y1566668D01*
X1102904D01*
G01X585016Y195176D02*
Y198733D01*
G01X582100Y787600D02*
Y789400D01*
X580942Y790558D01*
Y797111D01*
G01X586060D02*
Y793145D01*
G01Y804985D02*
Y808607D01*
X588501Y811048D01*
G01X577501Y816473D02*
Y811548D01*
G01D02*
Y810048D01*
X580942Y806607D01*
Y804985D01*
G01X588001Y823473D02*
X586379D01*
X582737Y819831D01*
G01X577501Y823473D02*
X581158D01*
G01X577501Y819623D02*
Y823473D01*
G01X575608Y892845D02*
X576453Y892000D01*
X580327D01*
G01X572458Y884845D02*
Y888845D01*
G01D02*
Y892845D01*
G01X708760Y1114468D02*
X712343Y1110885D01*
Y1071003D01*
X698070Y1056730D01*
X697230D01*
X693320Y1052820D01*
Y1051980D01*
X651240Y1009900D01*
X597400D01*
X594600Y1007100D01*
X588399D01*
X583059Y1001760D01*
Y990677D01*
X584923Y988813D01*
G01X701279Y1114468D02*
X705002Y1110745D01*
Y1070659D01*
X692972Y1058629D01*
Y1057973D01*
X690078Y1055079D01*
X688979D01*
X650800Y1016900D01*
X593079D01*
X574798Y998619D01*
Y990938D01*
X576923Y988813D01*
G01X687408Y1050045D02*
X652963Y1015600D01*
X593401D01*
X579052Y1001251D01*
Y990684D01*
X580923Y988813D01*
G01X697684Y1053324D02*
X652860Y1008500D01*
X597700D01*
X594300Y1005100D01*
X590053D01*
X586984Y1002031D01*
Y990752D01*
X588923Y988813D01*
G01X660138Y1211712D02*
X658087Y1209661D01*
Y1207399D01*
X656850Y1206162D01*
X651351D01*
X650709Y1205520D01*
Y1202862D01*
X650209Y1202362D01*
X647953D01*
X647017Y1201426D01*
Y1199622D01*
X645978Y1198583D01*
X638583D01*
X636500Y1196500D01*
X626987D01*
X626487Y1196000D01*
Y1174574D01*
X624313Y1172400D01*
X610368D01*
X609500Y1171532D01*
Y1169401D01*
X608499Y1168400D01*
X606892D01*
X605995Y1167503D01*
Y1165974D01*
X603659Y1163638D01*
X601963D01*
X592808Y1154483D01*
Y1154126D01*
X585010Y1146328D01*
Y1103125D01*
X590666Y1097469D01*
Y1079426D01*
X594000Y1076092D01*
Y1043034D01*
X587880Y1036914D01*
Y1034834D01*
G01X656398Y1211712D02*
X654394Y1209708D01*
X648234D01*
X647072Y1208546D01*
Y1206300D01*
X646572Y1205800D01*
X639499D01*
X637699Y1204000D01*
X579357D01*
X575620Y1207737D01*
G01X586502Y1227300D02*
Y1221524D01*
X592991Y1215035D01*
G01X667618Y1215452D02*
X666600Y1216470D01*
Y1218599D01*
X667887Y1219886D01*
Y1236613D01*
X666500Y1238000D01*
X601004D01*
X595287Y1232283D01*
X585396D01*
X583520Y1230407D01*
G01X664213Y1622402D02*
X660715Y1625900D01*
X627000D01*
X618100Y1617000D01*
Y1542600D01*
X610100Y1534600D01*
X594020D01*
X587809Y1528389D01*
G01X588501Y811048D02*
Y815973D01*
X588001Y816473D01*
G01Y819623D02*
Y823473D01*
G01X966127Y776382D02*
X959416Y783093D01*
X956537D01*
X955006Y782459D01*
X953047Y780500D01*
Y775475D01*
X949935Y772363D01*
Y744743D01*
X940082Y734890D01*
X875834D01*
X869123Y741601D01*
X826011D01*
X817907Y749705D01*
X805461D01*
X741214Y813952D01*
X732249D01*
X731067Y815134D01*
Y824420D01*
X622246Y933241D01*
X600009D01*
X597869Y935381D01*
Y947180D01*
X591754Y953295D01*
Y956979D01*
G01X616923Y988813D02*
Y987845D01*
X609625Y980547D01*
X607216D01*
X594768Y968099D01*
Y965531D01*
X601545Y958754D01*
X611839D01*
X730880Y839713D01*
Y828924D01*
G01X738681Y1144389D02*
X740350Y1142720D01*
Y1135969D01*
X741047Y1135272D01*
X744228D01*
X746200Y1133300D01*
X749580D01*
X750080Y1132800D01*
Y1069837D01*
X659166Y978923D01*
X611780D01*
X599983Y967126D01*
X598853D01*
X597556Y965829D01*
G01X716240Y1118208D02*
X718316Y1116132D01*
X720878D01*
X721921Y1115089D01*
Y1113584D01*
X722768Y1112737D01*
X724273D01*
X727304Y1109706D01*
Y1072112D01*
X722596Y1067404D01*
X721804D01*
X718996Y1064596D01*
Y1063804D01*
X659892Y1004700D01*
X602200D01*
X599005Y1001505D01*
Y990731D01*
X600923Y988813D01*
G01X716240Y1114468D02*
X719981Y1110727D01*
Y1071536D01*
X708072Y1059627D01*
X707228D01*
X703372Y1055771D01*
Y1054927D01*
X655645Y1007200D01*
X598600D01*
X594339Y1002939D01*
X592640D01*
X590785Y1001084D01*
Y990951D01*
X592923Y988813D01*
G01X722820Y1064608D02*
X661512Y1003300D01*
X606262D01*
X602889Y999927D01*
Y990847D01*
X604923Y988813D01*
G01X707252Y1055787D02*
X657465Y1006000D01*
X599800D01*
X594916Y1001116D01*
Y990820D01*
X596923Y988813D01*
G01X613461Y1160650D02*
Y1155160D01*
X612041Y1153740D01*
X611141D01*
X609536Y1152135D01*
Y1151136D01*
X608266Y1149866D01*
X599390D01*
X597760Y1148236D01*
Y1083209D01*
X600200Y1080769D01*
Y1056939D01*
X603682Y1053457D01*
G01X613676Y1164560D02*
X610162Y1161046D01*
Y1159462D01*
X608198Y1157498D01*
X607281D01*
X603918Y1154135D01*
X598974D01*
X595790Y1150951D01*
Y1080918D01*
X598121Y1078587D01*
Y1054897D01*
X610564Y1042454D01*
Y1039491D01*
X607993Y1036920D01*
G01X613676Y1169100D02*
X613276Y1168700D01*
X611190D01*
X609717Y1167227D01*
Y1166016D01*
X605267Y1161566D01*
X603758D01*
X602384Y1160192D01*
Y1157562D01*
X601610Y1156788D01*
X598841D01*
X593820Y1151767D01*
Y1079462D01*
X596088Y1077194D01*
Y1052250D01*
X606434Y1041904D01*
G01X622736Y1155610D02*
Y1155383D01*
X621053Y1153700D01*
X614301D01*
X613400Y1152799D01*
Y1151499D01*
X609635Y1147734D01*
Y1147180D01*
X608479Y1146024D01*
X603357D01*
X602281Y1144948D01*
Y1059406D01*
X606864Y1054823D01*
Y1049703D01*
X610501Y1046066D01*
X615783D01*
X617894Y1043955D01*
G01X641437Y1215452D02*
X641289Y1215600D01*
X596787D01*
X596022Y1214835D01*
X593191D01*
X592991Y1215035D01*
G01X648917Y1215452D02*
X646982Y1217387D01*
X639013D01*
X637100Y1219300D01*
X594951D01*
X594183Y1220068D01*
G01X597026Y1224472D02*
X593519D01*
G01X652657Y1219192D02*
Y1222044D01*
X651901Y1222800D01*
X597449D01*
X597026Y1223223D01*
Y1224472D01*
G01X656398Y1215452D02*
Y1228901D01*
X655099Y1230200D01*
X595478D01*
X594680Y1229402D01*
X592885D01*
G01X592634Y1234921D02*
Y1237647D01*
X596487Y1241500D01*
X673786D01*
X675098Y1240188D01*
Y1215452D01*
G01X621727Y1556800D02*
X619611Y1554684D01*
Y1542039D01*
X609705Y1532133D01*
X595809D01*
G01X608965Y966414D02*
Y963352D01*
X733105Y839212D01*
Y831987D01*
X733680Y831412D01*
Y828977D01*
G01X742421Y1114468D02*
X746172Y1110717D01*
Y1070619D01*
X664366Y988813D01*
X616923D01*
G01X727460Y1114468D02*
X728628D01*
X730533Y1112563D01*
X731638D01*
X734961Y1109240D01*
Y1071534D01*
X664332Y1000905D01*
X607685D01*
X607061Y1000281D01*
Y990675D01*
X608923Y988813D01*
G01X708760Y1118208D02*
X710557Y1120005D01*
X731824D01*
X733169Y1118660D01*
Y1113630D01*
X734329Y1112470D01*
X735416D01*
X738632Y1109254D01*
Y1069766D01*
X664846Y995980D01*
X614803D01*
X612923Y997860D01*
G01X613217Y1148530D02*
X611628Y1146941D01*
Y1144790D01*
X609238Y1142400D01*
X606965D01*
X605835Y1141270D01*
Y1059523D01*
X610780Y1054578D01*
Y1051037D01*
G01X613386Y1135334D02*
X609325Y1131273D01*
Y1059654D01*
X614533Y1054446D01*
Y1052384D01*
X617634Y1049283D01*
G01X612955Y1062941D02*
Y1069425D01*
X613270Y1069740D01*
Y1122269D01*
X614546Y1123545D01*
X616112D01*
X617126Y1124559D01*
Y1135334D01*
G01X620866Y1138484D02*
X617126D01*
G01X613386Y1143390D02*
Y1138484D01*
G01X622736Y1151870D02*
X620566Y1149700D01*
X617537D01*
X616367Y1148530D01*
G01X626476Y1151870D02*
X624388Y1149782D01*
X622082D01*
X620925Y1148625D01*
Y1147158D01*
X620176Y1146409D01*
X616405D01*
X613386Y1143390D01*
G01X624606Y1164960D02*
X621980D01*
X617840Y1169100D01*
X616826D01*
G01X626476Y1155610D02*
X624786Y1157300D01*
X618077D01*
X616611Y1158766D01*
Y1160650D01*
G01X622736Y1159350D02*
Y1161838D01*
X620014Y1164560D01*
X616826D01*
G01X648917Y1140649D02*
X647047Y1138779D01*
Y1113404D01*
X646241Y1112598D01*
X629598D01*
X628400Y1111400D01*
Y1105617D01*
X627900Y1105117D01*
X625235D01*
X624606Y1104488D01*
Y1036876D01*
X621592Y1033862D01*
G01X652657Y1140649D02*
Y1139500D01*
X654183Y1137974D01*
Y1131886D01*
X653539Y1131242D01*
X651842D01*
X650787Y1130187D01*
Y1113086D01*
X649200Y1111499D01*
Y1107819D01*
X648581Y1107200D01*
X634669D01*
X634000Y1106531D01*
Y1043003D01*
X621479Y1030482D01*
G01X620866Y1138484D02*
X623259D01*
X624594Y1139819D01*
Y1146271D01*
G01D02*
X622736Y1148129D01*
G01X633136Y1172500D02*
X632400Y1171764D01*
Y1169900D01*
X631393Y1168893D01*
X627272D01*
X626073Y1170092D01*
G01X624606Y1164960D02*
X626476Y1163090D01*
Y1159350D01*
G01X642414Y545528D02*
X644058D01*
X644619Y544967D01*
X647897D01*
G01D02*
Y542500D01*
X648397Y542000D01*
X666086D01*
X669546Y545460D01*
Y551894D01*
G01X651047Y544967D02*
X654897D01*
G01X650611Y618400D02*
Y617000D01*
X651111Y616500D01*
X656086D01*
X657302Y615284D01*
X665147D01*
X666180Y616317D01*
G01X643271Y1135040D02*
Y1135075D01*
X641437Y1136909D01*
G01X647277Y1193011D02*
Y1193540D01*
G01D02*
X645900Y1194917D01*
X639565D01*
G01X650787Y1217322D02*
X652657Y1215452D01*
G01X662935Y60513D02*
X668754Y66332D01*
Y89217D01*
X663620Y94351D01*
G01X665795Y60438D02*
Y60711D01*
X673913Y68829D01*
Y87935D01*
X667569Y94279D01*
G01X666989Y196665D02*
X671719Y191935D01*
X722355D01*
X729091Y198671D01*
X753182D01*
G01X666989Y192665D02*
X669389Y190265D01*
X670956D01*
X671006Y190215D01*
X723068D01*
X729362Y196509D01*
X765507D01*
X769351Y192665D01*
G01X667102Y186778D02*
X668869Y188545D01*
X670243D01*
X670293Y188495D01*
X723781D01*
X730075Y194789D01*
X761453D01*
X769464Y186778D01*
G01X654897Y544967D02*
Y549911D01*
X656026Y551040D01*
G01D02*
X657581Y552595D01*
Y577937D01*
G01X653761Y602400D02*
X656057D01*
X660586Y606929D01*
G01X653761Y598400D02*
X661487D01*
X665086Y601999D01*
Y604567D01*
G01X653761Y594400D02*
X655686D01*
X657330Y592756D01*
X662842D01*
X665586Y595500D01*
G01X653761Y610400D02*
X655367D01*
X657559Y612592D01*
X660827D01*
G01X653761Y614400D02*
Y610400D01*
G01Y606400D02*
X655986D01*
X659658Y610072D01*
X666244D01*
G01X653761Y618400D02*
X660546D01*
G01X663878Y1211712D02*
X665748Y1213582D01*
X673228D01*
G01X662008Y1217322D02*
X660138Y1215452D01*
G01X677586Y536425D02*
Y535000D01*
X682586Y530000D01*
G01X669546Y554847D02*
X672086D01*
X672586Y554347D01*
Y544000D01*
G01D02*
Y541000D01*
X674011Y539575D01*
X677586D01*
G01X680586Y568000D02*
X676632Y564046D01*
Y557800D01*
G01X693799Y1114468D02*
X693949Y1114318D01*
Y1068668D01*
X681256Y1055975D01*
G01X697539Y1118208D02*
X695693Y1120054D01*
X692997D01*
X689391Y1116448D01*
X685949D01*
X684449Y1114948D01*
Y1112050D01*
X686133Y1110366D01*
Y1066892D01*
X682088Y1062847D01*
G01X673228Y1213582D02*
X680709D01*
X681004Y1213877D01*
X681039D01*
G01X671358Y1211712D02*
X669488Y1209842D01*
G01Y1217322D02*
X671358Y1215452D01*
G01X696944Y766471D02*
Y762971D01*
G01D02*
X693999D01*
X692356Y764614D01*
G01X696944Y753471D02*
Y756971D01*
G01D02*
X694601D01*
X691991Y759581D01*
G01X696930Y780659D02*
X693840D01*
X692155Y778974D01*
G01X696930Y784659D02*
Y780659D01*
G01Y771159D02*
Y775159D01*
G01D02*
X693931D01*
X692221Y773449D01*
G01X705020Y1114468D02*
X708751Y1110737D01*
Y1070364D01*
X707914Y1069527D01*
X706890D01*
X687408Y1050045D01*
G01X697684Y1053324D02*
X713360Y1069000D01*
X714988D01*
X716291Y1070303D01*
Y1110677D01*
X712500Y1114468D01*
G01X701279Y1118208D02*
X699409Y1116338D01*
Y1113490D01*
X701409Y1111490D01*
Y1070087D01*
X690085Y1058763D01*
G01X699409Y1217322D02*
X702379D01*
X705001Y1219944D01*
Y1237521D01*
X705501Y1238021D01*
X790901D01*
X794971Y1233951D01*
G01X697539Y1215452D02*
Y1217670D01*
X699318Y1219449D01*
X700383D01*
X701330Y1220396D01*
Y1241153D01*
X701830Y1241653D01*
X796144D01*
X800262Y1237535D01*
G01X693799Y1215452D02*
Y1262226D01*
X694922Y1263349D01*
X726823D01*
G01X693799Y1211712D02*
X695617Y1213530D01*
X739487D01*
X740548Y1212469D01*
Y1210739D01*
X741487Y1209800D01*
X744699D01*
X746485Y1208014D01*
X788208D01*
G01X701279Y1215452D02*
X702445D01*
X705811Y1218818D01*
X707450D01*
X708712Y1220080D01*
Y1233930D01*
X709212Y1234430D01*
X789161D01*
X802394Y1221197D01*
G01X812405Y1228760D02*
X779965Y1261200D01*
X699786D01*
X697620Y1259034D01*
Y1219273D01*
X695669Y1217322D01*
G01X707492Y1633514D02*
X703104Y1629126D01*
Y1595998D01*
X698858Y1591752D01*
Y1591693D01*
G01X701899Y1633858D02*
Y1610089D01*
X698858Y1607048D01*
G01X712692Y356779D02*
X715655Y359742D01*
Y397898D01*
X719857Y402100D01*
Y412884D01*
X715655Y417086D01*
Y438323D01*
G01X715733Y447055D02*
Y443087D01*
X718805Y440015D01*
Y438323D01*
G01X711598D02*
X715655D01*
G01X709781Y442956D02*
X709682Y443055D01*
Y452129D01*
X713524Y455971D01*
X726293D01*
X726768Y456446D01*
Y458714D01*
G01X729721Y451628D02*
Y449916D01*
X728709Y448904D01*
X720172D01*
X718323Y447055D01*
X715733D01*
G01X707252Y1055787D02*
X721165Y1069700D01*
X722287D01*
X723593Y1071006D01*
Y1109747D01*
X719980Y1113360D01*
Y1114468D01*
G01X791986Y1224512D02*
X789964Y1226534D01*
X716987D01*
X715987Y1225534D01*
Y1218939D01*
X712500Y1215452D01*
G01X705019Y1215451D02*
X706842Y1217274D01*
X710187D01*
X712442Y1219529D01*
Y1229455D01*
X713450Y1230463D01*
X786282D01*
X788102Y1232283D01*
G01X713002Y1637887D02*
Y1634103D01*
X711275Y1632376D01*
Y1583022D01*
X708923Y1580670D01*
X707520D01*
G01X731511Y384500D02*
Y381113D01*
G01X732674Y451628D02*
Y453964D01*
X737282Y458572D01*
X739316D01*
G01X720996Y442856D02*
X725624D01*
X725874Y442606D01*
G01Y446606D02*
X722108D01*
X722097Y446595D01*
G01X736183Y467367D02*
X733430D01*
G01X788600Y1006923D02*
X785328Y1003651D01*
X777593D01*
X771660Y997718D01*
Y903662D01*
X786720Y888602D01*
Y869720D01*
X733000Y816000D01*
G01X722820Y1064608D02*
X727312Y1069100D01*
X730188D01*
X731271Y1070183D01*
Y1109330D01*
X727997Y1112604D01*
X726502D01*
X725609Y1113497D01*
Y1115776D01*
X725033Y1116352D01*
X723028D01*
X721172Y1118208D01*
X719980D01*
G01Y1215452D02*
Y1222560D01*
X720481Y1223061D01*
X764073D01*
X764941Y1222193D01*
Y1220041D01*
X765750Y1219232D01*
X786497D01*
X788327Y1221062D01*
G01X817360Y1228226D02*
X812206Y1233380D01*
X809635D01*
X779666Y1263349D01*
X726823D01*
G01X741161Y388000D02*
X745586D01*
G01D02*
X747086Y386500D01*
X747516D01*
X749606Y384410D01*
G01X734661Y384500D02*
X738011D01*
G01D02*
Y381075D01*
X739586Y379500D01*
X750238D01*
X752785Y382047D01*
G01X734661Y388000D02*
Y393633D01*
G01X738011Y388000D02*
X734661D01*
G01X760794Y389912D02*
X756848Y393858D01*
X749444D01*
G01X739316Y458572D02*
Y463235D01*
G01X736166D02*
Y467350D01*
X736183Y467367D01*
G01X736000Y864266D02*
X764882Y893148D01*
Y1106300D01*
X765382Y1106800D01*
X767250D01*
X768700Y1108250D01*
Y1136999D01*
X766732Y1138967D01*
Y1142519D01*
G01X755512Y1112598D02*
X757382Y1110728D01*
Y1069655D01*
X741180Y1053453D01*
Y997023D01*
X742407Y995796D01*
Y988452D01*
G01X755212Y1139074D02*
X764025D01*
X765100Y1137999D01*
Y1111249D01*
X764526Y1110675D01*
X762426D01*
X761251Y1109500D01*
Y1069125D01*
X743062Y1050936D01*
Y1004460D01*
G01X742421Y1144389D02*
X744272Y1142538D01*
Y1139670D01*
X746942Y1137000D01*
X755900D01*
X757300Y1135600D01*
Y1114386D01*
X755512Y1112598D01*
G01X755212Y1149704D02*
X751736D01*
X751441Y1149999D01*
X744291D01*
G01D02*
X742421Y1148129D01*
G01X755212Y1142224D02*
X753342D01*
X753047Y1142519D01*
X748031D01*
G01D02*
X746161Y1140649D01*
G01X753099Y1185514D02*
X751541Y1183956D01*
X748531D01*
G01X753537Y1178467D02*
X752379Y1179625D01*
X748531D01*
G01X742421Y1207972D02*
X746093Y1204300D01*
X788487D01*
X790587Y1202200D01*
G01X738681Y1207972D02*
X740487Y1206166D01*
Y1202700D01*
X740987Y1202200D01*
X743800D01*
X745500Y1200500D01*
X786387D01*
X790749Y1196138D01*
G01X742421Y1215452D02*
X746002Y1211871D01*
X788438D01*
X796777Y1206299D01*
G01X738681Y1215452D02*
X740551Y1217322D01*
X744478D01*
X746400Y1215400D01*
X796080D01*
X809600Y1201880D01*
Y1199316D01*
X811290Y1197626D01*
X816284D01*
G01X749439Y1458777D02*
X751293D01*
X776658Y1433412D01*
X779123D01*
X781569Y1435858D01*
X787494D01*
X791540Y1431812D01*
X793472D01*
X797173Y1428111D01*
Y1422260D01*
X790972Y1416059D01*
Y1410831D01*
X797173Y1404630D01*
Y1373317D01*
X824053Y1346437D01*
X874057D01*
X880303Y1352683D01*
X990340D01*
X994743Y1357086D01*
X1024163D01*
X1043475Y1376398D01*
Y1399243D01*
X1063141Y1418909D01*
X1357509D01*
X1361500Y1422900D01*
X1365625D01*
G01X806209Y1429135D02*
X804414Y1430930D01*
X801428D01*
X799932Y1429434D01*
X797752D01*
X794074Y1433112D01*
X792467D01*
X788200Y1437379D01*
X774655D01*
X750964Y1461070D01*
Y1465611D01*
X740529Y1476046D01*
Y1524112D01*
X740530Y1524113D01*
G01X765982Y94351D02*
X771418Y88915D01*
Y66634D01*
X765297Y60513D01*
G01X760574Y178560D02*
X756970Y182164D01*
Y185997D01*
X750667Y192300D01*
G01X753182Y198671D02*
X755675D01*
X756117Y198229D01*
X767787D01*
X774081Y191935D01*
X824717D01*
X831163Y198381D01*
X869997D01*
X871713Y196665D01*
G01X756086Y377912D02*
X760794D01*
G01Y385912D02*
X755210Y391496D01*
X755086D01*
G01X760794Y381912D02*
X756206Y386500D01*
X756086D01*
G01X760794Y393924D02*
Y397912D01*
G01D02*
X756174D01*
G01X760794Y409924D02*
X758010D01*
X757086Y409000D01*
X755086D01*
G01X760794Y405924D02*
X755510D01*
X753086Y403500D01*
G01X760794Y401924D02*
X756011D01*
X752670Y398583D01*
X751086D01*
G01X766732Y1142519D02*
Y1145583D01*
X765761Y1146554D01*
X755212D01*
G01X769931Y94279D02*
X776577Y87633D01*
Y69131D01*
X768157Y60711D01*
Y60438D01*
G01X769351Y192665D02*
X771751Y190265D01*
X773318D01*
X773368Y190215D01*
X825430D01*
X831876Y196661D01*
X867717D01*
X871713Y192665D01*
G01X769464Y186778D02*
X771231Y188545D01*
X772605D01*
X772655Y188495D01*
X826143D01*
X832589Y194941D01*
X863663D01*
X871826Y186778D01*
G01X814835Y1134729D02*
Y1120133D01*
X831685Y1103283D01*
Y1056388D01*
X807793Y1032496D01*
X782927D01*
X779072Y1028641D01*
Y1020872D01*
X783600Y1016344D01*
X786860D01*
X794958Y1008246D01*
Y1004114D01*
X778244Y987400D01*
Y906391D01*
X793304Y891331D01*
Y859327D01*
X806837Y845794D01*
X807153D01*
X812070Y840877D01*
X814299D01*
G01X806835Y1134729D02*
Y1122674D01*
X807368Y1122141D01*
X808167D01*
X808700Y1121608D01*
Y1120854D01*
X808167Y1120321D01*
X807368D01*
X806835Y1119788D01*
Y1093386D01*
X790001Y1076552D01*
Y1070997D01*
X775296Y1056292D01*
Y1020802D01*
X781840Y1014258D01*
X786371D01*
X793144Y1007485D01*
Y1004866D01*
X776430Y988152D01*
Y905639D01*
X791490Y890579D01*
Y857466D01*
X813810Y835146D01*
X813887D01*
G01X813000Y805000D02*
X808500Y809500D01*
Y815000D01*
X789820Y833680D01*
Y856703D01*
X789770Y856753D01*
Y889866D01*
X774710Y904926D01*
Y988865D01*
X791424Y1005579D01*
Y1006772D01*
X785658Y1012538D01*
X781127D01*
X773576Y1020089D01*
Y1057386D01*
X788281Y1072091D01*
Y1077265D01*
X798498Y1087482D01*
Y1145271D01*
X797160Y1146609D01*
G01X843665Y907110D02*
X839443Y902888D01*
X828667D01*
X827630Y903925D01*
X819589D01*
X818531Y902867D01*
X803959D01*
X780000Y926826D01*
Y986723D01*
X791456Y998179D01*
X803102D01*
X803602Y998679D01*
Y1002089D01*
G01X806161D02*
Y998417D01*
X804203Y996459D01*
X792169D01*
X781800Y986090D01*
Y928416D01*
X794733Y915483D01*
G01X796338Y1138130D02*
Y1087753D01*
X786409Y1077824D01*
Y1072482D01*
X771423Y1057496D01*
Y1019594D01*
X780351Y1010666D01*
X784857D01*
X788600Y1006923D01*
G01X780162Y1412848D02*
Y1411400D01*
X791059Y1400503D01*
Y1376093D01*
X821835Y1345317D01*
X874521D01*
X880767Y1351563D01*
X990804D01*
X995207Y1355966D01*
X1025644D01*
X1045502Y1375824D01*
Y1398784D01*
X1064507Y1417789D01*
X1376946D01*
X1379858Y1420701D01*
G01X777260Y1446237D02*
X775390D01*
X772563Y1449064D01*
Y1452361D01*
X774367Y1454165D01*
G01X790296Y1463459D02*
X788495D01*
X787863Y1464091D01*
X779245D01*
X772770Y1457616D01*
Y1454714D01*
X773319Y1454165D01*
X774367D01*
G01X787038Y1460533D02*
X786150Y1459645D01*
Y1459103D01*
X785496Y1458449D01*
Y1456409D01*
X782322Y1453235D01*
X780631D01*
G01X836258Y906510D02*
Y905957D01*
X834978Y904677D01*
X829497D01*
X828391Y905783D01*
X819013D01*
X817978Y904748D01*
X805468D01*
X794733Y915483D01*
G01X808720Y1002089D02*
Y998029D01*
X805430Y994739D01*
X792883D01*
X783700Y985556D01*
Y930902D01*
X804436Y910166D01*
X806168D01*
G01X815357Y920026D02*
X805364D01*
X792575Y932815D01*
G01X809892Y915705D02*
X804219D01*
X797178Y922746D01*
G01X811279Y1002089D02*
Y997963D01*
X806335Y993019D01*
X793597D01*
X785600Y985022D01*
Y934324D01*
X797178Y922746D01*
G01X818957Y1002089D02*
Y997257D01*
X809559Y987859D01*
X795959D01*
X791300Y983200D01*
Y942718D01*
X800018Y934000D01*
G01X813839Y1002089D02*
Y997539D01*
X807599Y991299D01*
X794311D01*
X787700Y984688D01*
Y937690D01*
X792575Y932815D01*
G01X816398Y1002089D02*
Y997293D01*
X808684Y989579D01*
X795025D01*
X789420Y983974D01*
Y940284D01*
X803507Y926197D01*
G01X844381Y923644D02*
Y927461D01*
X843086Y928756D01*
X838867D01*
X837041Y926930D01*
X815248D01*
X796079Y946099D01*
Y982581D01*
X797917Y984419D01*
X811147D01*
X824075Y997347D01*
Y1002089D01*
G01X840381Y923644D02*
X838815Y925210D01*
X813359D01*
X794281Y944288D01*
Y983748D01*
X796672Y986139D01*
X810314D01*
X821516Y997341D01*
Y1002089D01*
G01X793810Y1013122D02*
X798484Y1008448D01*
Y1002089D01*
G01X783659Y1019337D02*
X787631D01*
G01D02*
Y1019301D01*
X793810Y1013122D01*
G01X791686Y1019337D02*
X795631D01*
G01X801043Y1010773D02*
Y1012985D01*
X795631Y1018397D01*
Y1019337D01*
G01X790749Y1196138D02*
X789393Y1194782D01*
Y1190692D01*
X791740Y1188345D01*
X798542D01*
G01X807489Y1201043D02*
Y1197479D01*
X806989Y1196979D01*
X802108D01*
X793097Y1205990D01*
X788208Y1208014D01*
G01X804452Y1199814D02*
X800363Y1203903D01*
X796777Y1206299D01*
G01X794533Y1195766D02*
Y1198254D01*
X790587Y1202200D01*
G01X791986Y1224512D02*
X815455Y1201043D01*
G01X811485D02*
Y1202893D01*
X793316Y1221062D01*
X788327D01*
G01X794971Y1233951D02*
X809027Y1219895D01*
G01X819489Y1201039D02*
X817253Y1203275D01*
X817110D01*
X788102Y1232283D01*
G01X790989Y1455695D02*
X791795Y1454889D01*
Y1454566D01*
X785636Y1448407D01*
Y1444735D01*
X783267Y1442366D01*
Y1442282D01*
G01X799269Y1460979D02*
X800110Y1461820D01*
Y1468450D01*
X797318Y1471242D01*
G01X870035Y801032D02*
Y809596D01*
X858303Y821328D01*
X846431D01*
X845454Y822305D01*
X836156D01*
X832964Y825497D01*
X830412D01*
X818060Y837849D01*
Y840432D01*
X808759Y849733D01*
Y892881D01*
X816565Y900687D01*
X819515D01*
X820983Y902155D01*
X826996D01*
X828414Y900737D01*
X853292D01*
X855524Y898505D01*
G01X974985Y1290950D02*
X979607D01*
X981267Y1289290D01*
X981706Y1288230D01*
X982512Y1287424D01*
X1019157Y1198952D01*
Y1121393D01*
X1014186Y1116422D01*
X1006313Y1097415D01*
X983440Y1042193D01*
Y1005789D01*
X967763Y967939D01*
X930451Y930627D01*
X882582D01*
X868784Y916829D01*
Y905048D01*
X859883Y896147D01*
X856055D01*
X855710Y896492D01*
X852456D01*
X850616Y898332D01*
X834554D01*
X832562Y896340D01*
X829168D01*
X827112Y898396D01*
Y899142D01*
X825699Y900555D01*
X822402D01*
X820724Y898877D01*
X817018D01*
X810359Y892218D01*
Y852992D01*
X813838Y849513D01*
X815157D01*
X819926Y844744D01*
Y838246D01*
X825126Y833046D01*
X830014D01*
G01X812440Y862306D02*
X815042Y859704D01*
Y851866D01*
X822141Y844767D01*
Y837615D01*
X824950Y834806D01*
X827527D01*
X829700Y836979D01*
X836324D01*
X836341Y836962D01*
X838194D01*
G01X813819Y869079D02*
X813911Y869171D01*
Y872720D01*
X813819Y872812D01*
G01Y876605D02*
Y872812D01*
G01X814080Y864464D02*
X813819Y864725D01*
Y869079D01*
G01X827003Y880390D02*
X825366D01*
X824714Y879738D01*
X823303D01*
X819455Y883586D01*
X812219D01*
G01X853675Y875468D02*
Y874376D01*
X852885Y873586D01*
X836690D01*
X833671Y876605D01*
X832800D01*
X831314Y878091D01*
X822585D01*
X819842Y880834D01*
X812575D01*
G01X832258Y906474D02*
X830918Y907814D01*
X826318D01*
X823966Y910166D01*
X806168D01*
G01X817884Y915425D02*
X817604Y915705D01*
X813042D01*
G01X829995Y923151D02*
X829656Y923490D01*
X810528D01*
X800018Y934000D01*
G01X822773Y921393D02*
X822396Y921770D01*
X807934D01*
X803507Y926197D01*
G01X849205Y924129D02*
Y925463D01*
X844187Y930481D01*
X829373D01*
X827732Y928840D01*
X815827D01*
X814596Y930071D01*
Y932711D01*
X817229Y935344D01*
G01X801043Y980041D02*
Y974395D01*
X817383Y958055D01*
X821182D01*
X826319Y952918D01*
Y947131D01*
X820960Y941772D01*
Y939075D01*
X817229Y935344D01*
G01X822829Y960614D02*
X818443D01*
X803602Y975455D01*
Y980041D01*
G01X818070Y972723D02*
X809085D01*
X806161Y975647D01*
Y980041D01*
G01X799631Y1019337D02*
X803602Y1015366D01*
Y1002089D01*
G01X801043Y1010773D02*
Y1002089D01*
G01X807673Y1019337D02*
X808720Y1018290D01*
Y1002089D01*
G01X815673Y1019337D02*
Y1010807D01*
X813839Y1008973D01*
Y1002089D01*
G01X811673Y1019337D02*
X811279Y1018943D01*
Y1002089D01*
G01X803673Y1019337D02*
X806161Y1016849D01*
Y1002089D01*
G01X807020Y1217900D02*
X805691D01*
X802394Y1221197D01*
G01X800262Y1237535D02*
X812302Y1225495D01*
Y1223170D01*
G01X812405Y1228760D02*
X815149Y1226016D01*
G01X806148Y1375208D02*
X831007Y1350349D01*
X872435D01*
X878681Y1356595D01*
X988393D01*
X994256Y1362458D01*
X999842D01*
X1004233Y1366849D01*
X1009975D01*
X1011695Y1368569D01*
Y1380310D01*
X997873Y1394132D01*
X995480D01*
X995412Y1394200D01*
X993775D01*
G01X810204Y1401661D02*
Y1395680D01*
X801958Y1387434D01*
Y1373488D01*
X826217Y1349229D01*
X872899D01*
X879145Y1355475D01*
X988857D01*
X994720Y1361338D01*
X1000306D01*
X1004697Y1365729D01*
X1010439D01*
X1019391Y1374681D01*
Y1377061D01*
G01X833877Y1425782D02*
X829780Y1421685D01*
X821570D01*
X804654Y1404769D01*
G01X806194Y1425152D02*
Y1429120D01*
X806209Y1429135D01*
G01X812104Y1426483D02*
X809452Y1429135D01*
X806209D01*
G01X799343Y1436240D02*
Y1438040D01*
X799319Y1438064D01*
Y1439662D01*
X800277Y1440620D01*
X800467D01*
X800607Y1440760D01*
G01X803269Y1436240D02*
X799343D01*
G01X802684Y1465549D02*
X802419Y1465284D01*
Y1460979D01*
G01X801998Y1470991D02*
X806169D01*
X807576Y1469584D01*
G01X835000Y759075D02*
X827575D01*
X824500Y756000D01*
G01X817584Y764219D02*
X824781D01*
X826075Y762925D01*
X835000D01*
G01Y777075D02*
X827575D01*
X824500Y774000D01*
G01Y782500D02*
X826075Y780925D01*
X835000D01*
G01Y795075D02*
X827102D01*
X824342Y792315D01*
G01X824500Y800500D02*
X826075Y798925D01*
X835000D01*
G01X818500Y810135D02*
X828135D01*
X831075Y813075D01*
X835000D01*
G01X817845Y817879D02*
X823772D01*
X826075Y816925D01*
X835000D01*
G01X829946Y829788D02*
X831612D01*
X832506Y828894D01*
X841183D01*
X845884Y833595D01*
Y835459D01*
G01X831583Y853454D02*
Y849873D01*
X830696Y848986D01*
G01X828835Y854920D02*
X827037Y853122D01*
Y849495D01*
X827546Y848986D01*
G01X833327Y855560D02*
X833705Y855938D01*
Y858743D01*
X832964Y859484D01*
X831299D01*
G01X828835Y854920D02*
Y855541D01*
X831208Y857914D01*
Y859393D01*
X831299Y859484D01*
G01X842648Y875476D02*
Y876367D01*
X841589Y877426D01*
X839275D01*
X838378Y876529D01*
X837519D01*
X834815Y879233D01*
X833138D01*
X831981Y880390D01*
X830153D01*
G01X829852Y886930D02*
X825523D01*
X825490Y886897D01*
G01D02*
X824238D01*
X823407Y887728D01*
Y892170D01*
X821692Y893885D01*
X821572D01*
G01X834465Y884538D02*
X832073Y886930D01*
X829852D01*
G01X818507Y920026D02*
X820519D01*
X823771Y916774D01*
X825336D01*
G01X829848Y914211D02*
X829296D01*
X828475Y915032D01*
Y918757D01*
X825923Y921309D01*
Y921393D01*
G01X829995Y920001D02*
X831057Y918939D01*
Y916745D01*
G01X891367Y941126D02*
X881700D01*
X872354Y931780D01*
X846986D01*
X844330Y934436D01*
X832935D01*
X829617Y937754D01*
Y939583D01*
G01X822829Y960614D02*
X823440D01*
X830308Y953746D01*
Y947164D01*
X827108Y943964D01*
Y938930D01*
X819325Y931147D01*
X816519D01*
G01X829494Y972782D02*
X825205D01*
X825146Y972723D01*
G01D02*
X818070D01*
G01X819449Y1134534D02*
Y1131886D01*
X817006Y1129443D01*
Y1120756D01*
X833589Y1104173D01*
Y1023909D01*
X834033Y1023465D01*
Y1021509D01*
X833589Y1021065D01*
Y996749D01*
X834760Y995578D01*
Y991984D01*
X833589Y990813D01*
Y982720D01*
X828964Y978095D01*
Y977780D01*
G01X823673Y1019337D02*
Y1013339D01*
X818957Y1008623D01*
Y1002089D01*
G01X819673Y1019337D02*
Y1011893D01*
X816398Y1008618D01*
Y1002089D01*
G01X824075D02*
Y1004861D01*
X829517Y1010303D01*
G01X821516Y1002089D02*
Y1007550D01*
X823549Y1009583D01*
G01X827673Y1019337D02*
Y1013707D01*
X823549Y1009583D01*
G01X831673Y1019337D02*
Y1012459D01*
X829517Y1010303D01*
G01X891107Y1314305D02*
X881314Y1304512D01*
Y1295772D01*
X854920Y1269378D01*
X854397D01*
X853525Y1270250D01*
X852861D01*
X851778Y1269167D01*
Y1268503D01*
X852650Y1267631D01*
Y1267108D01*
X851426Y1265884D01*
X850903D01*
X850031Y1266756D01*
X849367D01*
X848284Y1265673D01*
Y1265009D01*
X849156Y1264137D01*
Y1263614D01*
X847932Y1262390D01*
X847409D01*
X846537Y1263262D01*
X845873D01*
X844790Y1262179D01*
Y1261515D01*
X845662Y1260643D01*
Y1260120D01*
X831133Y1245591D01*
Y1119102D01*
X840835Y1109400D01*
Y1011599D01*
X840935Y1011499D01*
G01X835431Y977775D02*
X836612Y978956D01*
Y1103583D01*
X819026Y1121169D01*
Y1128137D01*
G01X816284Y1197626D02*
X821523D01*
X823489Y1199592D01*
Y1200969D01*
G01X833877Y1425782D02*
Y1438320D01*
X831508Y1440689D01*
X826204D01*
G01X826219Y1455244D02*
X828850Y1457875D01*
Y1461228D01*
X831312Y1463690D01*
G01X826341Y1451236D02*
X828734Y1448843D01*
X833898D01*
G01X849500Y758500D02*
X846500D01*
X844500Y760500D01*
X840425D01*
X839000Y759075D01*
G01X849500Y763500D02*
X846499D01*
X845924Y762925D01*
X839000D01*
G01X835000Y766075D02*
X839000D01*
G01D02*
X839924D01*
X840999Y765000D01*
X845000D01*
X846075Y766075D01*
X854758D01*
G01X839000Y755925D02*
X852710D01*
G01X835000D02*
X839000D01*
G01X849500Y776500D02*
X846500D01*
X844500Y778500D01*
X840425D01*
X839000Y777075D01*
G01X849500Y781500D02*
X845075D01*
X844500Y780925D01*
X839000D01*
G01X835000Y773925D02*
X839000D01*
G01D02*
X842688D01*
X842803Y774040D01*
X851469D01*
X851584Y773925D01*
G01X849500Y794500D02*
X846500D01*
X844500Y796500D01*
X840425D01*
X839000Y795075D01*
G01X849500Y799500D02*
X845075D01*
X844500Y798925D01*
X839000D01*
G01X835000Y791925D02*
X839000D01*
G01D02*
X844520D01*
G01D02*
X854925D01*
X859000Y796000D01*
G01X835000Y784075D02*
X839000D01*
G01X853837D02*
X839000D01*
G01X849500Y812500D02*
X846500D01*
X844500Y814500D01*
X840425D01*
X839000Y813075D01*
G01X835000Y809925D02*
X839000D01*
G01D02*
X852250D01*
G01X839000Y802075D02*
X853837D01*
G01X835000D02*
X839000D01*
G01X849500Y817500D02*
X845075D01*
X844500Y816925D01*
X839000D01*
G01X846773Y827419D02*
X839912D01*
X836894Y824401D01*
G01X835000Y820075D02*
X839000D01*
G01D02*
X839590Y819485D01*
X852366D01*
X853851Y818000D01*
G01X845884Y839459D02*
X848384D01*
G01X845884D02*
Y843082D01*
X845476Y843490D01*
X843839D01*
G01X845884Y835459D02*
X846382Y835957D01*
Y836213D01*
X847660Y837491D01*
X862873D01*
X866811Y841429D01*
X869609D01*
G01X845884Y851459D02*
X843839Y849414D01*
Y847531D01*
G01X851184Y863459D02*
X849232Y861507D01*
X844602D01*
X843312Y862797D01*
Y863413D01*
G01X839530Y859408D02*
Y859678D01*
X838121Y861087D01*
X836644D01*
G01X853684Y859459D02*
X850004D01*
X846336Y855791D01*
Y855459D01*
G01X842734Y851459D02*
Y850643D01*
X841660Y849569D01*
X839324D01*
X837434Y851459D01*
G01X856834Y855459D02*
Y856965D01*
X856334Y857465D01*
X850523D01*
X849236Y856178D01*
Y854175D01*
X848598Y853537D01*
X844479D01*
X843436Y854580D01*
Y855397D01*
G01X873845Y855576D02*
X871039D01*
X866235Y850772D01*
X858471D01*
X857052Y849353D01*
X846766D01*
X845884Y850235D01*
Y851459D01*
G01X851184Y867459D02*
X849155Y865430D01*
X844539D01*
X843312Y866657D01*
Y867413D01*
G01X861771Y874368D02*
X861223D01*
X858223Y877368D01*
X844540D01*
X842648Y875476D01*
G01X843033Y879459D02*
X845876D01*
G01X843359Y871459D02*
X848384D01*
G01Y875459D02*
X848367Y875476D01*
X845798D01*
G01X856868Y892738D02*
X855008Y894598D01*
X847713D01*
X846453Y893338D01*
X844774D01*
X842939Y891503D01*
G01X843033Y883459D02*
X845600D01*
Y883492D01*
X845633D01*
G01X842940Y887490D02*
X845964D01*
G01X832258Y909624D02*
Y912223D01*
X836653Y916618D01*
X836909D01*
G01Y914018D02*
X836258Y913367D01*
Y909660D01*
G01X849600Y918028D02*
X849500D01*
X849400Y917928D01*
X848228D01*
X845751Y915451D01*
Y909196D01*
X843665Y907110D01*
G01X841274Y914060D02*
Y916602D01*
X840381Y917495D01*
Y920494D01*
G01X844381D02*
Y917678D01*
X843315Y916612D01*
G01X867096Y935963D02*
X862443Y940616D01*
X847442D01*
X838953Y949105D01*
X836243D01*
G01X833683Y939579D02*
Y941992D01*
X832952Y942723D01*
G01X833683Y936743D02*
Y939579D01*
G01X841689Y941243D02*
X840209Y942723D01*
X836952D01*
G01X841689Y941243D02*
Y938733D01*
X839846Y936890D01*
X836886D01*
X836243Y937533D01*
Y939579D01*
G01X872126Y934766D02*
X863811Y943081D01*
X852141D01*
X843623Y951599D01*
X835299D01*
X833683Y949983D01*
Y949105D01*
G01D02*
X832952Y947340D01*
Y945873D01*
G01X836952D02*
Y947393D01*
X836243Y949105D01*
G01X886926Y1298712D02*
Y1296518D01*
X834573Y1244165D01*
Y1120528D01*
X844275Y1110826D01*
Y1015827D01*
X846567Y1013535D01*
Y1005714D01*
X861031Y991250D01*
X872845D01*
X875391Y993796D01*
G01X889729Y1295516D02*
X888305D01*
X835709Y1242920D01*
Y1120976D01*
X845395Y1111290D01*
Y1016856D01*
X847702Y1014549D01*
Y1006897D01*
X857812Y996787D01*
X869376D01*
X872183Y993980D01*
G01X887342Y1314990D02*
X888773Y1316421D01*
X892829D01*
X894378Y1314872D01*
Y1311625D01*
X893721Y1310968D01*
Y1310304D01*
X895662Y1308364D01*
Y1307700D01*
X895145Y1307183D01*
X894481D01*
X892540Y1309123D01*
X891876D01*
X891359Y1308606D01*
Y1307942D01*
X893300Y1306002D01*
Y1305338D01*
X892783Y1304821D01*
X892119D01*
X890178Y1306761D01*
X889514D01*
X883702Y1300949D01*
Y1295727D01*
X832853Y1244878D01*
Y1119815D01*
X842555Y1110113D01*
Y1013241D01*
X844058Y1011738D01*
G01X889244Y1444859D02*
X880217Y1435832D01*
Y1423440D01*
X876705Y1419928D01*
X839731D01*
X833877Y1425782D01*
G01X836744Y1444849D02*
X838747Y1442846D01*
X843780D01*
X850168Y1436458D01*
Y1424232D01*
X853301Y1421099D01*
X875429D01*
X878244Y1423914D01*
Y1451605D01*
G01X833898Y1448843D02*
X835841Y1446900D01*
X841545D01*
X851494Y1436951D01*
Y1425049D01*
X853970Y1422573D01*
X875048D01*
X876626Y1424151D01*
Y1449965D01*
X873779Y1452812D01*
Y1459746D01*
X876905Y1462872D01*
X884781D01*
X886806Y1460847D01*
G01X834462Y1463690D02*
Y1460072D01*
X834475Y1460059D01*
G01X862936Y178560D02*
X859332Y182164D01*
Y185997D01*
X853029Y192300D01*
G01X861816Y388245D02*
Y384230D01*
X860586Y383000D01*
G01X854758Y766075D02*
X856925D01*
X859000Y764000D01*
G01X852710Y755925D02*
X854925D01*
X859000Y760000D01*
G01Y781000D02*
X855925Y784075D01*
X853837D01*
G01X851584Y773925D02*
X854925D01*
X859000Y778000D01*
G01X852250Y809925D02*
X854925D01*
X859000Y814000D01*
G01X853837Y802075D02*
X856925D01*
X859000Y800000D01*
G01X849923Y827419D02*
X855357D01*
X856992Y829054D01*
G01X883458Y837573D02*
X867690D01*
X859171Y829054D01*
X856992D01*
G01X853851Y818000D02*
X859000D01*
G01X853684Y843459D02*
X851184D01*
G01X856834D02*
X863717D01*
X867165Y846907D01*
X869886D01*
G01X848384Y839459D02*
X850336Y841411D01*
X851888D01*
X853684Y839615D01*
Y839459D01*
G01Y835459D02*
Y835283D01*
X851948Y833547D01*
X850296D01*
X848384Y835459D01*
G01X856834D02*
X863313D01*
X867104Y839250D01*
X879912D01*
X880404Y839742D01*
G01X856834Y839459D02*
X862338D01*
X867466Y844587D01*
X875089D01*
X875820Y843856D01*
G01X856834Y847459D02*
X858138Y846155D01*
X863982D01*
X867913Y850086D01*
X875171D01*
G01X848739Y847459D02*
Y847104D01*
X850255Y845588D01*
X852052D01*
X853684Y847220D01*
Y847459D01*
G01X851184Y863459D02*
X853684D01*
G01X862114Y859479D02*
X860162Y857527D01*
X858762D01*
X857601Y858688D01*
Y858692D01*
X856834Y859459D01*
G01X870108Y862191D02*
X867770D01*
X865058Y859479D01*
X862114D01*
G01X876751Y865038D02*
X868169D01*
X864640Y861509D01*
X857720D01*
X856834Y862395D01*
Y863459D01*
G01X856881Y851924D02*
X857299D01*
X858686Y853311D01*
X865218D01*
G01X878246Y859995D02*
X868704D01*
X864168Y855459D01*
X856834D01*
G01X863206Y864154D02*
Y865056D01*
X859983Y868279D01*
X857654D01*
X856834Y867459D01*
G01X881370Y867338D02*
X875547D01*
X875044Y866835D01*
X866860D01*
X864179Y864154D01*
X863206D01*
G01X851184Y867459D02*
X853684D01*
G01X867310Y873743D02*
X864562D01*
X862278Y871459D01*
X860834D01*
X856834Y875459D01*
G01X856825Y875468D02*
X856834Y875459D01*
G01Y871459D02*
Y875459D01*
G01X862674Y878942D02*
Y875271D01*
X861771Y874368D01*
G01X859234Y879600D02*
X859300D01*
X860819Y881119D01*
X870300D01*
G01X856834Y879459D02*
X859093D01*
X859234Y879600D01*
G01X853684Y879459D02*
Y879645D01*
X851929Y881400D01*
X850325D01*
X848384Y879459D01*
G01X853684Y871459D02*
Y870649D01*
X852480Y869445D01*
X850398D01*
X848384Y871459D01*
G01X853718Y892738D02*
X849438D01*
X849267Y892567D01*
G01X848322Y888421D02*
X848384Y888483D01*
Y888887D01*
X849797Y890300D01*
X853198D01*
X853715Y889783D01*
Y889518D01*
X853806Y889427D01*
Y887798D01*
X853715Y887707D01*
G01X856868Y892738D02*
X858135Y891471D01*
X862868D01*
G01D02*
X869119D01*
X881645Y878945D01*
G01X859614Y883800D02*
X863290D01*
X863631Y883459D01*
G01X856834D02*
X857175Y883800D01*
X859614D01*
G01X877800Y876500D02*
Y876674D01*
X871015Y883459D01*
X863631D01*
G01X859614Y887846D02*
X868558D01*
X868945Y887459D01*
G01X856865Y887707D02*
X859407D01*
X859550Y887850D01*
Y887846D01*
X859614D01*
G01X848200Y883400D02*
Y883600D01*
X849966Y885366D01*
X852433D01*
X853684Y884115D01*
Y883459D01*
G01X979001Y1288925D02*
X981293Y1286633D01*
X1015304Y1204519D01*
Y1122836D01*
X982020Y1042476D01*
Y1006073D01*
X966582Y968802D01*
X948223Y950443D01*
Y950408D01*
X947080Y949265D01*
X884679D01*
X882400Y951544D01*
X852119D01*
X851925Y951350D01*
G01X870519Y60438D02*
Y60711D01*
X878788Y68980D01*
Y87784D01*
X872293Y94279D01*
G01X867659Y60513D02*
X873629Y66483D01*
Y89066D01*
X868344Y94351D01*
G01X864966Y388245D02*
X868868D01*
X869846Y389223D01*
Y397240D01*
X868586Y398500D01*
G01X874851Y761259D02*
X869325D01*
G01X883126Y766124D02*
X882030Y763479D01*
X880054Y761503D01*
Y761259D01*
G01X874851Y769017D02*
Y764409D01*
G01X880054Y769358D02*
Y764409D01*
G01X886610Y758108D02*
X883636Y755134D01*
X881397D01*
X879875Y753612D01*
G01X874851Y758109D02*
X873059Y756317D01*
X871013D01*
X870017Y757313D01*
G01X880054Y758109D02*
X879145D01*
X873728Y752692D01*
G01X874807Y784757D02*
X877100Y782464D01*
Y778137D01*
X876096Y777133D01*
X874851D01*
G01X884894Y784778D02*
X883343Y783227D01*
X882524Y781250D01*
Y778077D01*
X881570Y777123D01*
X880054D01*
G01X874851Y773983D02*
Y769017D01*
G01X880054Y773973D02*
Y769358D01*
G01X870000Y780000D02*
X872217D01*
X872500Y780283D01*
X874851D01*
G01X879887Y784719D02*
X880054Y784552D01*
Y780273D01*
G01X875095Y789701D02*
Y787303D01*
X874807Y787015D01*
Y784757D01*
G01X875095Y792851D02*
X880040D01*
G01X875916Y816615D02*
Y816379D01*
X874036Y814499D01*
Y808177D01*
X875748Y806465D01*
X875916D01*
G01X883866Y820415D02*
Y815620D01*
X878038Y809792D01*
Y804989D01*
X879916Y803111D01*
Y801702D01*
X884002Y797616D01*
G01X881753Y833087D02*
X881788Y832910D01*
Y824050D01*
X881787Y824022D01*
X881753Y823847D01*
Y822452D01*
X875916Y816615D01*
G01X869886Y846907D02*
X877548D01*
X877573Y846882D01*
G01X869609Y841429D02*
X877387D01*
X877964Y842006D01*
X882175D01*
G01X875943Y843733D02*
X875820Y843856D01*
G01X887669Y864189D02*
X883633D01*
X881635Y862191D01*
X870108D01*
G01X865218Y853311D02*
X869798Y857891D01*
X884519D01*
G01X887669D02*
X885565Y859995D01*
X878246D01*
G01X875171Y850086D02*
X877519D01*
X877573Y850032D01*
G01X873845Y855576D02*
X876269Y853152D01*
G01X864255Y869142D02*
X867310Y872197D01*
Y873743D01*
G01X884519Y873638D02*
X877781D01*
X870300Y881119D01*
G01X868945Y887459D02*
X870698D01*
X881370Y876787D01*
G01X884519Y867338D02*
X882219Y865038D01*
X876751D01*
G01X867405Y869142D02*
X871271D01*
X871811Y869141D01*
X871876Y869076D01*
G01X879864D02*
X871876D01*
G01X865824Y878942D02*
X869061D01*
X873432Y874571D01*
G01X881370Y870488D02*
X877515D01*
X873432Y874571D01*
G01X879286Y908762D02*
Y895183D01*
G01X882930Y888000D02*
Y891539D01*
X879286Y895183D01*
G01X875286Y908762D02*
Y889170D01*
X877080Y887376D01*
G01D02*
X881370Y883086D01*
G01X880628Y918042D02*
X878762Y916176D01*
Y912436D01*
X879286Y911912D01*
G01X876628Y918042D02*
X874639Y916053D01*
Y912559D01*
X875286Y911912D01*
G01X883656Y1460847D02*
X880055D01*
X879174Y1459966D01*
Y1459551D01*
G01D02*
Y1455566D01*
X877181Y1453573D01*
X875744D01*
G01X878244Y1451605D02*
X879038Y1450811D01*
X887107D01*
X894143Y1443775D01*
Y1424784D01*
X898227Y1420700D01*
X916302D01*
X920249Y1424647D01*
Y1444682D01*
X919632Y1445299D01*
Y1450993D01*
X920244Y1451605D01*
G01X889949Y559763D02*
X888062Y557876D01*
X886782D01*
X883525Y554619D01*
G01X884903Y696678D02*
X883597D01*
X882995Y696076D01*
Y693221D01*
X883959Y692257D01*
X886837D01*
X886956Y692138D01*
X891012D01*
G01X893984Y696075D02*
X896716D01*
X897249Y696608D01*
X904025D01*
X905573Y695060D01*
Y692669D01*
X902236Y689332D01*
G01X893984Y694107D02*
X902011D01*
X902236Y694332D01*
G01X891031Y696075D02*
Y697368D01*
X889758Y698641D01*
X883373D01*
X881658Y696926D01*
Y692226D01*
X883605Y690279D01*
X884911D01*
G01X886610Y761258D02*
X884816D01*
X883413Y759855D01*
G01X886610Y769419D02*
Y764408D01*
G01X894116Y789701D02*
X895793Y788024D01*
Y782189D01*
X890722Y777118D01*
G01D02*
X885110D01*
G01Y773968D02*
Y770919D01*
X886610Y769419D01*
G01X892040Y784511D02*
X890922Y783393D01*
X886334Y781492D01*
X885110Y780268D01*
G01X898737Y792289D02*
X896684D01*
X896122Y792851D01*
X894116D01*
G01X884894D02*
X889516D01*
G01X884894Y784778D02*
Y789701D01*
G01X911028Y796598D02*
Y795155D01*
X909515Y793642D01*
X904246D01*
X901740Y796148D01*
X896217D01*
X893780Y798585D01*
Y804353D01*
X894024Y804597D01*
Y814507D01*
X891916Y816615D01*
G01X888016Y820415D02*
X887916Y820315D01*
Y808965D01*
G01D02*
Y806465D01*
G01X899916D02*
X899487Y806894D01*
X899356D01*
X897907Y808343D01*
Y809736D01*
X895866Y811777D01*
Y820415D01*
G01X886065Y828112D02*
Y825516D01*
X888016Y823565D01*
G01X892408Y834455D02*
X886065Y828112D01*
G01X898835Y831912D02*
X898243Y831320D01*
Y825942D01*
X895866Y823565D01*
G01X893843Y832448D02*
X892586Y831191D01*
Y824235D01*
X891916Y823565D01*
G01X886120Y832295D02*
X883866Y830041D01*
Y823565D01*
G01X891916Y820415D02*
Y816615D01*
G01X892408Y841353D02*
X890254Y839199D01*
Y835978D01*
G01X895558Y839952D02*
X897118Y836187D01*
Y833629D01*
X898835Y831912D01*
G01X893968Y838994D02*
X894791Y838171D01*
X895698Y835979D01*
Y834303D01*
X893843Y832448D01*
G01X890818Y842143D02*
Y841497D01*
X887879Y838558D01*
Y834054D01*
X886120Y832295D01*
G01X881753Y833087D02*
Y833907D01*
X889243Y841397D01*
G01X880404Y839742D02*
X884325D01*
G01X891386Y899501D02*
Y884631D01*
X890818Y884063D01*
Y879937D01*
G01X883286Y901937D02*
Y894796D01*
X887573Y890509D01*
Y886116D01*
X887669Y886020D01*
Y879937D01*
G01X889293Y882200D02*
Y894228D01*
X887286Y896235D01*
G01X906586Y900841D02*
X899881D01*
X895543Y896503D01*
Y882200D01*
G01X897623Y902409D02*
X893968Y898754D01*
Y879937D01*
G01X887286Y896235D02*
Y908762D01*
G01X884628Y918042D02*
X882762Y916176D01*
Y912436D01*
X883286Y911912D01*
G01X891286D02*
X889678D01*
X889178Y911412D01*
Y905619D01*
G01X891386Y899501D02*
Y908762D01*
X891286D01*
G01X883286Y901937D02*
Y908762D01*
G01X888628Y918042D02*
X886762Y916176D01*
Y912436D01*
X887286Y911912D01*
G01X889244Y1444859D02*
Y1427552D01*
X897736Y1419060D01*
X916246D01*
X921369Y1424183D01*
Y1446563D01*
X921498Y1446692D01*
G01X886806Y1460847D02*
Y1462220D01*
X887526Y1462940D01*
X890242D01*
X892350Y1460832D01*
Y1453950D01*
X895691Y1450609D01*
Y1425014D01*
X898633Y1422072D01*
X916089D01*
X919129Y1425112D01*
Y1444217D01*
X917905Y1445441D01*
Y1450481D01*
X915726Y1452660D01*
Y1454681D01*
X917271Y1456226D01*
X919285D01*
G01X941872Y440942D02*
Y412034D01*
X920106Y390268D01*
X904879D01*
X897736Y383125D01*
G01X914202Y797460D02*
X913152Y798510D01*
X910422D01*
X905776Y803156D01*
Y813502D01*
X903766Y815512D01*
Y820415D01*
G01X899916Y806465D02*
Y806237D01*
X897856Y804177D01*
Y800244D01*
X899744Y798356D01*
X905082D01*
X907866Y795572D01*
G01X909416Y816615D02*
X907798D01*
X907274Y816091D01*
Y808229D01*
X909038Y806465D01*
G01D02*
X913716D01*
G01X899816Y820415D02*
Y812285D01*
X901918Y810183D01*
Y801471D01*
X902641Y800748D01*
G01X906565Y842143D02*
X904136Y839714D01*
Y829710D01*
X906277Y827569D01*
Y821594D01*
X909416Y818455D01*
Y816615D01*
G01X899816Y823565D02*
Y828948D01*
X901095Y830227D01*
Y832905D01*
X899828Y834172D01*
X899527D01*
X898600Y835099D01*
Y838442D01*
X897636Y839406D01*
G01X903766Y823565D02*
X902630Y824701D01*
Y828027D01*
G01X900267Y842143D02*
X902630Y839780D01*
Y828027D01*
G01X908049Y835184D02*
X911578D01*
X915095Y838701D01*
G01X911286Y899612D02*
Y897780D01*
X910676Y897170D01*
X898416D01*
X897118Y895872D01*
Y879937D01*
G01X917770Y897618D02*
X911901Y891749D01*
Y882124D01*
X909714Y879937D01*
G01X911487Y894491D02*
X910714Y893718D01*
Y883486D01*
X907165Y879937D01*
X906565D01*
G01X903726Y884516D02*
Y879861D01*
X903817Y879770D01*
G01X905229Y878358D02*
X903817Y879770D01*
G01X915286Y908762D02*
Y898290D01*
X911487Y894491D01*
G01X903721Y888478D02*
X903742Y888499D01*
Y892455D01*
G01X903726Y884516D02*
Y888473D01*
X903721Y888478D01*
G01X911286Y908762D02*
Y899612D01*
G01X907286Y908762D02*
X907042Y908518D01*
Y902257D01*
X906586Y901801D01*
Y900841D01*
G01X908628Y918042D02*
X906762Y916176D01*
Y912436D01*
X907286Y911912D01*
G01X912628Y918042D02*
X910762Y916176D01*
Y912436D01*
X911286Y911912D01*
G01X899286Y908762D02*
X903286D01*
G01X897623Y902409D02*
X902337D01*
X903286Y903358D01*
Y908762D01*
G01X897169Y1225259D02*
X904921D01*
X906309Y1226647D01*
G01X936371Y951484D02*
X940582Y955695D01*
Y987932D01*
X947857Y995207D01*
X963166D01*
X976871Y1008912D01*
Y1042592D01*
X1010504Y1123796D01*
Y1203237D01*
X981379Y1273549D01*
X965838Y1289090D01*
X928449D01*
X918083Y1299456D01*
X910788D01*
G01X918265Y969745D02*
Y972537D01*
X921390Y975662D01*
X922054D01*
X927048Y970668D01*
X927712D01*
X928795Y971751D01*
Y972415D01*
X923801Y977409D01*
Y978073D01*
X924884Y979156D01*
X925548D01*
X930542Y974162D01*
X931206D01*
X932289Y975245D01*
Y975909D01*
X927295Y980903D01*
Y981567D01*
X928378Y982650D01*
X929042D01*
X934036Y977656D01*
X934700D01*
X935783Y978739D01*
Y979403D01*
X930789Y984397D01*
Y985061D01*
X933054Y987326D01*
X934118D01*
X935140Y986304D01*
X935804D01*
X936887Y987387D01*
Y988051D01*
X935665Y989273D01*
Y989937D01*
X945479Y999751D01*
X965277D01*
X975151Y1009625D01*
Y1042935D01*
X1008784Y1124143D01*
Y1202884D01*
X979931Y1272545D01*
X965165Y1287311D01*
X927209D01*
X917327Y1297193D01*
X908501D01*
X906506Y1299188D01*
G01X902908Y1299828D02*
X902843Y1299763D01*
Y1296627D01*
X903932Y1295538D01*
X903933D01*
X904126Y1295345D01*
X916742D01*
X926511Y1285576D01*
X964467D01*
X978473Y1271570D01*
X1007064Y1202536D01*
Y1124487D01*
X973431Y1043278D01*
Y1010338D01*
X964564Y1001471D01*
X944161D01*
X913005Y970315D01*
Y969605D01*
G01X911117Y1314130D02*
X931256Y1293991D01*
X979722D01*
X982991Y1290722D01*
X1026526Y1185611D01*
Y1182684D01*
X1025051Y1181209D01*
X1022708D01*
X1021147Y1179648D01*
Y1121155D01*
X1020682Y1120690D01*
Y1109520D01*
X1007670Y1096508D01*
X985040Y1041874D01*
Y1005469D01*
X984940Y1005227D01*
X965321Y957862D01*
X942468Y935009D01*
Y916033D01*
X942488Y916013D01*
Y908702D01*
X936328Y902542D01*
Y892238D01*
X939691Y888875D01*
X940799Y886199D01*
Y885724D01*
X942356Y884167D01*
X943806D01*
X948391Y879582D01*
Y873497D01*
X949480Y872408D01*
X950754D01*
X952151Y871011D01*
Y865311D01*
X950854Y864014D01*
Y824454D01*
X948648Y822248D01*
Y801598D01*
X948704Y801531D01*
X953199Y797036D01*
Y791010D01*
X955225Y788984D01*
G01X940716Y951733D02*
X966885Y977902D01*
X978820Y1006712D01*
Y1043114D01*
X1012104Y1123476D01*
Y1203747D01*
X982816Y1274456D01*
X966575Y1290695D01*
X929526D01*
X914500Y1305721D01*
X906455D01*
X902875Y1309301D01*
G01X946363Y951179D02*
X965461Y970277D01*
X980420Y1006393D01*
Y1042795D01*
X1013704Y1123156D01*
Y1204161D01*
X984224Y1275335D01*
X967214Y1292343D01*
X930141D01*
X913220Y1309264D01*
X905740D01*
G01X985324Y1358731D02*
X983127D01*
X982385Y1357989D01*
X906143D01*
X904177Y1359955D01*
G01X915800Y629700D02*
Y646505D01*
X977300Y708005D01*
Y722601D01*
X981000Y726301D01*
Y731995D01*
X960500Y752495D01*
Y768600D01*
X958000Y771100D01*
X956817D01*
X956017Y770300D01*
G01X957500Y780800D02*
Y775000D01*
X962300Y770200D01*
Y753300D01*
X983000Y732600D01*
Y725500D01*
X979300Y721800D01*
Y706900D01*
X918300Y645900D01*
Y629700D01*
G01X921790Y813465D02*
X926399Y808856D01*
X938357D01*
G01X917055Y837659D02*
X915912Y836516D01*
Y828468D01*
X914577Y827133D01*
G01X921127Y833588D02*
Y832174D01*
X924676Y828625D01*
Y820935D01*
X921790Y818049D01*
Y816615D01*
G01X922313Y842143D02*
Y840721D01*
X923747Y839287D01*
Y834872D01*
X923887Y834732D01*
Y833212D01*
X927630Y829469D01*
Y823563D01*
X927867Y823326D01*
Y823081D01*
G01X925228Y816934D02*
Y817606D01*
X927867Y820245D01*
Y823081D01*
G01X917503Y817982D02*
X919553Y820032D01*
X919853D01*
X921916Y822095D01*
G01X919163Y835844D02*
X918367Y835048D01*
Y831224D01*
X921916Y827675D01*
Y822095D01*
G01X917403Y822083D02*
X919702Y824382D01*
Y826833D01*
G01X919163Y838994D02*
Y838182D01*
X917247Y836266D01*
Y829288D01*
X919702Y826833D01*
G01X920753Y840483D02*
X921127Y840109D01*
Y833588D01*
G01X920723Y887700D02*
Y889277D01*
X926360Y894914D01*
Y895464D01*
X931597Y900701D01*
G01X917603Y884700D02*
Y889703D01*
X922475Y894575D01*
G01X923892Y889077D02*
Y887200D01*
G01X914428Y881600D02*
Y889834D01*
X914199Y890063D01*
G01X927062Y888027D02*
X928293Y889258D01*
X929557D01*
G01X927286Y908762D02*
Y899386D01*
X922475Y894575D01*
G01X935286Y908762D02*
X933779Y907255D01*
Y894879D01*
X931083Y892183D01*
X926998D01*
X923892Y889077D01*
G01X923286Y908762D02*
Y905769D01*
X923311Y905744D01*
Y899175D01*
X914199Y890063D01*
G01X920628Y918042D02*
X918762Y916176D01*
Y912436D01*
X919286Y911912D01*
G01X916628Y918042D02*
X914762Y916176D01*
Y912436D01*
X915286Y911912D01*
G01X924628Y918042D02*
X922762Y916176D01*
Y912436D01*
X923286Y911912D01*
G01X928628Y918042D02*
X926762Y916176D01*
Y912436D01*
X927286Y911912D01*
G01X931286Y908762D02*
X928940Y906416D01*
Y903358D01*
X931597Y900701D01*
G01X917770Y897618D02*
Y907246D01*
X919286Y908762D01*
G01X920628Y922551D02*
Y918042D01*
G01X916628Y922551D02*
Y918042D01*
G01X924628Y922551D02*
Y918042D01*
G01X928628Y922551D02*
Y918042D01*
G01X937428Y208298D02*
Y213807D01*
X937438Y213817D01*
G01X943382Y835395D02*
X942478Y836299D01*
X939410D01*
X938280Y837429D01*
Y839948D01*
X937228Y841000D01*
X937200D01*
G01X931261Y883702D02*
X930712Y884251D01*
Y888391D01*
X929845Y889258D01*
X929557D01*
G01X938752Y881986D02*
X934944D01*
G01D02*
X934447D01*
X932731Y883702D01*
X931261D01*
G01X936628Y918042D02*
X934762Y916176D01*
Y912436D01*
X935286Y911912D01*
G01X932628Y918042D02*
X930762Y916176D01*
Y912436D01*
X931286Y911912D01*
G01X936628Y922551D02*
Y918042D01*
G01X932628Y922551D02*
Y918042D01*
G01X943891Y1306608D02*
X947921Y1310638D01*
X1412312D01*
X1421238Y1301712D01*
G01X1424732Y1301603D02*
Y1302055D01*
X1412813Y1313974D01*
X948620D01*
X944207Y1318387D01*
Y1320739D01*
G01X949058Y919886D02*
X952936D01*
X952957Y919907D01*
G01D02*
X953049Y919999D01*
X954677D01*
X954769Y919907D01*
X957199D01*
X960408Y923116D01*
X960508D01*
G01X959545Y918306D02*
X960416Y919177D01*
Y923024D01*
X960508Y923116D01*
G01X971648Y1224207D02*
X962198D01*
X961146Y1225259D01*
G01X1428009Y1301760D02*
Y1302328D01*
X1413631Y1316706D01*
X951466D01*
X947308Y1320864D01*
Y1325035D01*
G01X978880Y869552D02*
X976899D01*
X975424Y871027D01*
X973130D01*
G01Y874177D02*
Y880162D01*
G01D02*
Y886648D01*
X974211Y887729D01*
Y889159D01*
X976296Y891244D01*
X976331D01*
X978436Y893349D01*
X991018D01*
X998054Y900385D01*
Y904833D01*
G01X971258Y897500D02*
Y901500D01*
G01D02*
Y905500D01*
G01X966813Y904556D02*
X968257Y906000D01*
X970758D01*
X971258Y905500D01*
G01X974408D02*
Y907128D01*
X973988Y907548D01*
Y910038D01*
G01X971672Y1228482D02*
Y1224231D01*
X971648Y1224207D01*
G01X978169Y1221268D02*
X977653Y1221784D01*
Y1231001D01*
X977022Y1231632D01*
X971672D01*
G01X990625Y1373400D02*
X985200D01*
X983000Y1375600D01*
X977600D01*
X974882Y1378318D01*
Y1392080D01*
G01X980047Y1397245D02*
X974882Y1392080D01*
G01X980139Y1393308D02*
X977154Y1390323D01*
Y1384497D01*
X978167Y1383484D01*
X981284D01*
X984600Y1386800D01*
G01X996024Y352132D02*
X995903Y352253D01*
Y358007D01*
X993603Y360307D01*
X989950D01*
G01D02*
X980081D01*
G01X984357Y777555D02*
X984603Y777309D01*
Y771411D01*
X987239Y768775D01*
X989884D01*
G01X990699Y778630D02*
X992000Y779931D01*
Y783425D01*
G01X1153229Y848581D02*
X1113742Y864937D01*
X1066560D01*
X1066090Y864467D01*
Y857706D01*
X1065620Y857236D01*
X1064090D01*
X1063620Y857706D01*
Y864467D01*
X1063150Y864937D01*
X1061620D01*
X1061150Y864467D01*
Y857569D01*
X1060680Y857099D01*
X1059150D01*
X1058680Y857569D01*
Y864467D01*
X1058210Y864937D01*
X1056680D01*
X1056210Y864467D01*
Y861842D01*
X1055740Y861372D01*
X1054210D01*
X1053740Y861842D01*
Y864467D01*
X1053270Y864937D01*
X1051740D01*
X1051270Y864467D01*
Y860611D01*
X1050800Y860141D01*
X1049270D01*
X1048800Y860611D01*
Y863770D01*
X1048018Y864552D01*
X1043352D01*
X1035422Y856622D01*
X997832D01*
X986921Y867533D01*
Y873056D01*
X990966Y877101D01*
Y879336D01*
X990554Y879748D01*
Y883233D01*
G01X1161535Y844167D02*
Y846863D01*
X1158591Y849807D01*
X1116553Y867220D01*
X1049820D01*
X1049172Y866572D01*
X1040752D01*
X1039745Y865565D01*
X1032045D01*
X1031545Y865065D01*
Y864510D01*
X1031044Y864009D01*
X1029381D01*
X1028911Y864479D01*
Y871307D01*
X1028441Y871777D01*
X1026911D01*
X1026441Y871307D01*
Y864479D01*
X1025971Y864009D01*
X1024441D01*
X1023971Y864479D01*
Y873724D01*
X1023501Y874194D01*
X1021971D01*
X1021501Y873724D01*
Y864479D01*
X1020838Y863816D01*
X993774D01*
X989381Y868209D01*
Y871666D01*
X998054Y880339D01*
Y883233D01*
G01X997632Y870398D02*
X992441D01*
G01X977771Y883217D02*
Y887684D01*
G01D02*
X984668D01*
X985554Y886798D01*
Y883233D01*
G01X988054D02*
Y888283D01*
G01X993054Y883233D02*
Y890094D01*
X995747Y892787D01*
X1005413D01*
G01X982783Y909995D02*
Y908552D01*
X983054Y908281D01*
Y904833D01*
G01X1185516Y844248D02*
X1170203Y854479D01*
X1044384Y906601D01*
X1017260Y911996D01*
X1016992Y912107D01*
X1016721Y912161D01*
X1004283Y917312D01*
X994959D01*
X988054Y910407D01*
Y904833D01*
G01X990554D02*
Y908994D01*
X996084Y914524D01*
X1004955D01*
X1011911Y907568D01*
Y906936D01*
X1013897Y904950D01*
G01X985554Y913434D02*
Y904833D01*
G01X990300Y897500D02*
X993054Y900254D01*
Y904833D01*
G01X989311Y920364D02*
X987797Y918850D01*
X985554Y913434D01*
G01X1548148Y1418847D02*
X1477099D01*
X1451877Y1393625D01*
Y1333900D01*
X1455800Y1329977D01*
Y1299500D01*
X1452897Y1296597D01*
X1439703D01*
X1436506Y1293400D01*
X1424000D01*
X1419700Y1297700D01*
X1412815D01*
X1402977Y1307538D01*
X989058D01*
X984817Y1303297D01*
G01X988784Y1361974D02*
Y1362244D01*
X992135Y1365595D01*
X998795D01*
X1002024Y1368824D01*
Y1380375D01*
X997199Y1385200D01*
X993775D01*
G01X985324Y1358731D02*
X988945D01*
X993792Y1363578D01*
X999378D01*
X1003924Y1368124D01*
Y1381276D01*
X996000Y1389200D01*
X993775D01*
G01Y1369200D02*
X998600D01*
G01X993775Y1373400D02*
X998600D01*
G01X980139Y1381496D02*
X983400D01*
G01D02*
X997105D01*
X997401Y1381200D01*
G01X986177Y1367678D02*
X989103D01*
X990625Y1369200D01*
G01X980166Y1373622D02*
X982692D01*
X986177Y1370137D01*
Y1367678D01*
G01X980203Y1377559D02*
X999124D01*
X999283Y1377400D01*
G01X993746Y1398271D02*
X998643D01*
G01X979996Y1386100D02*
X983096Y1389200D01*
X990625D01*
G01X985448Y1398271D02*
X990596D01*
G01X990625Y1394200D02*
X984922D01*
X980092Y1389370D01*
G01X998685Y1389915D02*
X996400Y1392200D01*
X992625D01*
X990625Y1394200D01*
G01X984600Y1386800D02*
X989025D01*
X990625Y1385200D01*
G01X1003029Y192300D02*
X1005144Y190185D01*
X1012346D01*
G01X997059Y348522D02*
X1002820Y342761D01*
G01D02*
Y341954D01*
G01X1005576Y801475D02*
Y805657D01*
X1009808Y809889D01*
X1011156D01*
G01X1002426Y801475D02*
X1000494D01*
X998376Y803593D01*
Y805985D01*
G01D02*
Y810970D01*
G01X1006054Y810969D02*
Y814607D01*
X1006430Y814983D01*
Y816957D01*
G01X1009580D02*
X1014372D01*
X1015797Y815532D01*
Y813322D01*
X1014781Y810869D01*
Y810319D01*
G01X1013081Y868206D02*
X1013048Y868239D01*
X1008988D01*
G01X1000782Y870398D02*
Y872383D01*
X1002176Y873777D01*
Y875303D01*
G01X1000554Y883233D02*
Y880678D01*
X1002176Y879056D01*
Y875303D01*
G01X1004713Y871389D02*
X1008988D01*
G01X1163579Y850774D02*
X1117790Y869740D01*
X1048776D01*
X1048128Y869092D01*
X1039708D01*
X1038701Y868085D01*
X1032615D01*
X1031457Y869243D01*
Y873590D01*
X1028499Y876548D01*
X1027111D01*
X1020369Y883290D01*
X1016077D01*
X1008995Y890372D01*
Y906714D01*
X1008973Y906736D01*
Y906770D01*
X1006888Y908855D01*
X1006854D01*
X1004004Y911705D01*
X997434D01*
X995554Y909825D01*
Y904833D01*
G01X998313Y888295D02*
X997953D01*
X995554Y885896D01*
Y883233D01*
G01X1005413Y892787D02*
Y897425D01*
G01Y900575D02*
Y905295D01*
G01X1021924Y980456D02*
Y980560D01*
X1018950Y983534D01*
X1008270D01*
X1006986Y984818D01*
Y989825D01*
X1008698Y991537D01*
X1011095D01*
X1012025Y990607D01*
Y987524D01*
X1012977Y986572D01*
X1017386D01*
X1018009Y987195D01*
Y988813D01*
G01X1009564Y988874D02*
Y986966D01*
X1011541Y984989D01*
X1065735D01*
X1068006Y987260D01*
Y990090D01*
X1070257Y992341D01*
X1122088D01*
X1199627Y1069880D01*
Y1109779D01*
X1196522Y1112884D01*
X1194871D01*
X1193649Y1114106D01*
Y1122552D01*
X1192601Y1123600D01*
X1165000D01*
X1163910Y1122510D01*
Y1120012D01*
X1162106Y1118208D01*
G01X1002652Y1023731D02*
X1006274Y1027353D01*
X1099582D01*
X1139666Y1067519D01*
Y1110521D01*
X1137795Y1112392D01*
Y1118476D01*
X1139419Y1120100D01*
X1148085D01*
X1149300Y1121315D01*
Y1122600D01*
X1150300Y1123600D01*
X1159216D01*
X1160393Y1122423D01*
Y1117431D01*
X1161239Y1116585D01*
X1167963D01*
X1169586Y1118208D01*
G01X1007850Y1368835D02*
X1006040Y1370645D01*
Y1382560D01*
X998685Y1389915D01*
G01X1022293Y94279D02*
X1028486Y88086D01*
Y68678D01*
X1020519Y60711D01*
Y60438D01*
G01X1018344Y94351D02*
X1023327Y89368D01*
Y66181D01*
X1017659Y60513D01*
G01X1010291Y199582D02*
X1019558Y190315D01*
X1084085D01*
X1090761Y196991D01*
X1113873D01*
X1118199Y192665D01*
X1124075D01*
G01X1021713Y196665D02*
X1026343Y192035D01*
X1083372D01*
X1090048Y198711D01*
X1114586D01*
X1116632Y196665D01*
X1124075D01*
G01X1021826Y186778D02*
X1023643Y188595D01*
X1084798D01*
X1091474Y195271D01*
X1113160D01*
X1121653Y186778D01*
X1124188D01*
G01X1011156Y809889D02*
X1013821Y812554D01*
Y813520D01*
G01X1013081Y868206D02*
X1016526D01*
X1017800Y866932D01*
Y867065D01*
G01X1013902Y897116D02*
Y893405D01*
G01Y897116D02*
X1014211Y897425D01*
X1018816D01*
X1021233Y895008D01*
X1021408D01*
G01X1029544Y884845D02*
X1028699Y884000D01*
X1024913D01*
G01X1013897Y897121D02*
X1013902Y897116D01*
G01X1013897Y904950D02*
Y900271D01*
G01X1205117Y1112598D02*
X1207166Y1110549D01*
Y1071141D01*
X1122703Y986678D01*
X1104021D01*
X1040733Y923390D01*
X1024234D01*
X1018419Y917575D01*
G01X1014009Y988813D02*
Y995229D01*
X1012149Y997089D01*
Y999775D01*
X1020705Y1008331D01*
Y1011533D01*
X1028629Y1019457D01*
X1095784D01*
X1139174Y1062847D01*
G01X1018009Y988813D02*
Y991341D01*
X1015979Y993371D01*
Y1000310D01*
X1022596Y1006927D01*
Y1011840D01*
X1025228Y1014472D01*
X1042129D01*
X1045994Y1018337D01*
X1097684D01*
X1136182Y1056835D01*
Y1056870D01*
X1137447Y1058135D01*
X1137482D01*
X1140034Y1060687D01*
X1140069D01*
X1141334Y1061952D01*
Y1061987D01*
X1147166Y1067819D01*
Y1114489D01*
X1150885Y1118208D01*
G01X1026009Y988813D02*
X1023869Y990953D01*
Y998884D01*
X1025224Y1000239D01*
X1026889D01*
X1031788Y1005138D01*
X1038516D01*
X1049374Y1015996D01*
X1101384D01*
X1139203Y1053815D01*
X1139237D01*
X1140502Y1055080D01*
Y1055114D01*
X1145011Y1059623D01*
Y1059658D01*
X1146276Y1060923D01*
X1146311D01*
X1154625Y1069237D01*
Y1114468D01*
G01X1022009Y988813D02*
X1020069Y990753D01*
Y999995D01*
X1021631Y1001557D01*
X1025232D01*
X1032017Y1008342D01*
Y1012198D01*
X1032896Y1013077D01*
X1043628D01*
X1047667Y1017116D01*
X1099483D01*
X1138342Y1055975D01*
G01X1026221Y1214372D02*
X1033048D01*
X1034220Y1213200D01*
X1044000D01*
X1049100Y1208100D01*
X1094400D01*
X1096007Y1209707D01*
X1102999D01*
X1103997Y1210705D01*
Y1212319D01*
X1104931Y1213253D01*
X1118765D01*
X1120964Y1215452D01*
G01X1021976Y1218169D02*
X1041031D01*
X1047600Y1211600D01*
X1095700D01*
X1097720Y1213620D01*
X1100431D01*
X1102263Y1215452D01*
G01X1032694Y892845D02*
Y897249D01*
X1038010Y902565D01*
G01X1029544Y892845D02*
Y888845D01*
G01D02*
Y884845D01*
G01X1038009Y988813D02*
X1036149Y990673D01*
Y998631D01*
X1038407Y1000889D01*
X1039368D01*
X1044339Y1005860D01*
X1054022D01*
X1056197Y1008035D01*
X1102484D01*
X1144494Y1050045D01*
G01X1030009Y988813D02*
X1028001Y990821D01*
Y998483D01*
X1033536Y1004018D01*
X1038980D01*
X1049762Y1014800D01*
X1103208D01*
X1147171Y1058763D01*
G01X1042009Y988813D02*
X1040145Y990677D01*
Y999620D01*
X1045265Y1004740D01*
X1054486D01*
X1056661Y1006915D01*
X1105306D01*
X1153875Y1055484D01*
X1153910D01*
X1169429Y1071003D01*
Y1110885D01*
X1165846Y1114468D01*
G01X1034009Y988813D02*
X1031884Y990938D01*
Y998719D01*
X1036063Y1002898D01*
X1039444D01*
X1039544Y1002998D01*
X1039569D01*
X1043551Y1006980D01*
X1053558D01*
X1055733Y1009155D01*
X1100549D01*
X1147997Y1056603D01*
X1148066D01*
X1162088Y1070625D01*
Y1110745D01*
X1158365Y1114468D01*
G01X1032831Y1207950D02*
X1040281Y1200500D01*
X1093899D01*
X1095668Y1202269D01*
X1102969D01*
X1104158Y1203458D01*
Y1208358D01*
X1105508Y1209708D01*
X1111480D01*
X1113484Y1211712D01*
G01X1040606Y1230407D02*
X1042699Y1232500D01*
X1051728D01*
X1057028Y1237800D01*
X1123800D01*
X1124900Y1236700D01*
Y1219801D01*
X1124300Y1219201D01*
Y1215856D01*
X1124704Y1215452D01*
G01X1383505Y349437D02*
X1378383Y354559D01*
Y360817D01*
X1375969Y363231D01*
X1318942D01*
X1302311Y346600D01*
X1250200D01*
X1230500Y326900D01*
X1206253D01*
X1205053Y328100D01*
X1181273D01*
X1180318Y329055D01*
X1143056D01*
X1131201Y317200D01*
X1105562D01*
X1089306Y300944D01*
X1087118D01*
X1077974Y291800D01*
X1071235D01*
X1057335Y277900D01*
X1047359D01*
X1045364Y279895D01*
G01X1051796Y279965D02*
X1053430Y281599D01*
X1056900D01*
X1072401Y297100D01*
X1080100D01*
X1086796Y303796D01*
X1089642D01*
X1104943Y319097D01*
X1128896D01*
X1140843Y331044D01*
X1180783D01*
X1181827Y330000D01*
X1207223D01*
X1208323Y328900D01*
X1229822D01*
X1249622Y348700D01*
X1284900D01*
X1288200Y352000D01*
X1295700D01*
X1298600Y349100D01*
X1301501D01*
X1317352Y364951D01*
X1377797D01*
X1380648Y362100D01*
Y355988D01*
X1384265Y352371D01*
G01X1054009Y988813D02*
X1052149Y990673D01*
Y998631D01*
X1053432Y999914D01*
X1055544D01*
X1059185Y1003555D01*
X1112106D01*
X1164338Y1055787D01*
G01X1046009Y988813D02*
X1044149Y990673D01*
Y998946D01*
X1048823Y1003620D01*
X1054950D01*
X1057125Y1005795D01*
X1107241D01*
X1154770Y1053324D01*
G01X1173326Y1114468D02*
X1177067Y1110727D01*
Y1071536D01*
X1163478Y1057947D01*
X1163443D01*
X1110171Y1004675D01*
X1058332D01*
X1056157Y1002500D01*
X1049287D01*
X1047871Y1001084D01*
Y990951D01*
X1050009Y988813D01*
G01X1173326Y1118208D02*
X1175402Y1116132D01*
X1177964D01*
X1179007Y1115089D01*
Y1113584D01*
X1179854Y1112737D01*
X1181359D01*
X1184390Y1109706D01*
Y1072112D01*
X1179046Y1066768D01*
X1179011D01*
X1114678Y1002435D01*
X1059953D01*
X1056149Y998631D01*
Y990673D01*
X1058009Y988813D01*
G01X1046485Y1034538D02*
X1050865Y1038918D01*
Y1154899D01*
X1054483Y1158517D01*
Y1158783D01*
X1057267Y1161567D01*
X1057533D01*
X1059604Y1163638D01*
X1060839D01*
X1063081Y1165880D01*
Y1167481D01*
X1064000Y1168400D01*
X1064900D01*
X1066800Y1170300D01*
Y1171553D01*
X1067947Y1172700D01*
X1076901D01*
X1078014Y1173813D01*
Y1181214D01*
X1079928Y1183128D01*
Y1184528D01*
X1080700Y1185300D01*
X1082500D01*
X1083500Y1186300D01*
Y1196300D01*
X1084000Y1196800D01*
X1094299D01*
X1096099Y1198600D01*
X1103001D01*
X1104103Y1199702D01*
Y1200904D01*
X1105561Y1202362D01*
X1106962D01*
X1107795Y1203195D01*
Y1205094D01*
X1108901Y1206200D01*
X1114101D01*
X1115124Y1207223D01*
Y1209612D01*
X1117224Y1211712D01*
G01X1070762Y1169100D02*
X1070562Y1168900D01*
X1068476D01*
X1066803Y1167227D01*
Y1166003D01*
X1062366Y1161566D01*
X1061166D01*
X1059470Y1159870D01*
Y1158570D01*
X1052900Y1152000D01*
Y1044668D01*
X1057212Y1040356D01*
G01X1070762Y1164560D02*
X1067248Y1161046D01*
Y1159252D01*
X1065494Y1157498D01*
X1060699D01*
X1053926Y1150725D01*
Y1070734D01*
X1055073Y1069587D01*
Y1046926D01*
X1065079Y1036920D01*
G01X1070547Y1160650D02*
Y1155068D01*
X1069219Y1153740D01*
X1067333D01*
X1066622Y1153029D01*
Y1151186D01*
X1065302Y1149866D01*
X1056476D01*
X1055200Y1148590D01*
Y1082855D01*
X1057093Y1080962D01*
Y1057132D01*
X1060768Y1053457D01*
G01X1049930Y1221407D02*
X1052137Y1219200D01*
X1093524D01*
X1095424Y1217300D01*
X1104155D01*
X1106003Y1215452D01*
G01X1043588Y1227300D02*
Y1221524D01*
X1050178Y1214934D01*
G01X1098523Y1215452D02*
X1050696D01*
X1050178Y1214934D01*
G01X1050605Y1224472D02*
X1054295D01*
G01D02*
X1056067Y1222700D01*
X1109499D01*
X1110000Y1222199D01*
Y1218935D01*
X1111613Y1217322D01*
G01X1049770Y1229402D02*
X1050768Y1230400D01*
X1111900D01*
X1113600Y1228700D01*
Y1219076D01*
X1115354Y1217322D01*
G01X1049720Y1234921D02*
Y1237721D01*
X1053499Y1241500D01*
X1130900D01*
X1132184Y1240216D01*
Y1215452D01*
G01X1410817Y1305417D02*
Y1302143D01*
X1413460Y1299500D01*
X1452400D01*
X1453600Y1300700D01*
Y1322707D01*
X1444571Y1331736D01*
Y1338529D01*
X1433100Y1350000D01*
X1371900D01*
X1365300Y1343400D01*
X1051700D01*
X1049600Y1345500D01*
Y1347392D01*
X1049670Y1347462D01*
G01X1046075Y1350650D02*
Y1343625D01*
X1049700Y1340000D01*
X1366900D01*
X1373600Y1346700D01*
X1425400D01*
X1433400Y1338700D01*
X1441200D01*
G01X1049493Y1350694D02*
X1047701Y1348902D01*
Y1344799D01*
X1050800Y1341700D01*
X1366195D01*
X1372895Y1348400D01*
X1431800D01*
X1435900Y1344300D01*
Y1340800D01*
G01X1223818Y1142519D02*
Y1138967D01*
X1225786Y1136999D01*
Y1108250D01*
X1224336Y1106800D01*
X1222468D01*
X1221968Y1106300D01*
Y1065632D01*
X1254425Y1033175D01*
Y1024991D01*
X1253229Y1023795D01*
X1161829D01*
X1123292Y985258D01*
X1122851D01*
X1122832Y985239D01*
X1114318D01*
X1060698Y931619D01*
G01X1062009Y988813D02*
X1060149Y990673D01*
Y998631D01*
X1062833Y1001315D01*
X1116613D01*
X1179906Y1064608D01*
G01X1065823Y988773D02*
X1064149Y990447D01*
Y998631D01*
X1065713Y1000195D01*
X1120708D01*
X1192047Y1071534D01*
Y1109240D01*
X1188724Y1112563D01*
X1187437D01*
X1185532Y1114468D01*
X1184546D01*
G01X1199507D02*
X1203258Y1110717D01*
Y1070619D01*
X1121452Y988813D01*
X1074009D01*
G01X1165846Y1118208D02*
X1167643Y1120005D01*
X1188910D01*
X1190255Y1118660D01*
Y1113630D01*
X1191415Y1112470D01*
X1192502D01*
X1195718Y1109254D01*
Y1069766D01*
X1121932Y995980D01*
X1071889D01*
X1070009Y997860D01*
G01X1079822Y1155610D02*
X1077912Y1153700D01*
X1071670D01*
X1070800Y1152830D01*
Y1151900D01*
X1068300Y1149400D01*
Y1148900D01*
X1065600Y1146200D01*
X1060099D01*
X1059300Y1145401D01*
Y1059069D01*
X1063714Y1054655D01*
Y1049867D01*
X1075697Y1037884D01*
X1079178D01*
G01X1074212Y1135334D02*
X1070410Y1131532D01*
Y1068060D01*
X1074232Y1064238D01*
Y1055836D01*
G01X1070472Y1135334D02*
X1066411Y1131273D01*
Y1059086D01*
X1073996Y1051501D01*
Y1043913D01*
X1076577Y1041332D01*
G01X1067866Y1051037D02*
Y1054067D01*
X1063200Y1058733D01*
Y1141300D01*
X1064300Y1142400D01*
X1066324D01*
X1068714Y1144790D01*
Y1146941D01*
X1070303Y1148530D01*
G01X1077952Y1138484D02*
X1074212D01*
G01X1070472D02*
Y1143390D01*
G01D02*
X1073491Y1146409D01*
X1077262D01*
X1078011Y1147158D01*
Y1148795D01*
X1078998Y1149782D01*
X1081474D01*
X1083562Y1151870D01*
G01X1073453Y1148530D02*
X1074923Y1150000D01*
X1077408D01*
X1079278Y1151870D01*
X1079822D01*
G01X1083562Y1155610D02*
X1081838Y1157334D01*
X1075129D01*
X1073697Y1158766D01*
Y1160650D01*
G01X1079822Y1159350D02*
Y1161838D01*
X1077100Y1164560D01*
X1073912D01*
G01X1081692Y1164960D02*
X1079066D01*
X1074926Y1169100D01*
X1073912D01*
G01X1106003Y1140649D02*
X1104133Y1138779D01*
Y1113404D01*
X1103327Y1112598D01*
X1082429D01*
X1081692Y1111861D01*
Y1052117D01*
X1076868Y1047293D01*
G01X1109743Y1140649D02*
Y1139500D01*
X1111269Y1137974D01*
Y1131886D01*
X1110625Y1131242D01*
X1108928D01*
X1107873Y1130187D01*
Y1113500D01*
X1105900Y1111527D01*
Y1107600D01*
X1105400Y1107100D01*
X1091419D01*
X1090919Y1106600D01*
Y1104127D01*
X1090269Y1103477D01*
X1087102D01*
X1085432Y1101807D01*
Y1050786D01*
X1079910Y1045264D01*
G01X1081680Y1146271D02*
Y1139775D01*
X1080389Y1138484D01*
X1077952D01*
G01X1079822Y1148129D02*
X1081680Y1146271D01*
G01X1090200Y1172100D02*
X1089500Y1171400D01*
Y1169593D01*
X1088800Y1168893D01*
X1084358D01*
X1083159Y1170092D01*
G01X1081692Y1164960D02*
X1083562Y1163090D01*
Y1159350D01*
G01X1088715Y1533457D02*
Y1531448D01*
X1086867Y1529600D01*
X1084000D01*
G01X1091529Y1528718D02*
X1089700Y1526889D01*
Y1521000D01*
G01X1088715Y1537257D02*
Y1533457D01*
G01X1099501Y545528D02*
X1101145D01*
X1101706Y544967D01*
X1104984D01*
G01D02*
Y542500D01*
X1105484Y542000D01*
X1123173D01*
X1126633Y545460D01*
Y551894D01*
G01X1107698Y618400D02*
Y617000D01*
X1108198Y616500D01*
X1113173D01*
X1114389Y615284D01*
X1122234D01*
X1123267Y616317D01*
G01X1092769Y936975D02*
X1096535Y940741D01*
X1181415D01*
X1184950Y937206D01*
Y934079D01*
X1185420Y933609D01*
X1187151D01*
G01X1100357Y1135040D02*
Y1135075D01*
X1098523Y1136909D01*
G01X1096651Y1194917D02*
X1102783D01*
X1104363Y1193337D01*
G01D02*
Y1193011D01*
G01X1101402Y1518200D02*
Y1513425D01*
X1101375Y1513398D01*
G01X1095500Y1521000D02*
Y1525420D01*
X1096780Y1526700D01*
G01X1101402Y1518200D02*
Y1531702D01*
G01X1091865Y1537257D02*
X1094923D01*
X1096780Y1535400D01*
G01X1120706Y94351D02*
X1125613Y89444D01*
Y66105D01*
X1120021Y60513D01*
G01X1124655Y94279D02*
X1130772Y88162D01*
Y68602D01*
X1122881Y60711D01*
Y60438D01*
G01X1108134Y544967D02*
X1111984D01*
G01X1113113Y551040D02*
X1111984Y549911D01*
Y544967D01*
G01X1114668Y577937D02*
Y552595D01*
X1113113Y551040D01*
G01X1110848Y602400D02*
X1113144D01*
X1117673Y606929D01*
G01X1110848Y594400D02*
X1112773D01*
X1114417Y592756D01*
X1119929D01*
X1122673Y595500D01*
G01X1110848Y598400D02*
X1118574D01*
X1122173Y601999D01*
Y604567D01*
G01X1110848Y606400D02*
X1113073D01*
X1116745Y610072D01*
X1123331D01*
G01X1110848Y618400D02*
X1117633D01*
G01X1110848Y610400D02*
X1112454D01*
X1114646Y612592D01*
X1117914D01*
G01X1110848Y614400D02*
Y610400D01*
G01X1120964Y1211712D02*
X1122834Y1213582D01*
X1130314D01*
G01X1119094Y1217322D02*
X1117224Y1215452D01*
G01X1107873Y1217322D02*
X1109743Y1215452D01*
G01X1124075Y192665D02*
X1126525Y190215D01*
X1186335D01*
X1192662Y196542D01*
X1222560D01*
X1226437Y192665D01*
G01X1124075Y196665D02*
X1128805Y191935D01*
X1185622D01*
X1192358Y198671D01*
X1210268D01*
G01X1124188Y186778D02*
X1125905Y188495D01*
X1187048D01*
X1193375Y194822D01*
X1218506D01*
X1226550Y186778D01*
G01X1134673Y536425D02*
Y535000D01*
X1139673Y530000D01*
G01X1126633Y554847D02*
X1129173D01*
X1129673Y554347D01*
Y544000D01*
G01D02*
Y541000D01*
X1131098Y539575D01*
X1134673D01*
G01X1137673Y568000D02*
X1133719Y564046D01*
Y557800D01*
G01X1131750Y768859D02*
X1137374Y763235D01*
X1151168D01*
X1152485Y764552D01*
G01X1131743Y779174D02*
Y768866D01*
X1131750Y768859D01*
G01X1139617Y782914D02*
X1144122Y778409D01*
X1146674D01*
G01X1138342Y1055975D02*
X1150885Y1068518D01*
Y1114468D01*
G01X1139174Y1062847D02*
X1143219Y1066892D01*
Y1110366D01*
X1141535Y1112050D01*
Y1115436D01*
X1142547Y1116448D01*
X1146477D01*
X1150083Y1120054D01*
X1152779D01*
X1154625Y1118208D01*
G01X1130314Y1213582D02*
X1136731D01*
X1137026Y1213877D01*
X1138125D01*
G01X1126574Y1217322D02*
X1128444Y1215452D01*
G01Y1211712D02*
X1126574Y1209842D01*
G01X1160913Y772243D02*
Y769458D01*
X1155501Y764046D01*
Y753792D01*
X1148962Y747253D01*
G01X1147468Y766093D02*
X1149258Y767883D01*
X1155258D01*
X1157173Y769798D01*
Y772243D01*
G01X1146674Y778409D02*
X1152676D01*
X1153433Y779166D01*
Y782873D01*
G01X1149060Y797142D02*
Y800642D01*
G01Y806642D02*
Y810142D01*
G01D02*
X1150485D01*
X1153485Y813142D01*
G01X1149060Y800642D02*
X1152730D01*
X1154985Y802897D01*
G01X1144494Y1050045D02*
X1145146D01*
X1165837Y1070736D01*
Y1110737D01*
X1162106Y1114468D01*
G01X1154770Y1053324D02*
X1155924D01*
X1173377Y1070777D01*
Y1110677D01*
X1169586Y1114468D01*
G01X1147171Y1058763D02*
X1158495Y1070087D01*
Y1111490D01*
X1156495Y1113490D01*
Y1116338D01*
X1158365Y1118208D01*
G01X1262421Y1195059D02*
X1261114D01*
X1259801Y1196372D01*
Y1198998D01*
X1258566Y1200233D01*
X1256140D01*
X1248359Y1208014D01*
X1203571D01*
X1201785Y1209800D01*
X1198573D01*
X1197634Y1210739D01*
Y1212469D01*
X1196573Y1213530D01*
X1152703D01*
X1150885Y1211712D01*
G01Y1215452D02*
Y1262226D01*
X1152008Y1263349D01*
X1236752D01*
X1266721Y1233380D01*
X1269292D01*
X1274446Y1228226D01*
G01X1154625Y1215452D02*
Y1217670D01*
X1156404Y1219449D01*
X1157469D01*
X1158416Y1220396D01*
Y1241153D01*
X1158916Y1241653D01*
X1253230D01*
X1257348Y1237535D01*
G01X1269491Y1228760D02*
X1237051Y1261200D01*
X1156872D01*
X1154706Y1259034D01*
Y1219273D01*
X1152755Y1217322D01*
G01X1192957Y435158D02*
X1183763Y425964D01*
X1175485D01*
X1174132Y424611D01*
X1162673D01*
X1162139Y425145D01*
Y427017D01*
G01X1193000Y444841D02*
X1191572Y443413D01*
X1190731Y441384D01*
X1184110Y434763D01*
Y429998D01*
X1182340Y428228D01*
X1176947D01*
X1172172Y433003D01*
G01X1162107Y435029D02*
X1158257D01*
G01X1172172Y433003D02*
X1162959D01*
X1162107Y433855D01*
Y435029D01*
G01X1192702Y440489D02*
X1185754Y433541D01*
Y429658D01*
X1183180Y427084D01*
X1173649D01*
X1171755Y428978D01*
X1163043D01*
X1162107Y429914D01*
Y431029D01*
G01D02*
X1158257D01*
G01Y427029D02*
X1158269Y427017D01*
X1162139D01*
G01X1172742Y438323D02*
X1168685D01*
G01X1183855Y458714D02*
Y456446D01*
X1183380Y455971D01*
X1178507D01*
X1170711Y448175D01*
Y444739D01*
X1168928Y442956D01*
X1166868D01*
G01X1169697Y797485D02*
X1173697D01*
G01X1160197D02*
X1164197D01*
G01D02*
X1164732Y798020D01*
Y802269D01*
G01X1164338Y1055787D02*
X1165460D01*
X1180679Y1071006D01*
Y1109747D01*
X1177066Y1113360D01*
Y1114468D01*
G01X1169586Y1215452D02*
X1173073Y1218939D01*
Y1225534D01*
X1174073Y1226534D01*
X1247050D01*
X1249072Y1224512D01*
G01X1162105Y1215451D02*
X1163928Y1217274D01*
X1167273D01*
X1169528Y1219529D01*
Y1229455D01*
X1170536Y1230463D01*
X1243368D01*
X1245188Y1232283D01*
G01X1158365Y1215452D02*
X1159531D01*
X1162897Y1218818D01*
X1164536D01*
X1165798Y1220080D01*
Y1233930D01*
X1166298Y1234430D01*
X1246247D01*
X1259480Y1221197D01*
G01X1156495Y1217322D02*
X1159465D01*
X1162087Y1219944D01*
Y1237521D01*
X1162587Y1238021D01*
X1247987D01*
X1252057Y1233951D01*
G01X1188598Y384500D02*
Y381500D01*
G01X1175892Y438323D02*
Y440419D01*
X1174284Y442027D01*
Y443585D01*
G01D02*
Y445929D01*
X1177259Y448904D01*
X1185796D01*
X1186808Y449916D01*
Y451628D01*
G01X1182961Y442606D02*
X1182711Y442856D01*
X1178083D01*
G01X1182961Y446606D02*
X1179195D01*
X1179184Y446595D01*
G01X1269749Y937697D02*
X1265993D01*
X1250841Y922545D01*
Y875941D01*
X1199232Y824332D01*
Y806489D01*
X1184397Y791654D01*
Y773188D01*
X1176269Y765060D01*
X1173034D01*
G01X1173122Y802759D02*
X1173182Y802699D01*
Y800336D01*
X1173697Y799821D01*
Y797485D01*
G01X1177431Y874388D02*
Y878738D01*
G01X1184652Y886399D02*
X1181872Y883619D01*
Y881564D01*
X1179046Y878738D01*
X1177431D01*
G01Y871238D02*
X1180239Y868430D01*
G01X1187431Y878738D02*
Y874388D01*
G01X1183431D02*
Y876099D01*
X1182602Y876928D01*
Y879142D01*
G01X1187431Y874388D02*
X1183431D01*
G01X1182602Y879142D02*
X1183955Y880495D01*
Y882372D01*
X1185058Y883475D01*
G01X1187871Y895751D02*
Y891398D01*
X1184652Y888179D01*
Y886399D01*
G01X1181654Y894671D02*
Y905471D01*
X1182694Y906511D01*
X1195714D01*
X1196661Y907458D01*
Y922901D01*
G01X1187431Y881888D02*
X1188535Y882992D01*
Y886977D01*
X1190431Y888873D01*
G01X1181151Y919034D02*
X1185312Y914873D01*
Y910317D01*
G01X1187871Y916534D02*
Y910317D01*
G01X1181151Y926609D02*
Y930459D01*
G01X1177186D02*
X1175469Y928742D01*
Y915523D01*
X1174461Y914515D01*
G01X1181151Y923459D02*
Y919034D01*
G01X1187151Y926609D02*
X1185269D01*
X1184151Y925491D01*
Y920254D01*
X1187871Y916534D01*
G01X1187151Y930459D02*
Y926609D01*
G01X1181151Y930459D02*
X1177186D01*
G01X1190805Y959596D02*
Y956875D01*
X1188219Y954289D01*
Y951789D01*
G01D02*
Y947364D01*
X1189219Y946364D01*
G01X1187951Y976722D02*
Y980520D01*
X1187049Y981422D01*
X1183919D01*
X1181438Y978941D01*
G01D02*
Y974811D01*
X1182779Y973470D01*
Y971818D01*
G01X1190805Y976722D02*
Y981703D01*
X1187714Y984794D01*
G01D02*
X1186219Y986289D01*
Y992289D01*
X1186794Y992864D01*
X1189219D01*
G01X1177066Y1118208D02*
X1178258D01*
X1180114Y1116352D01*
X1182119D01*
X1182695Y1115776D01*
Y1113497D01*
X1183588Y1112604D01*
X1185195D01*
X1188357Y1109442D01*
Y1070257D01*
X1182708Y1064608D01*
X1179906D01*
G01X1177066Y1215452D02*
Y1221666D01*
X1178461Y1223061D01*
X1221159D01*
X1222027Y1222193D01*
Y1220041D01*
X1222836Y1219232D01*
X1243583D01*
X1245413Y1221062D01*
G01X1206693Y384410D02*
X1204603Y386500D01*
X1204173D01*
X1202673Y388000D01*
G01D02*
X1198248D01*
G01X1191748Y384500D02*
X1195098D01*
G01D02*
Y381075D01*
X1196673Y379500D01*
X1207325D01*
X1209872Y382047D01*
G01X1191748Y388000D02*
Y392676D01*
G01X1195098Y388000D02*
X1191748D01*
G01X1189761Y451628D02*
Y453766D01*
X1194567Y458572D01*
X1196403D01*
G01D02*
Y463235D01*
G01X1193253D02*
Y467350D01*
X1193270Y467367D01*
G01X1461474Y655807D02*
X1448602Y642935D01*
X1441542D01*
X1434936Y636329D01*
X1395151D01*
X1374820Y615998D01*
Y566219D01*
X1324650Y516049D01*
X1263450D01*
X1238359Y490958D01*
X1194922D01*
X1190517Y486553D01*
Y470120D01*
X1193270Y467367D01*
G01X1192431Y871238D02*
Y868620D01*
G01Y874388D02*
Y878738D01*
G01X1197152Y882399D02*
Y880899D01*
X1194991Y878738D01*
X1192431D01*
G01X1192990Y895751D02*
Y891251D01*
X1197152Y887089D01*
Y882399D01*
G01X1190431Y888873D02*
Y895751D01*
G01X1192651Y918534D02*
X1190431Y916314D01*
Y910317D01*
G01X1191151Y926609D02*
Y930459D01*
G01X1196661Y922901D02*
Y928916D01*
X1195118Y930459D01*
G01X1191151Y923459D02*
X1192651Y921959D01*
Y918534D01*
G01X1189219Y943214D02*
Y940703D01*
G01X1201219Y943214D02*
X1198650Y940645D01*
X1197173D01*
G01X1191151Y930459D02*
X1195118D01*
G01X1201219Y946364D02*
X1197219D01*
G01D02*
X1193365Y950218D01*
Y959596D01*
G01X1203219Y962789D02*
X1193719D01*
X1193365Y962435D01*
Y959596D01*
G01X1193219Y946364D02*
X1189219D01*
G01X1190805Y959596D02*
Y963375D01*
X1193219Y965789D01*
X1194989D01*
X1195522Y966322D01*
Y967467D01*
X1196055Y968000D01*
X1196809D01*
X1197342Y967467D01*
Y966322D01*
X1197875Y965789D01*
X1200794D01*
X1202719Y967714D01*
G01Y970864D02*
X1199294D01*
X1198719Y970289D01*
X1193719D01*
X1190719Y973289D01*
Y976636D01*
X1190805Y976722D01*
G01X1207219Y970864D02*
X1203794Y974289D01*
X1200219D01*
X1198219Y972289D01*
X1194719D01*
X1193365Y973643D01*
Y976722D01*
G01X1193483Y983053D02*
X1193365Y982935D01*
Y976722D01*
G01X1207219Y967714D02*
Y964790D01*
X1205218Y962789D01*
X1203219D01*
G01X1189219Y992864D02*
Y993944D01*
X1194261Y998986D01*
X1195914D01*
X1196300Y998600D01*
G01X1193219Y992864D02*
X1197622D01*
X1198365Y992121D01*
Y987935D01*
X1193483Y983053D01*
G01X1202028Y998349D02*
X1200034Y996355D01*
X1194974D01*
X1193219Y994600D01*
Y992864D01*
G01X1412698Y997590D02*
X1415906D01*
X1418722Y994774D01*
Y985673D01*
X1410216Y977167D01*
X1356323D01*
X1338040Y995450D01*
X1213286D01*
X1212975Y995761D01*
X1212246D01*
X1197915Y1010092D01*
Y1011876D01*
X1199700Y1013661D01*
G01X1203419Y1011161D02*
X1215348Y999232D01*
X1228644D01*
X1228800Y999076D01*
X1231668D01*
X1232201Y999609D01*
Y1000367D01*
X1232734Y1000900D01*
X1233488D01*
X1234021Y1000367D01*
Y999609D01*
X1234554Y999076D01*
X1235308D01*
X1235841Y999609D01*
Y1000367D01*
X1236374Y1000900D01*
X1237128D01*
X1237661Y1000367D01*
Y999609D01*
X1238194Y999076D01*
X1339595D01*
X1357684Y980987D01*
X1394542D01*
X1397592Y984037D01*
G01X1405090Y981903D02*
X1402074Y978887D01*
X1357422D01*
X1357042Y979267D01*
X1356971D01*
X1339068Y997170D01*
X1213999D01*
X1200008Y1011161D01*
G01X1419446Y977192D02*
X1416950Y974696D01*
X1355180D01*
X1335839Y994037D01*
X1212456D01*
X1211852Y994641D01*
X1211782D01*
X1196795Y1009628D01*
Y1012785D01*
X1196845Y1012835D01*
Y1014808D01*
X1201468Y1019431D01*
X1201800D01*
G01X1195767Y1144389D02*
X1197436Y1142720D01*
Y1135969D01*
X1198133Y1135272D01*
X1201314D01*
X1203286Y1133300D01*
X1206666D01*
X1207166Y1132800D01*
Y1114647D01*
X1205117Y1112598D01*
G01X1199507Y1144389D02*
X1201358Y1142538D01*
Y1139670D01*
X1202028Y1139000D01*
X1208200D01*
X1210400Y1136800D01*
X1213186D01*
X1214386Y1135600D01*
Y1114386D01*
X1212598Y1112598D01*
G01X1201377Y1149999D02*
X1208527D01*
X1208822Y1149704D01*
X1212298D01*
G01X1199507Y1148129D02*
X1201377Y1149999D01*
G01X1203247Y1140649D02*
X1205117Y1142519D01*
G01X1246056Y1205107D02*
X1244766D01*
X1243959Y1204300D01*
X1203179D01*
X1199507Y1207972D01*
G01X1255628Y1188345D02*
X1254636Y1189337D01*
X1253964D01*
X1242801Y1200500D01*
X1202586D01*
X1200886Y1202200D01*
X1198073D01*
X1197573Y1202700D01*
Y1206166D01*
X1195767Y1207972D01*
G01X1258237Y1203115D02*
X1256597Y1204755D01*
X1245947Y1211871D01*
X1203088D01*
X1199507Y1215452D01*
G01X1195767D02*
X1197637Y1217322D01*
X1201564D01*
X1203486Y1215400D01*
X1253166D01*
X1266437Y1202129D01*
Y1199565D01*
X1268376Y1197626D01*
X1273370D01*
G01X1217660Y178560D02*
X1214056Y182164D01*
Y185997D01*
X1207753Y192300D01*
G01X1210268Y198671D02*
X1224431D01*
X1231117Y191985D01*
X1281782D01*
X1287963Y198166D01*
X1327298D01*
X1328799Y196665D01*
G01X1213173Y377912D02*
X1217881D01*
G01Y389912D02*
X1213935Y393858D01*
X1206531D01*
G01X1217881Y381912D02*
X1213293Y386500D01*
X1213173D01*
G01X1217881Y385912D02*
X1212297Y391496D01*
X1212173D01*
G01X1217881Y401924D02*
X1213098D01*
X1209757Y398583D01*
X1208173D01*
G01X1217881Y393924D02*
Y397912D01*
G01D02*
X1213261D01*
G01X1217881Y405924D02*
X1212597D01*
X1210173Y403500D01*
G01X1217881Y409924D02*
X1215097D01*
X1214173Y409000D01*
X1212173D01*
G01X1246300Y1027800D02*
X1245962Y1028138D01*
Y1035675D01*
X1214468Y1067169D01*
Y1110728D01*
X1212598Y1112598D01*
G01X1252148Y1026223D02*
Y1027819D01*
X1249935Y1030032D01*
Y1034990D01*
X1218337Y1066588D01*
Y1109500D01*
X1219512Y1110675D01*
X1221612D01*
X1222186Y1111249D01*
Y1137999D01*
X1221111Y1139074D01*
X1212298D01*
G01X1223818Y1142519D02*
Y1145583D01*
X1222847Y1146554D01*
X1212298D01*
G01X1205117Y1142519D02*
X1210133D01*
X1210428Y1142224D01*
X1212298D01*
G01X1205617Y1179625D02*
X1209465D01*
X1210623Y1178467D01*
G01X1210185Y1185514D02*
X1208627Y1183956D01*
X1205617D01*
G01X1227017Y94279D02*
X1233286Y88010D01*
Y70754D01*
X1225243Y62711D01*
Y60438D01*
G01X1223068Y94351D02*
X1228127Y89292D01*
Y68647D01*
X1222383Y62903D01*
Y60513D01*
G01X1226437Y192665D02*
X1228837Y190265D01*
X1282495D01*
X1288676Y196446D01*
X1325018D01*
X1328799Y192665D01*
G01X1226550Y186778D02*
X1228317Y188545D01*
X1283208D01*
X1289389Y194726D01*
X1320964D01*
X1328912Y186778D01*
G01X1229438Y332584D02*
X1247900Y351046D01*
X1284078D01*
X1292738Y359706D01*
X1307280D01*
X1314374Y366800D01*
X1369599D01*
X1395242Y392443D01*
X1402656D01*
X1408254Y398041D01*
G01X1275794Y1134729D02*
X1273130Y1137393D01*
X1267223D01*
X1266061Y1136231D01*
Y1095935D01*
X1288391Y1073605D01*
Y1045038D01*
X1248106Y1004753D01*
Y1004700D01*
G01X1245400Y1003700D02*
Y1004900D01*
X1247900Y1007400D01*
X1248301D01*
X1259463Y1018562D01*
Y1041597D01*
X1250946Y1050114D01*
X1250922D01*
X1246443Y1054593D01*
Y1075414D01*
X1263921Y1092892D01*
Y1134729D01*
G01X1253424Y1138130D02*
Y1087625D01*
X1243070Y1077271D01*
Y1051236D01*
X1255845Y1038461D01*
Y1023645D01*
X1247000Y1014800D01*
X1246000D01*
G01X1254200Y1146600D02*
X1254246Y1146554D01*
Y1140328D01*
X1255559Y1139015D01*
Y1087443D01*
X1244620Y1076504D01*
Y1069713D01*
X1244670Y1069663D01*
Y1053933D01*
X1257683Y1040920D01*
Y1021155D01*
X1252500Y1015972D01*
Y1014288D01*
G01X1255296Y1196056D02*
Y1197017D01*
X1253713Y1198600D01*
Y1200040D01*
X1251853Y1201900D01*
X1251313D01*
X1250534Y1201121D01*
Y1200457D01*
X1252150Y1198841D01*
Y1198177D01*
X1251633Y1197660D01*
X1250969D01*
X1249353Y1199276D01*
X1248689D01*
X1247946Y1198533D01*
X1247282D01*
X1246765Y1199050D01*
Y1199714D01*
X1249839Y1202788D01*
Y1203452D01*
X1248955Y1204336D01*
X1247094Y1205107D01*
X1246056D01*
G01X1249072Y1224512D02*
X1272541Y1201043D01*
G01X1245413Y1221062D02*
X1250402D01*
X1268571Y1202893D01*
Y1201043D01*
G01X1245188Y1232283D02*
X1274196Y1203275D01*
X1274339D01*
X1276575Y1201039D01*
G01X1252057Y1233951D02*
X1266113Y1219895D01*
G01X1253904Y1519645D02*
Y1484378D01*
X1292015Y1446267D01*
X1307290D01*
X1313740Y1452717D01*
G01X1250055Y1710189D02*
X1543384D01*
X1547874Y1714679D01*
Y1715699D01*
X1543384Y1720189D01*
X1250055D01*
G01X1263805Y327257D02*
X1267562D01*
G01X1262500Y330655D02*
Y329244D01*
X1262965Y328779D01*
Y327946D01*
X1263654Y327257D01*
X1263805D01*
G01X1276425Y334500D02*
X1265500D01*
X1264215Y333215D01*
G01X1262500Y330655D02*
X1264007Y331279D01*
X1265494D01*
X1266636Y332421D01*
X1274504D01*
X1276425Y330500D01*
G01X1269733Y864397D02*
X1271438Y861846D01*
G01X1274396Y866896D02*
X1272244D01*
X1271593Y867547D01*
X1269733D01*
G01X1269221Y894760D02*
X1269130Y894669D01*
X1266596D01*
X1262713Y898552D01*
Y920485D01*
X1269401Y927173D01*
X1285474D01*
X1287035Y925612D01*
X1296711D01*
X1297806Y926707D01*
Y929258D01*
X1303055Y934507D01*
Y936558D01*
X1306227Y939730D01*
X1324830D01*
X1326065Y940965D01*
X1355248D01*
X1356055Y941772D01*
X1359219D01*
X1359947Y941044D01*
X1363052D01*
X1364275Y942267D01*
X1367403D01*
X1368554Y941116D01*
X1371323D01*
X1373768Y943561D01*
X1381536D01*
X1385555Y939542D01*
X1410203D01*
X1412946Y942285D01*
X1416244D01*
G01X1270276Y897062D02*
X1266936D01*
X1264942Y899056D01*
Y919478D01*
X1270983Y925519D01*
X1284467D01*
X1285924Y924062D01*
X1297931D01*
X1299532Y925663D01*
Y928719D01*
X1304745Y933932D01*
X1313805D01*
X1318053Y938180D01*
X1325880D01*
X1327057Y939357D01*
X1351343D01*
X1354279Y936421D01*
X1412509D01*
X1412606Y936324D01*
X1416281D01*
X1416802Y936845D01*
G01X1480144Y946880D02*
X1482205Y944819D01*
Y942402D01*
X1481358Y941555D01*
X1478412D01*
X1477620Y942347D01*
X1432137D01*
X1431634Y942850D01*
X1423427D01*
X1419103Y938526D01*
Y932760D01*
X1418604Y932261D01*
X1388016D01*
X1385904Y934373D01*
X1348218D01*
X1344913Y937678D01*
X1327678D01*
X1326275Y936275D01*
X1319301D01*
X1315407Y932381D01*
X1309725D01*
X1307236Y929892D01*
Y924642D01*
X1305082Y922488D01*
X1284368D01*
X1282966Y923890D01*
X1272716D01*
X1268437Y919611D01*
Y913425D01*
X1271601Y910261D01*
X1277139D01*
X1279944Y913066D01*
X1289781D01*
X1295897Y906950D01*
X1304994D01*
X1310780Y901164D01*
X1314326D01*
X1319562Y895928D01*
X1320267D01*
X1321644Y894551D01*
G01X1323549Y897045D02*
X1321556Y899038D01*
X1318753D01*
X1315197Y902594D01*
X1311984D01*
X1306078Y908500D01*
X1296540D01*
X1290424Y914616D01*
X1279301D01*
X1276496Y911811D01*
X1272244D01*
X1269987Y914068D01*
Y918968D01*
X1273359Y922340D01*
X1282323D01*
X1283725Y920938D01*
X1305725D01*
X1308786Y923999D01*
Y929249D01*
X1310368Y930831D01*
X1320691D01*
X1322758Y928764D01*
X1325275D01*
X1326210Y929699D01*
Y934014D01*
X1328273Y936077D01*
X1344249D01*
X1347554Y932772D01*
X1385240D01*
X1387711Y930301D01*
X1419416D01*
X1421063Y931948D01*
Y937950D01*
X1424326Y941213D01*
X1429495D01*
X1429980Y940728D01*
X1460686D01*
X1461888Y939526D01*
Y936055D01*
G01X1306385Y1036646D02*
Y1036952D01*
X1290249Y1053088D01*
Y1074456D01*
X1267921Y1096784D01*
Y1134729D01*
G01X1264575Y1201043D02*
Y1197213D01*
X1262421Y1195059D01*
G01X1258237Y1203115D02*
X1261538Y1199814D01*
G01X1259480Y1221197D02*
X1263449Y1217228D01*
G01X1257348Y1237535D02*
X1269388Y1225495D01*
Y1223170D01*
G01X1269491Y1228760D02*
X1272235Y1226016D01*
G01X1270712Y327257D02*
X1271277Y326692D01*
X1303000D01*
G01X1289345Y330655D02*
X1283154D01*
X1282999Y330500D01*
X1279575D01*
G01X1292500Y335000D02*
X1280075D01*
X1279575Y334500D01*
G01X1377024Y397713D02*
Y391424D01*
X1354400Y368800D01*
X1313846D01*
X1306539Y361493D01*
X1286535D01*
X1284419Y359377D01*
G01X1458214Y406231D02*
X1428686D01*
X1424945Y402490D01*
X1374440D01*
X1347850Y375900D01*
X1331337D01*
X1330300Y374863D01*
X1287385D01*
X1284466Y371944D01*
X1279842D01*
X1274436Y377350D01*
G01X1279460Y874487D02*
X1284865D01*
X1287314Y872038D01*
X1290604D01*
X1292757Y869885D01*
X1301267D01*
X1302411Y871029D01*
X1307190D01*
X1308661Y872500D01*
X1316000D01*
X1317464Y873964D01*
X1320055D01*
G01X1279460Y879487D02*
X1277274Y877301D01*
Y873549D01*
X1278552Y872271D01*
X1284580D01*
X1286637Y870214D01*
X1290304D01*
X1292057Y868461D01*
X1301629D01*
X1302972Y869804D01*
X1308461D01*
X1309265Y869000D01*
X1311421D01*
X1313289Y870868D01*
X1316868D01*
X1318390Y872390D01*
G01X1276142Y905173D02*
X1270737D01*
X1270586Y905324D01*
G01X1340524Y894087D02*
X1341973Y895536D01*
Y906808D01*
X1340234Y908547D01*
X1336711D01*
X1329501Y915757D01*
X1314293D01*
X1310870Y919180D01*
X1289740D01*
X1287163Y916603D01*
X1279792D01*
X1276587Y919808D01*
X1274670D01*
G01X1276049Y940256D02*
X1281400D01*
G01D02*
Y938481D01*
X1282107Y937774D01*
X1293528D01*
X1294289Y938535D01*
X1298777D01*
X1300323Y940081D01*
Y940441D01*
X1301437Y941555D01*
X1304422D01*
X1304577Y941400D01*
X1322015D01*
X1323551Y942936D01*
Y944829D01*
X1325222Y946500D01*
X1337400D01*
X1339600Y944300D01*
X1342984D01*
X1345340Y946656D01*
X1384120D01*
X1389010Y941766D01*
X1408688D01*
X1411586Y944664D01*
X1478941D01*
X1480109Y943496D01*
G01X1271921Y1134729D02*
Y1095217D01*
X1291969Y1075169D01*
Y1053801D01*
X1301834Y1043936D01*
X1305971D01*
X1312873Y1037034D01*
Y1036543D01*
G01X1310773Y1282411D02*
X1310051Y1283133D01*
Y1285990D01*
X1309270Y1286771D01*
X1306264D01*
X1292037Y1272544D01*
Y1250422D01*
X1279939Y1238324D01*
Y1216598D01*
X1285705Y1210832D01*
Y1083866D01*
X1293689Y1075882D01*
Y1054514D01*
X1302547Y1045656D01*
X1318799D01*
X1322773Y1041682D01*
Y1040599D01*
G01X1273370Y1197626D02*
X1278609D01*
X1280575Y1199592D01*
Y1200969D01*
G01X1308107Y1283395D02*
X1307085Y1282373D01*
X1303758D01*
X1293296Y1271911D01*
Y1249351D01*
X1281339Y1237394D01*
Y1217084D01*
X1287065Y1211358D01*
Y1084090D01*
X1294809Y1076346D01*
Y1054978D01*
X1303011Y1046776D01*
X1319629D01*
X1325071Y1041334D01*
Y1039375D01*
X1323572Y1037876D01*
X1320549D01*
G01X1336551Y26534D02*
X1334382D01*
X1328340Y20492D01*
X1311099D01*
X1305266Y26325D01*
X1302139D01*
G01X1289032Y866935D02*
X1302185D01*
X1302954Y867704D01*
X1305786D01*
G01X1296425Y879800D02*
X1293500D01*
G01X1296425Y871800D02*
X1293500D01*
G01X1296425Y875800D02*
X1293500D01*
G01X1299575Y879800D02*
X1307300D01*
X1307500Y880000D01*
G01X1291039Y881802D02*
X1297573D01*
X1299575Y879800D01*
G01X1314641Y874641D02*
X1312641D01*
X1312129Y874129D01*
X1307949D01*
X1306449Y872629D01*
X1300404D01*
X1299575Y871800D01*
G01Y875800D02*
X1301877D01*
X1304050Y874900D01*
G01X1296866Y894993D02*
Y892241D01*
X1296425Y891800D01*
G01X1305250Y889250D02*
X1303800Y887800D01*
X1299575D01*
G01X1296425D02*
Y889792D01*
X1296713Y890080D01*
X1298801D01*
X1299575Y890854D01*
Y891800D01*
G01X1296425Y887800D02*
X1293272D01*
G01X1293500Y883800D02*
X1296425D01*
G01X1291039Y885651D02*
X1291649D01*
X1293500Y883800D01*
G01X1299575D02*
X1303800D01*
X1304000Y884000D01*
G01X1324470Y908192D02*
X1314320D01*
X1311034Y911478D01*
X1300029D01*
G01X1288500Y901254D02*
Y904120D01*
G01X1296466Y899610D02*
Y903469D01*
G01X1292836Y975244D02*
X1317688D01*
X1321417Y978973D01*
X1346842D01*
X1354073Y971742D01*
X1418345D01*
X1419821Y973219D01*
X1435669Y989066D01*
Y1005366D01*
G01X1336623Y30483D02*
X1333995D01*
X1333126Y29614D01*
X1327133D01*
X1323170Y25651D01*
X1309618D01*
X1304101Y31168D01*
X1302785D01*
G01X1320022Y178560D02*
X1316418Y182164D01*
Y185997D01*
X1310115Y192300D01*
G01X1319000Y685500D02*
X1310798Y693702D01*
Y728697D01*
X1314601Y732500D01*
X1319000D01*
G01X1315000Y811620D02*
Y816425D01*
G01Y819575D02*
Y824500D01*
X1317276Y826776D01*
G01D02*
X1321500Y831000D01*
Y834465D01*
X1323205Y836170D01*
G01X1306416Y838266D02*
X1303628Y841054D01*
G01X1307500Y880000D02*
X1312000D01*
X1313310Y878690D01*
G01X1314641Y874641D02*
X1316101D01*
X1317000Y875540D01*
G01X1320055Y877114D02*
X1312614D01*
X1311229Y875729D01*
X1307460D01*
X1305459Y874900D01*
X1304050D01*
G01X1304000Y884000D02*
X1310839D01*
X1313000Y881839D01*
G01X1306075Y944000D02*
X1312549D01*
X1312575Y943974D01*
G01X1328799Y192665D02*
X1331199Y190265D01*
X1432496D01*
X1438753Y196522D01*
X1474943D01*
X1478800Y192665D01*
G01X1328799Y196665D02*
X1333479Y191985D01*
X1431783D01*
X1438040Y198242D01*
X1477223D01*
X1478800Y196665D01*
G01X1328912Y186778D02*
X1330679Y188545D01*
X1433209D01*
X1439466Y194802D01*
X1470889D01*
X1478913Y186778D01*
G01X1331922Y359836D02*
X1332386Y360300D01*
X1368029D01*
X1383380Y344949D01*
X1391937D01*
X1394952Y347964D01*
X1404536D01*
X1406372Y349800D01*
X1439132D01*
X1439719Y350387D01*
G01X1333000Y816425D02*
Y813620D01*
X1331000Y811620D01*
G01X1328500Y816425D02*
Y813120D01*
X1327000Y811620D01*
G01X1324000Y816425D02*
Y812620D01*
X1323000Y811620D01*
G01X1337500Y816425D02*
Y814120D01*
X1335000Y811620D01*
G01X1319500Y816425D02*
Y814001D01*
X1319000Y813501D01*
Y811620D01*
G01X1330850Y830350D02*
X1324000Y823500D01*
Y819575D01*
G01X1334229Y833729D02*
X1330850Y830350D01*
G01X1331877Y825377D02*
X1328500Y822000D01*
Y819575D01*
G01X1331877Y825377D02*
X1334800Y828300D01*
G01X1321972Y825042D02*
X1319500Y822570D01*
Y819575D01*
G01X1321972Y825042D02*
X1327930Y831000D01*
G01X1333000Y819575D02*
X1337463Y824038D01*
G01X1324778Y895816D02*
X1323549Y897045D01*
G01X1337384Y897337D02*
X1336698Y898023D01*
X1335269D01*
X1333755Y899537D01*
Y905337D01*
X1330900Y908192D01*
X1324470D01*
G01X1338500Y921075D02*
Y922441D01*
X1336557Y924384D01*
Y927564D01*
X1335709Y928412D01*
X1330941D01*
X1329199Y930154D01*
Y933825D01*
G01X1339685Y1109319D02*
X1338714D01*
X1337265Y1107870D01*
X1333672D01*
X1332669Y1106867D01*
G01X1332455Y1111198D02*
Y1108817D01*
X1332669Y1108603D01*
Y1106867D01*
G01X1434697Y347125D02*
X1430797Y343225D01*
X1394901D01*
X1390776Y339100D01*
X1385199D01*
X1384199Y340100D01*
X1382304D01*
X1380141Y342263D01*
Y345559D01*
X1367800Y357900D01*
X1362100D01*
X1349636Y345436D01*
Y340862D01*
G01X1351000Y816425D02*
Y811620D01*
G01X1346500Y816425D02*
Y814000D01*
X1347000Y813500D01*
Y811620D01*
G01X1342000Y816425D02*
Y812620D01*
X1343000Y811620D01*
G01X1348000Y832000D02*
Y830000D01*
X1346500Y828500D01*
Y819575D01*
G01X1342103Y836170D02*
X1343500Y834773D01*
Y832000D01*
X1344000Y831500D01*
Y825500D01*
G01D02*
Y821575D01*
X1342000Y819575D01*
G01X1351000D02*
X1353000Y821575D01*
Y824000D01*
G01X1337500Y819575D02*
X1341500Y823575D01*
Y831000D01*
G01X1340535Y835200D02*
Y833465D01*
X1341500Y832500D01*
Y831000D01*
G01X1337463Y824038D02*
X1338953Y825528D01*
Y836170D01*
G01X1345252D02*
X1348000Y833422D01*
Y832000D01*
G01X1343674Y895474D02*
X1344600Y896400D01*
Y906730D01*
X1340413Y910917D01*
Y911087D01*
X1338500Y913000D01*
G01X1351550Y892862D02*
X1348134Y896278D01*
G01X1343500Y911000D02*
X1342500Y912000D01*
Y917925D01*
G01X1354699Y892862D02*
Y894155D01*
X1348935Y899919D01*
Y905565D01*
X1343500Y911000D01*
G01X1348500Y913500D02*
X1349500Y912500D01*
Y910062D01*
X1350120Y909442D01*
X1353914D01*
X1356274Y907082D01*
Y895400D01*
G01X1350500Y917925D02*
Y916000D01*
X1356141Y910359D01*
G01X1338500Y917925D02*
Y913000D01*
G01X1346500Y917925D02*
Y915500D01*
X1348500Y913500D01*
G01X1342500Y921075D02*
X1340635Y922940D01*
Y928365D01*
X1338500Y930500D01*
G01X1346500Y921075D02*
X1344635Y922940D01*
Y928365D01*
X1342500Y930500D01*
G01X1350500Y921075D02*
X1348635Y922940D01*
Y928365D01*
X1346500Y930500D01*
G01X1354500Y921075D02*
X1352635Y922940D01*
Y928365D01*
X1350500Y930500D01*
G01X1369000Y816425D02*
Y813620D01*
X1367000Y811620D01*
G01X1355000D02*
Y814000D01*
X1355500Y814500D01*
Y816425D01*
G01X1364500D02*
Y813120D01*
X1363000Y811620D01*
G01X1360000Y816425D02*
Y812620D01*
X1359000Y811620D01*
G01X1354699Y836170D02*
Y833000D01*
X1357249Y830450D01*
Y827251D01*
X1360000Y824500D01*
G01D02*
Y819575D01*
G01X1353000Y824000D02*
Y826500D01*
X1352000Y827500D01*
Y833087D01*
X1351550Y833537D01*
Y836170D01*
G01X1365730Y827770D02*
X1369000Y824500D01*
G01X1361500Y831500D02*
Y829500D01*
X1364500Y826500D01*
Y819575D01*
G01X1359426Y833574D02*
X1361500Y831500D01*
G01X1355000Y829500D02*
Y826624D01*
X1355500Y826124D01*
Y819575D01*
G01X1355000Y829500D02*
X1353137Y831363D01*
Y834400D01*
G01X1356141Y910359D02*
X1358000Y908500D01*
Y895861D01*
X1360999Y892862D01*
G01X1362510Y912490D02*
X1364900Y910100D01*
Y899196D01*
X1367500Y896596D01*
Y893064D01*
X1367298Y892862D01*
G01X1362566Y897934D02*
X1361000Y899500D01*
Y904000D01*
G01X1358500Y917925D02*
Y916500D01*
X1362510Y912490D01*
G01X1354500Y917925D02*
Y916000D01*
X1361000Y909500D01*
Y904000D01*
G01X1362500Y917925D02*
X1368155Y912270D01*
G01X1366500Y917925D02*
X1372000Y912425D01*
Y910000D01*
X1372600Y909400D01*
Y906458D01*
G01X1366500Y921075D02*
X1364635Y922940D01*
Y928365D01*
X1362500Y930500D01*
G01X1358500Y921075D02*
X1356635Y922940D01*
Y928365D01*
X1354500Y930500D01*
G01X1362500Y921075D02*
X1360635Y922940D01*
Y928365D01*
X1358500Y930500D01*
G01X1370500Y921075D02*
X1368635Y922940D01*
Y928365D01*
X1366500Y930500D01*
G01X1371792Y1109320D02*
X1370922D01*
X1369270Y1107668D01*
X1365598D01*
X1364797Y1106867D01*
G01X1364666Y1111198D02*
Y1108734D01*
X1364797Y1108603D01*
Y1106867D01*
G01X1365625Y1422900D02*
X1365709Y1422984D01*
Y1452717D01*
G01X1373500Y816425D02*
Y814120D01*
X1371000Y811620D01*
G01X1382667Y816296D02*
Y813526D01*
X1381428Y812287D01*
G01X1473489Y861354D02*
X1472861Y860726D01*
X1435061D01*
X1418862Y844527D01*
Y812000D01*
X1414070Y807208D01*
X1386507D01*
X1381428Y812287D01*
G01X1369000Y824500D02*
Y819575D01*
G01X1378000D02*
X1373500D01*
G01X1375480Y824745D02*
Y823263D01*
X1373500Y821283D01*
Y819575D01*
G01X1372914Y828814D02*
X1375480Y826248D01*
Y824745D01*
G01X1381481Y825415D02*
X1382667Y824229D01*
Y819446D01*
G01X1376747Y836170D02*
Y830149D01*
X1381481Y825415D01*
G01X1376747Y839320D02*
X1379567Y836500D01*
X1386287D01*
G01X1377500Y904000D02*
X1378500Y901585D01*
Y899500D01*
X1375172Y896172D01*
Y894600D01*
G01X1378317Y894670D02*
X1381418Y897771D01*
Y901553D01*
X1382500Y902635D01*
Y907500D01*
G01X1368155Y912270D02*
X1369300Y911125D01*
Y901201D01*
X1370447Y900054D01*
Y892862D01*
G01X1380000Y912500D02*
Y898715D01*
X1376747Y895462D01*
Y892862D01*
G01X1372022Y894500D02*
Y903776D01*
X1372600Y904354D01*
Y906458D01*
G01X1374500Y912000D02*
X1375500Y911000D01*
Y905707D01*
X1373597Y901111D01*
Y892862D01*
G01X1374500Y917925D02*
X1377500Y914925D01*
Y904000D01*
G01X1382500Y917925D02*
Y907500D01*
G01X1378500Y917925D02*
X1380000Y916425D01*
Y912500D01*
G01X1370500Y917925D02*
X1374500Y913925D01*
Y912000D01*
G01X1378500Y921075D02*
X1376267Y923308D01*
Y928733D01*
X1374500Y930500D01*
G01Y921075D02*
X1372385Y923190D01*
Y928615D01*
X1370500Y930500D01*
G01X1382500Y921075D02*
X1384411Y922986D01*
Y926574D01*
X1383544Y927441D01*
X1381559D01*
X1378500Y930500D01*
G01X1383162Y991829D02*
X1390954Y984037D01*
X1394442D01*
G01X1379858Y1420701D02*
X1383032Y1423875D01*
Y1452717D01*
G01X1409900Y1442356D02*
Y1504100D01*
X1378600Y1535400D01*
Y1619900D01*
X1376098Y1622402D01*
X1374370D01*
G01X1386008Y569000D02*
X1390741D01*
G01X1386008Y561000D02*
Y565000D01*
G01D02*
X1390741D01*
G01X1386008Y611500D02*
X1390741D01*
G01X1386008Y607500D02*
Y611500D01*
G01Y615500D02*
X1390741D01*
G01X1386287Y836500D02*
X1389098D01*
X1397707Y845109D01*
X1399872D01*
G01X1386295Y917925D02*
Y914087D01*
X1387753Y912629D01*
G01X1401265Y989465D02*
Y985538D01*
X1399764Y984037D01*
X1397592D01*
G01X1398854Y987277D02*
Y989762D01*
X1400871Y991779D01*
X1407658D01*
X1408740Y992861D01*
G01X1393081Y1027202D02*
X1388128D01*
G01D02*
X1388012D01*
X1385732Y1029482D01*
G01X1387813Y1030952D02*
X1389412Y1032551D01*
X1393909D01*
G01X1398289Y1027044D02*
Y1028171D01*
X1393909Y1032551D01*
G01X1405189Y1109318D02*
X1404194D01*
X1402653Y1107777D01*
X1399166D01*
X1398256Y1106867D01*
G01X1398113Y1111258D02*
Y1108746D01*
X1398256Y1108603D01*
Y1106867D01*
G01X1427000Y802500D02*
X1423522D01*
X1419626Y798604D01*
Y770726D01*
X1414368Y765468D01*
Y721368D01*
X1410000Y717000D01*
G01X1427000Y846500D02*
X1426715D01*
X1422370Y842155D01*
Y809578D01*
X1417111Y804319D01*
Y772199D01*
X1410000Y765088D01*
Y761000D01*
G01X1402064Y961181D02*
Y965913D01*
G01X1405090Y981903D02*
X1407265Y984078D01*
Y989465D01*
G01D02*
X1410831D01*
X1411890Y990524D01*
Y992861D01*
G01X1407431Y1024254D02*
Y1028267D01*
G01X1402215Y1020440D02*
Y1023590D01*
X1402809Y1024184D01*
G01D02*
X1402879Y1024254D01*
X1407431D01*
G01X1407825Y1423700D02*
Y1426975D01*
G01X1410975Y1423700D02*
Y1429525D01*
X1409900Y1430600D01*
Y1442356D01*
G01X1430444Y602800D02*
X1430944Y603300D01*
Y605443D01*
G01X1431000Y591000D02*
Y594444D01*
X1430444Y595000D01*
Y599650D01*
G01X1430217Y871027D02*
X1433530D01*
X1435082Y869475D01*
G01X1430217Y874177D02*
Y880162D01*
G01D02*
Y888308D01*
X1433833Y891924D01*
X1436172D01*
X1439508Y895260D01*
X1453372D01*
X1455141Y897029D01*
Y904833D01*
G01X1427925Y901500D02*
Y905500D01*
G01D02*
X1427720Y905295D01*
X1423190D01*
G01X1427925Y897500D02*
Y901500D01*
G01X1431075Y905500D02*
X1432010Y906435D01*
Y913916D01*
X1424897Y921029D01*
Y936777D01*
G01X1429907Y936998D02*
X1436575Y930330D01*
Y923924D01*
X1442641Y917858D01*
Y904833D01*
G01X1437352Y1109344D02*
X1436519D01*
X1434999Y1107824D01*
X1431341D01*
X1430384Y1106867D01*
G01X1430356Y1111197D02*
Y1108631D01*
X1430384Y1108603D01*
Y1106867D01*
G01X1548616Y931602D02*
X1544598Y935620D01*
Y969532D01*
X1555141Y980075D01*
X1639311D01*
X1644215Y975171D01*
X1768712D01*
X1785695Y992154D01*
Y998731D01*
X1781878Y1002548D01*
X1768931D01*
X1758396Y1013083D01*
Y1017569D01*
X1761850Y1021023D01*
Y1023664D01*
X1758396Y1027118D01*
Y1115049D01*
X1748644Y1124801D01*
Y1202617D01*
X1744778Y1206483D01*
Y1215562D01*
X1745528Y1216312D01*
Y1241824D01*
X1771573Y1267869D01*
X1801310D01*
X1835487Y1302046D01*
Y1458715D01*
X1747986Y1546216D01*
X1594918D01*
X1581541Y1532839D01*
X1444950D01*
X1437768Y1525657D01*
Y1513487D01*
X1427094Y1502813D01*
X1421964D01*
G01X1429587Y1527450D02*
X1440617Y1538480D01*
X1540402D01*
X1553635Y1551713D01*
Y1578045D01*
X1556260Y1580670D01*
G01X1448994Y596782D02*
X1445108Y600668D01*
Y601079D01*
G01X1441958D02*
X1438893D01*
X1434944Y597130D01*
G01X1447003Y874859D02*
Y873715D01*
X1444075Y870787D01*
X1438950D01*
X1435043Y874694D01*
G01X1442641Y883233D02*
Y886755D01*
X1441633Y887763D01*
X1434858D01*
G01D02*
Y883217D01*
G01X1447641Y883233D02*
Y889614D01*
X1445367Y891888D01*
G01X1445141Y883233D02*
Y888039D01*
X1441223Y891957D01*
G01X1443231Y899006D02*
Y900495D01*
X1445141Y902405D01*
Y904833D01*
G01X1440141D02*
Y899602D01*
X1439103Y898564D01*
G01X1447261Y898571D02*
X1448142Y899452D01*
Y900400D01*
X1450141Y902399D01*
Y904833D01*
G01X1447641D02*
Y908750D01*
X1448633Y909742D01*
X1463171D01*
X1467508Y905405D01*
G01X1440425Y931500D02*
Y927000D01*
G01X1454809Y928108D02*
X1453733D01*
X1450061Y924436D01*
X1448581D01*
G01D02*
X1441307D01*
X1440425Y925318D01*
Y927000D01*
G01Y936000D02*
X1435516D01*
G01X1443575Y931500D02*
Y936000D01*
G01D02*
X1445564D01*
X1445976Y935588D01*
X1448743D01*
G01X1548504Y915689D02*
Y925289D01*
X1542358Y931435D01*
Y970462D01*
X1554211Y982315D01*
X1640239D01*
X1644917Y977637D01*
X1768010D01*
X1783455Y993082D01*
Y997803D01*
X1780950Y1000308D01*
X1768003D01*
X1756156Y1012155D01*
Y1114121D01*
X1746199Y1124078D01*
Y1201114D01*
X1742289Y1205024D01*
Y1216547D01*
X1742972Y1217230D01*
Y1242436D01*
X1770645Y1270109D01*
X1800382D01*
X1833247Y1302974D01*
Y1456675D01*
X1752244Y1537678D01*
X1607294D01*
X1596817Y1527201D01*
X1443103D01*
G01X1441145Y1540415D02*
X1540055D01*
X1552022Y1552382D01*
Y1617978D01*
X1547598Y1622402D01*
G01X1548629Y927836D02*
X1543478Y932987D01*
Y969997D01*
X1554676Y981195D01*
X1639775D01*
X1644497Y976473D01*
X1768430D01*
X1784575Y992618D01*
Y998267D01*
X1781414Y1001428D01*
X1768467D01*
X1757276Y1012619D01*
Y1114585D01*
X1747343Y1124518D01*
Y1201740D01*
X1743653Y1205430D01*
Y1216093D01*
X1744304Y1216744D01*
Y1242184D01*
X1771109Y1268989D01*
X1800846D01*
X1834367Y1302510D01*
Y1457465D01*
X1753034Y1538798D01*
X1604412D01*
X1602160Y1536546D01*
X1594649D01*
X1588979Y1530876D01*
X1446135D01*
G01X1440153Y1563093D02*
X1455934Y1547312D01*
X1544587D01*
X1550350Y1553075D01*
Y1604296D01*
X1547598Y1607048D01*
G01X1443769Y1562173D02*
X1459193D01*
X1470309Y1573289D01*
Y1614404D01*
X1478307Y1622402D01*
G01X1457641Y883233D02*
Y880678D01*
X1458531Y879788D01*
Y876216D01*
X1457174Y874859D01*
G01D02*
X1450153D01*
G01X1461113Y871389D02*
X1466075D01*
G01X1455141Y883233D02*
Y886687D01*
X1457218Y888764D01*
G01X1450141Y883233D02*
Y886783D01*
X1449803Y887121D01*
Y889931D01*
X1451840Y891968D01*
X1455883D01*
X1456737Y892822D01*
X1462391D01*
G01D02*
X1462500Y892931D01*
Y897425D01*
G01X1452641Y888033D02*
Y883233D01*
G01X1451286Y898549D02*
Y899797D01*
X1452641Y901152D01*
Y904833D01*
G01X1462500Y900575D02*
Y905295D01*
G01X1448743Y935588D02*
X1454809D01*
G01X1466026Y957819D02*
X1462819D01*
X1462000Y957000D01*
G01X1466026Y962937D02*
X1462095D01*
X1461371Y962213D01*
X1460127D01*
X1458202Y960288D01*
G01X1457937Y966712D02*
Y970421D01*
X1459138Y971622D01*
X1464706D01*
G01X1459519Y989432D02*
Y979157D01*
X1461936Y976740D01*
X1464706D01*
G01X1475096Y988813D02*
Y987198D01*
X1474576Y986678D01*
X1469910D01*
X1469285Y987303D01*
Y990214D01*
X1467771Y991728D01*
X1465396D01*
X1464219Y990551D01*
Y985094D01*
X1466295Y983018D01*
X1531177D01*
X1536838Y977357D01*
Y918153D01*
X1525960Y907275D01*
X1524250D01*
X1519800Y902825D01*
Y885290D01*
X1517789Y883279D01*
X1511184D01*
X1509661Y881756D01*
Y855091D01*
X1518494Y846258D01*
Y831219D01*
X1549999Y799714D01*
X1612084D01*
X1613775Y798023D01*
Y772881D01*
X1617649Y769007D01*
Y752870D01*
X1622169Y748350D01*
Y732053D01*
X1612543Y722427D01*
X1611027D01*
G01X1456280Y1023405D02*
X1459413D01*
X1463361Y1027353D01*
X1492583D01*
X1496570Y1031340D01*
X1560656D01*
X1596753Y1067437D01*
Y1110247D01*
X1594882Y1112118D01*
Y1118476D01*
X1596606Y1120200D01*
X1604900D01*
X1606407Y1121707D01*
Y1122534D01*
X1607373Y1123500D01*
X1616403D01*
X1617480Y1122423D01*
Y1117431D01*
X1618326Y1116585D01*
X1625050D01*
X1626673Y1118208D01*
G01X1475431Y94351D02*
X1480414Y89368D01*
Y66181D01*
X1474746Y60513D01*
G01X1479380Y94279D02*
X1485573Y88086D01*
Y68678D01*
X1477606Y60711D01*
Y60438D01*
G01X1478800Y192665D02*
X1481879Y189586D01*
X1528216D01*
X1532592Y193962D01*
X1533256D01*
X1534577Y192641D01*
X1535241D01*
X1535758Y193158D01*
Y193822D01*
X1534437Y195143D01*
Y195807D01*
X1535646Y197016D01*
X1570623D01*
X1574974Y192665D01*
X1581162D01*
G01X1478800Y196665D02*
X1483051Y192414D01*
X1525387D01*
X1532073Y199100D01*
X1571154D01*
X1573589Y196665D01*
X1581162D01*
G01X1478913Y186778D02*
X1533733D01*
X1542052Y195097D01*
X1570040D01*
X1578359Y186778D01*
X1581275D01*
G01X1471006Y744818D02*
X1476559D01*
X1477228Y745487D01*
X1603956D01*
X1610142Y739301D01*
X1619099D01*
X1620100Y738300D01*
G01X1470801Y739280D02*
X1468763D01*
X1467016Y741027D01*
Y756850D01*
X1472338Y762172D01*
X1492045D01*
X1505566Y748651D01*
X1600505D01*
X1608704Y756850D01*
Y775304D01*
X1609500Y776100D01*
G01X1466075Y868239D02*
X1470135D01*
X1470168Y868206D01*
G01D02*
X1474883D01*
G01X1466465Y897425D02*
Y896081D01*
X1467556Y894990D01*
Y893449D01*
G01X1473387Y897425D02*
X1466465D01*
G01X1467508Y905405D02*
X1466465Y904362D01*
Y900575D01*
G01X1480270Y927324D02*
X1484824D01*
G01X1477120D02*
Y931324D01*
G01X1485500Y932500D02*
X1482676Y935324D01*
X1480270D01*
G01X1465833Y931848D02*
X1468152D01*
X1470500Y929500D01*
X1472000D01*
G01D02*
X1473500D01*
X1475324Y931324D01*
X1477120D01*
G01Y939324D02*
Y935324D01*
G01X1465833Y935588D02*
X1466097Y935324D01*
X1472500D01*
G01D02*
X1477120D01*
G01X1480414Y952214D02*
X1478104Y954524D01*
Y955024D01*
X1475309Y957819D01*
X1473900D01*
G01X1486888Y958378D02*
Y956796D01*
X1485895Y955803D01*
X1484003D01*
X1480414Y952214D01*
G01X1482237Y966028D02*
X1481709Y965500D01*
X1479000D01*
X1476437Y962937D01*
X1473900D01*
G01X1486925Y968000D02*
X1485387D01*
X1483387Y970000D01*
X1479196D01*
G01D02*
X1477000D01*
X1475378Y971622D01*
X1472580D01*
G01X1480414Y975064D02*
X1478738Y976740D01*
X1472580D01*
G01X1486568Y977181D02*
X1482531D01*
X1480414Y975064D01*
G01X1467096Y988813D02*
Y986497D01*
X1468284Y985309D01*
X1523142D01*
X1525261Y987428D01*
Y990258D01*
X1527344Y992341D01*
X1579175D01*
X1656714Y1069880D01*
Y1109779D01*
X1653609Y1112884D01*
X1651958D01*
X1650736Y1114106D01*
Y1122864D01*
X1650100Y1123500D01*
X1622099D01*
X1620997Y1122398D01*
Y1120012D01*
X1619193Y1118208D01*
G01X1479096Y988813D02*
X1477156Y990753D01*
Y1009221D01*
X1482440Y1014505D01*
X1502143D01*
X1504578Y1016940D01*
X1556394D01*
X1595429Y1055975D01*
G01X1471296Y988813D02*
Y991349D01*
X1469019Y993626D01*
Y1009274D01*
X1479845Y1020100D01*
X1481500D01*
X1485600Y1024200D01*
X1502536D01*
X1506676Y1028340D01*
X1561754D01*
X1596261Y1062847D01*
G01X1475096Y988813D02*
Y993347D01*
X1473066Y995377D01*
Y1011607D01*
X1479510Y1018051D01*
X1482551D01*
X1483584Y1019084D01*
X1555366D01*
X1595411Y1059129D01*
X1595963D01*
X1604253Y1067419D01*
Y1114489D01*
X1607972Y1118208D01*
G01X1483096Y988813D02*
X1480999Y990910D01*
Y1001394D01*
X1480525Y1001868D01*
Y1005132D01*
X1481628Y1006235D01*
X1485795D01*
X1488518Y1008958D01*
Y1011859D01*
X1489413Y1012754D01*
X1490235D01*
X1490236Y1012755D01*
X1490904D01*
X1490905Y1012754D01*
X1503219D01*
X1506272Y1015807D01*
X1558838D01*
X1600355Y1057324D01*
Y1058705D01*
X1604196Y1062546D01*
X1605021D01*
X1611712Y1069237D01*
Y1114468D01*
G01X1559350Y1215452D02*
Y1215331D01*
X1557639Y1213620D01*
X1552720D01*
X1550800Y1211700D01*
X1549430D01*
X1548400Y1210670D01*
Y1209600D01*
X1546624Y1207824D01*
X1504083D01*
X1493738Y1218169D01*
X1479063D01*
G01X1491471Y327200D02*
X1486860D01*
G01X1491471D02*
Y318454D01*
X1491925Y318000D01*
G01X1501500Y321000D02*
X1499500Y323000D01*
Y325500D01*
X1497800Y327200D01*
X1494621D01*
G01X1501000Y317500D02*
X1499000D01*
X1498500Y318000D01*
X1495075D01*
G01X1488138Y880839D02*
Y878339D01*
G01X1491988Y870339D02*
X1488138D01*
G01D02*
Y872839D01*
G01X1495138Y870339D02*
X1500063D01*
G01X1491988Y880839D02*
X1488138D01*
G01X1495138D02*
X1495638Y881339D01*
X1500563D01*
G01X1490411Y891615D02*
X1492711D01*
X1494954Y893858D01*
Y895264D01*
G01X1487107Y887767D02*
X1491107D01*
G01X1487107D02*
X1484155D01*
X1482195Y885807D01*
G01X1487107Y887767D02*
Y891461D01*
X1487261Y891615D01*
G01X1490000Y924075D02*
Y928655D01*
G01X1490038Y958378D02*
X1493888D01*
G01D02*
Y956612D01*
X1494500Y956000D01*
X1501000D01*
X1503000Y954000D01*
Y948297D01*
X1507244Y944053D01*
Y939256D01*
X1509500Y937000D01*
G01X1490075Y963500D02*
X1493925D01*
G01X1509500Y944138D02*
X1506500Y947138D01*
Y953500D01*
X1499500Y960500D01*
Y965500D01*
X1499000Y966000D01*
X1494425D01*
X1493925Y965500D01*
Y963500D01*
G01Y968000D02*
Y970925D01*
X1495500Y972500D01*
G01X1490075Y968000D02*
X1493925D01*
G01X1489718Y977181D02*
Y972718D01*
X1489500Y972500D01*
G01X1493568Y977181D02*
X1489718D01*
G01X1486925Y963500D02*
X1484765D01*
X1482237Y966028D01*
G01X1487096Y988813D02*
X1485088Y990821D01*
Y1003792D01*
X1489742Y1008446D01*
Y1010537D01*
X1490592Y1011387D01*
X1503994D01*
X1507250Y1014643D01*
X1560138D01*
X1604258Y1058763D01*
G01X1491096Y988813D02*
X1488971Y990938D01*
Y998719D01*
X1495289Y1005037D01*
X1498695D01*
X1500262Y1006604D01*
X1508623D01*
X1511046Y1009027D01*
X1556993D01*
X1602004Y1054038D01*
X1603622D01*
X1608377Y1058793D01*
Y1059861D01*
X1619175Y1070659D01*
Y1110745D01*
X1615452Y1114468D01*
G01X1495096Y988813D02*
X1493225Y990684D01*
Y1000371D01*
X1496611Y1003757D01*
X1499323D01*
X1501050Y1005484D01*
X1509087D01*
X1511510Y1007907D01*
X1559443D01*
X1601581Y1050045D01*
G01X1499096Y988813D02*
X1497232Y990677D01*
Y999620D01*
X1501976Y1004364D01*
X1509551D01*
X1511974Y1006787D01*
X1562299D01*
X1606977Y1051465D01*
Y1052458D01*
X1612306Y1057787D01*
X1613300D01*
X1626516Y1071003D01*
Y1110885D01*
X1622933Y1114468D01*
G01X1570571Y1211712D02*
X1568567Y1209708D01*
X1562407D01*
X1561245Y1208546D01*
Y1203320D01*
X1560223Y1202298D01*
X1552498D01*
X1550544Y1200344D01*
X1497186D01*
X1489793Y1207737D01*
G01X1578051Y1215452D02*
X1575852Y1213253D01*
X1561834D01*
X1561220Y1212639D01*
Y1210966D01*
X1559961Y1209707D01*
X1554130D01*
X1552784Y1208361D01*
Y1206284D01*
X1550831Y1204331D01*
X1500176D01*
X1490135Y1214372D01*
X1483308D01*
G01X1500353Y859855D02*
Y859820D01*
X1514713Y845460D01*
Y829911D01*
X1547605Y797019D01*
X1604029D01*
X1609711Y791337D01*
Y778859D01*
X1612444Y776126D01*
Y772206D01*
X1615968Y768682D01*
Y745232D01*
X1616683Y744517D01*
G01X1504938Y859711D02*
Y856964D01*
X1515935Y845967D01*
Y830418D01*
X1548112Y798241D01*
X1606834D01*
X1609948Y795127D01*
X1611873D01*
G01X1500563Y881339D02*
X1503004Y878898D01*
X1506626D01*
G01X1500063Y870339D02*
X1501563D01*
X1505004Y873780D01*
X1506626D01*
G01X1512712Y867418D02*
X1510845Y869285D01*
Y881045D01*
X1511700Y881900D01*
X1518127D01*
X1521021Y884794D01*
Y901844D01*
X1524550Y905373D01*
X1526322D01*
X1538449Y917500D01*
Y971857D01*
X1552764Y986172D01*
X1638914D01*
X1641455Y988713D01*
X1735598D01*
X1742043Y982268D01*
X1749803D01*
X1755009Y987474D01*
X1773095D01*
X1776416Y990795D01*
Y995740D01*
X1775247Y996909D01*
X1766650D01*
X1752796Y1010763D01*
Y1112729D01*
X1742626Y1122899D01*
Y1199100D01*
X1737829Y1203897D01*
X1733924D01*
X1728656Y1209165D01*
Y1215486D01*
X1733739Y1220569D01*
Y1237955D01*
X1769253Y1273469D01*
X1797576D01*
X1828552Y1304445D01*
Y1409979D01*
X1816954Y1421577D01*
X1622971D01*
X1601991Y1442557D01*
X1596790D01*
G01X1510500Y925925D02*
Y922452D01*
X1509274Y921226D01*
G01X1515925Y943000D02*
X1514500D01*
X1512500Y945000D01*
Y947500D01*
X1509500Y950500D01*
G01X1502863Y930740D02*
Y932837D01*
G01X1501647D02*
X1502863D01*
G01X1498983Y944443D02*
Y935501D01*
X1501647Y932837D01*
G01X1505640Y931858D02*
Y942159D01*
X1504085Y943714D01*
G01X1513424Y975244D02*
X1517424D01*
G01X1621425Y1055787D02*
X1569065Y1003427D01*
X1513419D01*
X1509089Y999097D01*
Y990820D01*
X1511096Y988813D01*
G01X1630413Y1114468D02*
X1634154Y1110727D01*
Y1071536D01*
X1622217Y1059599D01*
X1620789D01*
X1618030Y1056840D01*
Y1055412D01*
X1567165Y1004547D01*
X1512902D01*
X1510446Y1002091D01*
X1505965D01*
X1504958Y1001084D01*
Y990951D01*
X1507096Y988813D01*
G01X1503096D02*
X1501157Y990752D01*
Y1001703D01*
X1502698Y1003244D01*
X1510015D01*
X1512438Y1005667D01*
X1564200D01*
X1611857Y1053324D01*
G01X1515096Y988813D02*
X1513178Y990731D01*
Y1000009D01*
X1515476Y1002307D01*
X1571672D01*
X1633637Y1064272D01*
Y1064987D01*
X1636303Y1067653D01*
X1637018D01*
X1641477Y1072112D01*
Y1109706D01*
X1638446Y1112737D01*
X1636941D01*
X1636094Y1113584D01*
Y1115089D01*
X1635051Y1116132D01*
X1632489D01*
X1630413Y1118208D01*
G01X1574311Y1211712D02*
X1572416Y1209817D01*
Y1207087D01*
X1571491Y1206162D01*
X1565524D01*
X1564882Y1205520D01*
Y1202862D01*
X1564382Y1202362D01*
X1562126D01*
X1561190Y1201426D01*
Y1199622D01*
X1560151Y1198583D01*
X1552683D01*
X1550800Y1196700D01*
X1541300D01*
X1540800Y1196200D01*
Y1186601D01*
X1539499Y1185300D01*
X1537801D01*
X1536853Y1184352D01*
Y1178654D01*
X1538728Y1176779D01*
Y1172943D01*
X1538228Y1172443D01*
X1524584D01*
X1523764Y1171623D01*
Y1169492D01*
X1522672Y1168400D01*
X1521065D01*
X1520168Y1167503D01*
Y1165974D01*
X1517832Y1163638D01*
X1516136D01*
X1506981Y1154483D01*
Y1154126D01*
X1499183Y1146328D01*
Y1103125D01*
X1504839Y1097469D01*
Y1079426D01*
X1509005Y1075260D01*
Y1039971D01*
X1503572Y1034538D01*
G01X1527849Y1169100D02*
X1527502Y1168753D01*
X1524768D01*
X1523890Y1167875D01*
Y1166016D01*
X1519440Y1161566D01*
X1517931D01*
X1516557Y1160192D01*
Y1158522D01*
X1515376Y1157341D01*
X1513567D01*
X1507993Y1151767D01*
Y1079462D01*
X1511136Y1076319D01*
Y1051621D01*
X1521939Y1040818D01*
G01X1522099Y1035521D02*
X1524567D01*
X1525058Y1036012D01*
Y1042133D01*
X1513189Y1054002D01*
Y1077692D01*
X1509963Y1080918D01*
Y1150951D01*
X1513062Y1154050D01*
X1519183D01*
X1520140Y1155007D01*
Y1156184D01*
X1521454Y1157498D01*
X1523087D01*
X1524335Y1158746D01*
Y1161046D01*
X1527849Y1164560D01*
G01X1527634Y1160650D02*
Y1154772D01*
X1526602Y1153740D01*
X1525010D01*
X1523709Y1152439D01*
Y1151054D01*
X1522521Y1149866D01*
X1513563D01*
X1511933Y1148236D01*
Y1083209D01*
X1515241Y1079901D01*
Y1056071D01*
X1517855Y1053457D01*
G01X1500675Y1227300D02*
Y1221524D01*
X1507232Y1214967D01*
G01X1555610Y1215452D02*
X1507717D01*
X1507232Y1214967D01*
G01X1508356Y1220068D02*
X1509324Y1219100D01*
X1559442D01*
X1563090Y1215452D01*
G01X1497693Y1230407D02*
X1499011Y1231725D01*
X1511200D01*
X1512518Y1230407D01*
X1577504D01*
X1578004Y1229907D01*
Y1219239D01*
X1581791Y1215452D01*
G01X1506807Y1234921D02*
X1507654Y1234074D01*
X1588049D01*
X1589271Y1232852D01*
Y1215452D01*
G01X1507692Y1224472D02*
X1511338D01*
X1511550Y1224260D01*
G01D02*
X1513010Y1222800D01*
X1565574D01*
X1566830Y1221544D01*
Y1219192D01*
G01X1507058Y1229402D02*
X1508453D01*
X1511360Y1226495D01*
X1569571D01*
X1570571Y1225495D01*
Y1215452D01*
G01X1525000Y892925D02*
Y885381D01*
X1518517Y878898D01*
G01D02*
X1514500D01*
G01X1529000Y884006D02*
Y882549D01*
X1520231Y873780D01*
X1518452D01*
G01D02*
X1514500D01*
G01X1548080Y910757D02*
X1545604Y908281D01*
X1537206D01*
X1525000Y896075D01*
G01X1547644Y903060D02*
X1544186Y906518D01*
X1539443D01*
X1529000Y896075D01*
G01Y892925D02*
Y884006D01*
G01X1522881Y901034D02*
X1524491D01*
X1539905Y916448D01*
Y971480D01*
X1553203Y984778D01*
X1639414D01*
X1642018Y987382D01*
X1734911D01*
X1741202Y981091D01*
X1750322D01*
X1755342Y986111D01*
X1773316D01*
X1781215Y994010D01*
Y996241D01*
X1779427Y998029D01*
X1767114D01*
X1753916Y1011227D01*
Y1113193D01*
X1743810Y1123299D01*
Y1199764D01*
X1739751Y1203823D01*
Y1213504D01*
X1735135Y1218120D01*
Y1237767D01*
X1769717Y1272349D01*
X1798353D01*
X1829880Y1303876D01*
Y1410488D01*
X1809692Y1430676D01*
Y1457136D01*
X1802813Y1464015D01*
G01X1522954Y897951D02*
X1523453D01*
X1541238Y915736D01*
Y970927D01*
X1553756Y983445D01*
X1639967D01*
X1642571Y986049D01*
X1734358D01*
X1740500Y979907D01*
X1750816D01*
X1755900Y984991D01*
X1773780D01*
X1782335Y993546D01*
Y997339D01*
X1780486Y999188D01*
X1767539D01*
X1755036Y1011691D01*
Y1113657D01*
X1745074Y1123619D01*
Y1200247D01*
X1741114Y1204207D01*
Y1213814D01*
X1736291Y1218637D01*
Y1237339D01*
X1770181Y1271229D01*
X1799918D01*
X1832127Y1303438D01*
Y1410686D01*
X1812202Y1430611D01*
Y1432624D01*
G01X1520933Y918341D02*
X1526206D01*
G01X1521500Y947500D02*
X1522925Y946075D01*
Y943000D01*
G01X1528500Y947612D02*
Y945425D01*
X1526075Y943000D01*
G01X1516500Y947500D02*
X1519075Y944925D01*
Y943000D01*
G01X1525559Y953563D02*
Y951941D01*
X1526939Y950561D01*
Y949173D01*
X1528500Y947612D01*
G01X1520441Y953563D02*
Y952564D01*
X1520414Y952500D01*
X1519671Y950706D01*
X1519646Y950646D01*
X1516500Y947500D01*
G01X1525559Y961437D02*
Y964042D01*
X1526059Y964542D01*
X1528054D01*
X1529097Y965585D01*
Y967090D01*
G01X1520441Y961437D02*
Y964500D01*
X1517470Y967471D01*
G01X1528357Y974666D02*
X1528014Y974323D01*
X1525005D01*
G01X1533244Y974651D02*
X1531680Y976215D01*
X1529906D01*
X1528357Y974666D01*
G01X1530594Y979952D02*
X1526664D01*
X1521956Y975244D01*
X1517424D01*
G01X1529097Y967090D02*
Y968772D01*
X1528357Y969512D01*
Y971516D01*
G01X1517470Y967471D02*
X1517424Y967517D01*
Y972094D01*
G01X1523096Y988813D02*
X1521234Y990675D01*
Y998807D01*
X1522466Y1000039D01*
X1577639D01*
X1649134Y1071534D01*
Y1109166D01*
X1645737Y1112563D01*
X1644706D01*
X1642801Y1114468D01*
X1641633D01*
G01X1519096Y988813D02*
X1517062Y990847D01*
Y999927D01*
X1518317Y1001182D01*
X1573567D01*
X1636993Y1064608D01*
G01X1527096Y997860D02*
X1528976Y995980D01*
X1579019D01*
X1652805Y1069766D01*
Y1109394D01*
X1649729Y1112470D01*
X1648502D01*
X1647342Y1113630D01*
Y1118660D01*
X1645997Y1120005D01*
X1624730D01*
X1622933Y1118208D01*
G01X1524953Y1051037D02*
Y1054578D01*
X1523925Y1055606D01*
Y1100932D01*
X1523175Y1101682D01*
X1521123D01*
X1520004Y1102801D01*
Y1141266D01*
X1521138Y1142400D01*
X1523411D01*
X1525801Y1144790D01*
Y1146941D01*
X1527390Y1148530D01*
G01X1531947Y1046212D02*
X1528706Y1049453D01*
Y1056754D01*
X1527596Y1057864D01*
Y1104168D01*
X1526806Y1104958D01*
X1525346D01*
X1523870Y1106434D01*
Y1131645D01*
X1527559Y1135334D01*
G01X1536909Y1155610D02*
Y1155383D01*
X1535202Y1153676D01*
X1528718D01*
X1527594Y1152552D01*
Y1151572D01*
X1523808Y1147786D01*
Y1147180D01*
X1522652Y1146024D01*
X1517530D01*
X1516454Y1144948D01*
Y1099009D01*
X1517650Y1097813D01*
X1519071D01*
X1520097Y1096787D01*
Y1055763D01*
X1521141Y1054719D01*
Y1049807D01*
X1524882Y1046066D01*
X1527833D01*
X1532067Y1041832D01*
G01X1531546Y1062769D02*
X1531623Y1062846D01*
Y1107839D01*
X1530518Y1108944D01*
X1528939D01*
X1527474Y1110409D01*
Y1131509D01*
X1531299Y1135334D01*
G01X1527559Y1143390D02*
Y1138484D01*
G01Y1143390D02*
X1530218Y1146049D01*
X1533989D01*
X1535098Y1147158D01*
Y1148499D01*
X1536381Y1149782D01*
X1538561D01*
X1540649Y1151870D01*
G01X1531096Y988813D02*
X1578539D01*
X1660345Y1070619D01*
Y1110717D01*
X1656594Y1114468D01*
G01X1563090Y1140649D02*
X1561220Y1138779D01*
Y1113404D01*
X1560414Y1112598D01*
X1543369D01*
X1542537Y1111766D01*
Y1105617D01*
X1542037Y1105117D01*
X1539408D01*
X1538779Y1104488D01*
Y1058986D01*
X1536246Y1056453D01*
X1531993D01*
G01X1566830Y1140649D02*
Y1139500D01*
X1568356Y1137974D01*
Y1131886D01*
X1567712Y1131242D01*
X1566015D01*
X1564960Y1130187D01*
Y1112960D01*
X1563427Y1111427D01*
Y1107873D01*
X1562654Y1107100D01*
X1548800D01*
X1547900Y1106200D01*
Y1103781D01*
X1547400Y1103281D01*
X1545956D01*
X1542519Y1099844D01*
Y1059054D01*
X1534314Y1050849D01*
X1531961D01*
G01X1535039Y1138484D02*
X1531299D01*
G01X1538767Y1146271D02*
Y1139819D01*
X1537432Y1138484D01*
X1535039D01*
G01X1536909Y1151870D02*
X1535025Y1149986D01*
X1531996D01*
X1530540Y1148530D01*
G01X1536909Y1148129D02*
X1538767Y1146271D01*
G01X1540649Y1155610D02*
X1538959Y1157300D01*
X1532250D01*
X1530784Y1158766D01*
Y1160650D01*
G01X1547309Y1171908D02*
X1546770Y1171369D01*
X1546500Y1170717D01*
Y1169489D01*
X1545649Y1168638D01*
X1538845D01*
G01X1536909Y1159350D02*
Y1161838D01*
X1534187Y1164560D01*
X1530999D01*
G01Y1169100D02*
X1532013D01*
X1536153Y1164960D01*
X1538908D01*
X1540487Y1163381D01*
G01D02*
X1540649Y1163219D01*
Y1159350D01*
G01X1556588Y545528D02*
X1558232D01*
X1558793Y544967D01*
X1562071D01*
G01D02*
Y542500D01*
X1562571Y542000D01*
X1580260D01*
X1583720Y545460D01*
Y551894D01*
G01X1552000Y969850D02*
X1555802Y973652D01*
X1769202D01*
X1780095Y984545D01*
X1781582D01*
X1791588Y994551D01*
X1808549D01*
X1819900Y983200D01*
Y906900D01*
G01X1557444Y1135040D02*
Y1135075D01*
X1555610Y1136909D01*
G01X1547309Y1171908D02*
Y1172500D01*
G01X1553738Y1194917D02*
X1559982D01*
X1561450Y1193449D01*
G01D02*
Y1193011D01*
G01X1557147Y1418806D02*
X1551339D01*
X1551298Y1418847D01*
G01X1557147Y1418806D02*
Y1422922D01*
X1556260Y1423809D01*
Y1452717D01*
G01X1577793Y94351D02*
X1583078Y89066D01*
Y66483D01*
X1577108Y60513D01*
G01X1585435Y341787D02*
X1578587D01*
G01X1585435Y337787D02*
X1582181D01*
X1581659Y338309D01*
X1578420D01*
G01X1571755Y577937D02*
Y552595D01*
X1570200Y551040D01*
G01D02*
X1569071Y549911D01*
Y544967D01*
G01X1565221D02*
X1569071D01*
G01X1567935Y594400D02*
X1569860D01*
X1571504Y592756D01*
X1577016D01*
X1579760Y595500D01*
G01X1567935Y602400D02*
X1570231D01*
X1574760Y606929D01*
G01X1567935Y598400D02*
X1575661D01*
X1579260Y601999D01*
Y604567D01*
G01X1567935Y618400D02*
X1574720D01*
G01X1567935Y610400D02*
X1569541D01*
X1571733Y612592D01*
X1575001D01*
G01X1567935Y614400D02*
Y610400D01*
G01Y606400D02*
X1570160D01*
X1573832Y610072D01*
X1580418D01*
G01X1564785Y618400D02*
Y617000D01*
X1565285Y616500D01*
X1570260D01*
X1571476Y615284D01*
X1579321D01*
X1580354Y616317D01*
G01X1564960Y1217322D02*
X1566830Y1215452D01*
G01X1576181Y1217322D02*
X1574311Y1215452D01*
G01X1578051Y1211712D02*
X1579921Y1213582D01*
X1587401D01*
G01X1581742Y94279D02*
X1588237Y87784D01*
Y68980D01*
X1579968Y60711D01*
Y60438D01*
G01X1581162Y192665D02*
X1583562Y190265D01*
X1637220D01*
X1643325Y196370D01*
X1679819D01*
X1683524Y192665D01*
G01X1581162Y196665D02*
X1585842Y191985D01*
X1636507D01*
X1642612Y198090D01*
X1666580D01*
X1667318Y198828D01*
G01X1581275Y186778D02*
X1583042Y188545D01*
X1637933D01*
X1644038Y194650D01*
X1675765D01*
X1683637Y186778D01*
G01X1595069Y337361D02*
X1589011D01*
X1588585Y337787D01*
G01X1595109Y342663D02*
X1589461D01*
X1588585Y341787D01*
G01X1591760Y536425D02*
Y535000D01*
X1596760Y530000D01*
G01X1583720Y554847D02*
X1586260D01*
X1586760Y554347D01*
Y544000D01*
G01D02*
Y541000D01*
X1588185Y539575D01*
X1591760D01*
G01X1594760Y568000D02*
X1590806Y564046D01*
Y557800D01*
G01X1583661Y1217322D02*
X1585531Y1215452D01*
G01Y1211712D02*
X1583661Y1209842D01*
G01X1587401Y1213582D02*
X1593818D01*
X1594113Y1213877D01*
X1595212D01*
G01X1786091Y1443715D02*
X1780913Y1438537D01*
Y1434037D01*
X1772933Y1426057D01*
X1624827D01*
X1605516Y1445368D01*
Y1454374D01*
X1603437Y1456453D01*
X1598189Y1458627D01*
X1594723D01*
X1592643Y1460707D01*
G01X1593019Y1457557D02*
X1593873Y1456703D01*
X1599401D01*
X1602965Y1455227D01*
X1604270Y1453922D01*
Y1445030D01*
X1624363Y1424937D01*
X1774055D01*
X1783178Y1434060D01*
Y1437550D01*
G01X1606190Y803774D02*
X1612270D01*
X1615603Y800441D01*
Y773248D01*
X1618982Y769869D01*
Y754253D01*
X1623892Y749343D01*
Y730554D01*
X1618457Y725119D01*
Y708043D01*
X1620600Y705900D01*
G01X1606709Y819165D02*
X1612162D01*
X1617623Y813704D01*
Y773444D01*
X1620929Y770138D01*
Y754762D01*
X1625488Y750203D01*
Y728188D01*
X1620500Y723200D01*
G01X1604258Y1058763D02*
X1615582Y1070087D01*
Y1110518D01*
X1613582Y1112518D01*
Y1116338D01*
X1615452Y1118208D01*
G01X1595429Y1055975D02*
X1607972Y1068518D01*
Y1114468D01*
G01X1601581Y1050045D02*
X1602457D01*
X1622924Y1070512D01*
Y1110737D01*
X1619193Y1114468D01*
G01X1596261Y1062847D02*
X1600306Y1066892D01*
Y1109894D01*
X1598622Y1111578D01*
Y1115422D01*
X1599648Y1116448D01*
X1603564D01*
X1607170Y1120054D01*
X1609866D01*
X1611712Y1118208D01*
G01X1731533Y1228226D02*
X1726379Y1233380D01*
X1723808D01*
X1693839Y1263349D01*
X1612411D01*
X1607972Y1258910D01*
Y1215452D01*
G01X1717406Y1195603D02*
X1715917Y1197092D01*
Y1197343D01*
X1706654Y1206606D01*
X1703523Y1207903D01*
X1663109D01*
X1661212Y1209800D01*
X1655660D01*
X1654721Y1210739D01*
Y1212469D01*
X1653660Y1213530D01*
X1609790D01*
X1607972Y1211712D01*
G01X1609842Y1217322D02*
X1611793Y1219273D01*
Y1259494D01*
X1613499Y1261200D01*
X1694138D01*
X1726578Y1228760D01*
G01X1600333Y1449068D02*
Y1445799D01*
X1623435Y1422697D01*
X1775985D01*
X1787745Y1434457D01*
Y1437765D01*
G01X1601968Y1453442D02*
X1602970Y1452440D01*
Y1444746D01*
X1623899Y1423817D01*
X1774931D01*
X1785504Y1434390D01*
Y1438832D01*
X1791215Y1444543D01*
X1795374D01*
G01X1772188Y1428369D02*
X1770996Y1427177D01*
X1625292D01*
X1606760Y1445709D01*
Y1454867D01*
X1603446Y1458181D01*
X1597457Y1460662D01*
G01X1596038Y1480678D02*
Y1478659D01*
X1597039Y1477658D01*
Y1475100D01*
G01X1600008Y1480678D02*
Y1477942D01*
X1599726Y1477660D01*
Y1474990D01*
G01X1600008Y1483828D02*
Y1488492D01*
G01X1596038Y1483828D02*
Y1492000D01*
G01X1650044Y435158D02*
X1640869Y425983D01*
X1632591D01*
X1631219Y424611D01*
X1619760D01*
X1619226Y425145D01*
Y427017D01*
G01D02*
X1615356D01*
X1615344Y427029D01*
G01X1619194Y435029D02*
X1615344D01*
G01X1619194D02*
Y433855D01*
X1620046Y433003D01*
X1629259D01*
G01X1649789Y440489D02*
X1642841Y433541D01*
Y429658D01*
X1640291Y427108D01*
X1633084D01*
X1631214Y428978D01*
X1620130D01*
X1619194Y429914D01*
Y431029D01*
G01D02*
X1615344D01*
G01X1629829Y438323D02*
X1625772D01*
G01X1640942Y458714D02*
Y456446D01*
X1640467Y455971D01*
X1631826D01*
X1628642Y452787D01*
Y444985D01*
X1626613Y442956D01*
X1623955D01*
G01X1621425Y1055787D02*
X1622513D01*
X1637766Y1071040D01*
Y1109747D01*
X1634153Y1113360D01*
Y1114468D01*
G01X1611857Y1053324D02*
X1612809D01*
X1630464Y1070979D01*
Y1110677D01*
X1626673Y1114468D01*
G01X1619192Y1215451D02*
X1621015Y1217274D01*
X1624518D01*
X1626615Y1219371D01*
Y1229963D01*
X1627115Y1230463D01*
X1700455D01*
X1702275Y1232283D01*
G01X1626673Y1215452D02*
X1630424Y1219203D01*
Y1226034D01*
X1630924Y1226534D01*
X1704137D01*
X1706159Y1224512D01*
G01X1714435Y1237535D02*
X1710317Y1241653D01*
X1616003D01*
X1615503Y1241153D01*
Y1220396D01*
X1614556Y1219449D01*
X1613491D01*
X1611712Y1217670D01*
Y1215452D01*
G01X1615452D02*
X1616618D01*
X1619984Y1218818D01*
X1621623D01*
X1622885Y1220080D01*
Y1233930D01*
X1623385Y1234430D01*
X1703334D01*
X1716567Y1221197D01*
G01X1613582Y1217322D02*
X1616552D01*
X1619174Y1219944D01*
Y1237521D01*
X1619674Y1238021D01*
X1705074D01*
X1709144Y1233951D01*
G01X1632979Y438323D02*
Y440499D01*
X1630650Y442828D01*
Y443035D01*
G01X1629259Y433003D02*
X1631017D01*
X1635792Y428228D01*
X1639427D01*
X1641197Y429998D01*
Y434763D01*
X1647799Y441365D01*
X1648640Y443394D01*
X1650087Y444841D01*
G01X1630650Y443035D02*
Y446348D01*
X1633206Y448904D01*
X1642883D01*
X1643895Y449916D01*
Y451628D01*
G01X1640048Y442606D02*
X1639798Y442856D01*
X1635170D01*
G01X1635185Y446595D02*
X1636271D01*
X1636282Y446606D01*
X1640048D01*
G01X1636993Y1064608D02*
X1639009D01*
X1645444Y1071043D01*
Y1109256D01*
X1642096Y1112604D01*
X1640675D01*
X1639782Y1113497D01*
Y1115776D01*
X1639206Y1116352D01*
X1637201D01*
X1635345Y1118208D01*
X1634153D01*
G01Y1215452D02*
X1637944Y1219243D01*
Y1222483D01*
X1638522Y1223061D01*
X1678246D01*
X1679114Y1222193D01*
Y1220041D01*
X1679923Y1219232D01*
X1700670D01*
X1702500Y1221062D01*
G01X1663780Y384410D02*
X1661690Y386500D01*
X1661260D01*
X1659760Y388000D01*
G01D02*
X1655335D01*
G01X1648835Y384500D02*
X1652185D01*
G01D02*
Y381075D01*
X1653760Y379500D01*
X1664412D01*
X1666959Y382047D01*
G01X1645685Y384500D02*
Y381500D01*
G01X1648835Y388000D02*
Y390500D01*
G01X1652185Y388000D02*
X1648835D01*
G01X1646848Y451628D02*
Y453672D01*
X1651748Y458572D01*
X1653490D01*
G01D02*
Y463235D01*
G01X1650357Y467367D02*
X1647604D01*
G01X1650340Y463235D02*
Y467350D01*
X1650357Y467367D01*
G01X1652944Y993796D02*
X1664253Y1005105D01*
Y1110549D01*
X1662204Y1112598D01*
G01X1667815Y1064640D02*
Y1004991D01*
X1653414Y990590D01*
G01X1662204Y1112598D02*
X1663800Y1114194D01*
Y1131961D01*
X1662330Y1133431D01*
X1660470D01*
X1658629Y1135272D01*
X1655220D01*
X1654523Y1135969D01*
Y1142720D01*
X1652854Y1144389D01*
G01X1656594D02*
X1658445Y1142538D01*
Y1139670D01*
X1661115Y1137000D01*
X1666413D01*
X1667756Y1135657D01*
Y1133757D01*
X1668256Y1133257D01*
X1670156D01*
X1671400Y1132013D01*
Y1115101D01*
X1670499Y1114200D01*
X1668399D01*
X1667815Y1113616D01*
Y1064640D01*
G01X1658464Y1149999D02*
X1665614D01*
X1665909Y1149704D01*
X1669385D01*
G01X1656594Y1148129D02*
X1658464Y1149999D01*
G01X1704760Y1202200D02*
X1703279Y1200719D01*
X1663227D01*
X1661451Y1202495D01*
X1659517D01*
X1658450Y1203562D01*
Y1206116D01*
X1656594Y1207972D01*
G01X1652854D02*
X1654660Y1206166D01*
Y1199100D01*
X1655360Y1198400D01*
X1661401D01*
X1662437Y1197364D01*
Y1195786D01*
X1667023Y1191200D01*
X1709860D01*
X1712560Y1188500D01*
X1712715D01*
G01X1652854Y1215452D02*
X1654724Y1217322D01*
X1663083D01*
X1664905Y1215500D01*
X1710153D01*
X1723532Y1202121D01*
Y1199557D01*
X1725463Y1197626D01*
X1730457D01*
G01X1715324Y1203115D02*
X1712174Y1206265D01*
X1711822Y1206499D01*
X1711682Y1207200D01*
X1712731Y1208769D01*
X1712591Y1209471D01*
X1711994Y1209871D01*
X1711292Y1209731D01*
X1710243Y1208162D01*
X1709541Y1208022D01*
X1708944Y1208422D01*
X1708804Y1209124D01*
X1709853Y1210693D01*
X1709713Y1211395D01*
X1709116Y1211795D01*
X1708414Y1211655D01*
X1707365Y1210086D01*
X1706663Y1209946D01*
X1706066Y1210346D01*
X1705926Y1211048D01*
X1706975Y1212617D01*
X1706835Y1213319D01*
X1706238Y1213719D01*
X1705536Y1213579D01*
X1704487Y1212010D01*
X1703784Y1211871D01*
X1663246D01*
X1661490Y1213627D01*
X1658419D01*
X1656594Y1215452D01*
G01X1674747Y178560D02*
X1671143Y182164D01*
Y185997D01*
X1664840Y192300D01*
G01X1667318Y198828D02*
X1668056Y198090D01*
X1682099D01*
X1688204Y191985D01*
X1738869D01*
X1745088Y198204D01*
X1784347D01*
X1785886Y196665D01*
G01X1674968Y385912D02*
X1669384Y391496D01*
X1669260D01*
G01X1674968Y389912D02*
X1671022Y393858D01*
X1663618D01*
G01X1670260Y377912D02*
X1674968D01*
G01Y381912D02*
X1670380Y386500D01*
X1670260D01*
G01X1674968Y409924D02*
X1672184D01*
X1671260Y409000D01*
X1669260D01*
G01X1674968Y401924D02*
X1670185D01*
X1666844Y398583D01*
X1665260D01*
G01X1674968Y393924D02*
Y397912D01*
G01D02*
X1670348D01*
G01X1674968Y405924D02*
X1669684D01*
X1667260Y403500D01*
G01X1669385Y1139074D02*
X1671810D01*
X1675424Y1135460D01*
Y1057458D01*
X1745824Y987058D01*
G01X1669385Y1146554D02*
X1679934D01*
X1680905Y1145583D01*
Y1142519D01*
G01X1662204D02*
X1667220D01*
X1667515Y1142224D01*
X1669385D01*
G01X1660334Y1140649D02*
X1662204Y1142519D01*
G01X1667272Y1185514D02*
X1665714Y1183956D01*
X1662704D01*
G01Y1179625D02*
X1666552D01*
X1667710Y1178467D01*
G01X1680155Y94351D02*
X1685176Y89330D01*
Y66219D01*
X1679470Y60513D01*
G01X1684104Y94279D02*
X1690335Y88048D01*
Y68716D01*
X1682330Y60711D01*
Y60438D01*
G01X1683524Y192665D02*
X1685924Y190265D01*
X1739582D01*
X1745801Y196484D01*
X1778860D01*
X1779519Y195825D01*
Y193954D01*
X1779989Y193484D01*
X1780719D01*
X1781189Y193954D01*
Y195825D01*
X1781659Y196295D01*
X1782149D01*
X1785779Y192665D01*
G01X1785999Y186778D02*
X1784059D01*
X1776073Y194764D01*
X1746514D01*
X1740295Y188545D01*
X1685404D01*
X1683637Y186778D01*
G01X1680905Y1142519D02*
Y1138979D01*
X1679055Y1137129D01*
Y1058163D01*
X1749314Y987904D01*
G01X1710511Y1138130D02*
Y1088805D01*
X1699372Y1077666D01*
Y1040215D01*
X1748290Y991297D01*
X1751854D01*
G01X1762486Y990260D02*
X1755680D01*
X1702759Y1043181D01*
Y1076048D01*
X1721008Y1094297D01*
Y1134729D01*
G01X1748677Y993986D02*
X1701015Y1041648D01*
Y1076970D01*
X1712646Y1088601D01*
Y1139015D01*
X1711333Y1140328D01*
Y1146609D01*
G01X1712542Y1196600D02*
X1710800Y1198342D01*
Y1199816D01*
X1708416Y1202200D01*
X1704760D01*
G01X1702500Y1221062D02*
X1707489D01*
X1725658Y1202893D01*
Y1201043D01*
G01X1702275Y1232283D02*
X1731283Y1203275D01*
X1731426D01*
X1733662Y1201039D01*
G01X1706159Y1224512D02*
X1729628Y1201043D01*
G01X1729008Y1134729D02*
X1727240Y1136497D01*
X1724045D01*
X1723118Y1135570D01*
Y1123471D01*
X1744196Y1102393D01*
Y1004248D01*
X1755969Y992475D01*
X1760201D01*
G01X1721662Y1201043D02*
Y1197213D01*
X1719508Y1195059D01*
X1717950D01*
X1717406Y1195603D01*
G01X1715324Y1203115D02*
X1718625Y1199814D01*
G01X1716567Y1221197D02*
X1720536Y1217228D01*
G01X1709144Y1233951D02*
X1713914D01*
X1723200Y1224665D01*
Y1219895D01*
G01X1714435Y1237535D02*
X1726475Y1225495D01*
Y1223170D01*
G01X1725746Y385123D02*
X1729877Y380992D01*
X1737927D01*
X1741746Y377173D01*
G01X1758881Y995633D02*
Y996806D01*
X1747636Y1008051D01*
Y1104055D01*
X1732881Y1118810D01*
Y1134729D01*
G01X1753860Y997271D02*
X1745916Y1005215D01*
Y1103106D01*
X1725008Y1124014D01*
Y1134636D01*
G01X1730457Y1197626D02*
X1735696D01*
X1737662Y1199592D01*
Y1200969D01*
G01X1726578Y1228760D02*
X1729322Y1226016D01*
G01X1774476Y995049D02*
X1766077D01*
X1751076Y1010050D01*
Y1109704D01*
X1744529Y1116251D01*
G01X1773810Y990821D02*
X1767872D01*
X1749356Y1009337D01*
Y1107259D01*
X1742029Y1114586D01*
Y1116251D01*
G01X1777109Y178560D02*
X1773505Y182164D01*
Y185997D01*
X1767202Y192300D01*
G01X1764906Y474382D02*
X1766088Y473200D01*
X1772974D01*
X1774500Y474726D01*
Y486346D01*
X1770135Y490711D01*
G01X1786466Y94279D02*
X1788376Y92369D01*
Y66243D01*
X1786221Y64088D01*
Y61635D01*
X1785246Y60660D01*
G01X1782517Y94351D02*
X1784127Y92741D01*
Y64356D01*
X1781832Y62061D01*
Y60513D01*
G01X1817766Y1205475D02*
X1817129D01*
X1813484Y1209120D01*
Y1212222D01*
X1811917Y1213789D01*
Y1221450D01*
X1807622Y1225745D01*
X1805126D01*
G01X1817832Y1209407D02*
Y1205541D01*
X1817766Y1205475D01*
G01X1834665Y1213239D02*
X1834662Y1213236D01*
X1819906D01*
X1819227Y1212557D01*
X1817832D01*
G54D106*
X1795453Y812874D03*
Y834922D03*
G54D22*
X7983Y1529035D03*
Y1525635D03*
X35688Y111255D03*
Y114655D03*
X28388Y121742D03*
X35688Y125428D03*
X28388Y132515D03*
Y118342D03*
X35688Y128828D03*
X28388Y135915D03*
X35825Y1464845D03*
X39225D03*
X76005Y114623D03*
Y111223D03*
Y125396D03*
Y128796D03*
X76112Y1348187D03*
X79512D03*
X76112Y1360099D03*
X79512D03*
Y1372385D03*
X76112D03*
Y1384297D03*
X79512D03*
X86407Y132509D03*
Y118335D03*
Y121735D03*
Y135909D03*
X88352Y1348187D03*
X91752D03*
X100592D03*
X91752Y1360099D03*
X88352D03*
X100592D03*
Y1384297D03*
Y1372385D03*
X91752D03*
X88352D03*
Y1384297D03*
X91752D03*
Y1396583D03*
X88352D03*
X100592D03*
X91752Y1408495D03*
X88352D03*
X100592D03*
X116232Y1348187D03*
X112832D03*
X103992D03*
X112832Y1360099D03*
X116232D03*
X103992D03*
Y1372385D03*
Y1384297D03*
X112832D03*
X116232Y1372385D03*
Y1384297D03*
X112832Y1372385D03*
X116232Y1396583D03*
X112832D03*
X103992D03*
X112832Y1408495D03*
X116232D03*
X103992D03*
X130750Y132515D03*
Y121742D03*
Y118342D03*
Y135915D03*
X125072Y1348187D03*
X128472D03*
Y1360099D03*
X125072D03*
Y1384297D03*
X128472D03*
X125072Y1372385D03*
X128472D03*
X125072Y1396583D03*
X128472D03*
X125072Y1408495D03*
X128472D03*
X138050Y111255D03*
Y114655D03*
Y128828D03*
Y125428D03*
X148692Y391001D03*
Y394401D03*
Y405174D03*
X140690Y401513D03*
Y398113D03*
X148692Y408574D03*
X138290Y412287D03*
X148692Y419347D03*
Y422747D03*
X138290Y415687D03*
Y426460D03*
X148692Y433521D03*
X138290Y429860D03*
X148692Y436921D03*
X138290Y440633D03*
Y444033D03*
Y469387D03*
Y472787D03*
X148692Y476499D03*
X138290Y483560D03*
X148692Y490673D03*
X138290Y486960D03*
X148692Y479899D03*
Y494073D03*
Y524033D03*
Y520633D03*
X138290Y516921D03*
Y513521D03*
Y531094D03*
X148692Y538206D03*
Y534806D03*
X138290Y527694D03*
X140712Y1348187D03*
X137312D03*
X149552D03*
X137312Y1360099D03*
X140712D03*
X149552D03*
Y1384297D03*
Y1372385D03*
X140712D03*
Y1384297D03*
X137312D03*
Y1372385D03*
X140712Y1396583D03*
X137312D03*
X149552D03*
X140712Y1408495D03*
X137312D03*
X149552D03*
X165192Y1348187D03*
X161792D03*
X152952D03*
X165192Y1360099D03*
X161792D03*
X152952D03*
Y1384297D03*
Y1372385D03*
X161792Y1384297D03*
X165192Y1372385D03*
Y1384297D03*
X161792Y1372385D03*
X165192Y1396583D03*
X161792D03*
X152952D03*
X165192Y1408495D03*
X161792D03*
X152952D03*
X178367Y111223D03*
Y114623D03*
Y128796D03*
Y125396D03*
X177432Y1348187D03*
X174032D03*
Y1360099D03*
X177432D03*
Y1384297D03*
X174032D03*
Y1372385D03*
X177432D03*
Y1396583D03*
X174032D03*
X177432Y1408495D03*
X174032D03*
X188769Y118335D03*
Y121735D03*
Y132509D03*
Y135909D03*
X189672Y1348187D03*
X186272D03*
X198512D03*
X189672Y1360099D03*
X186272D03*
X198512D03*
Y1384297D03*
Y1372385D03*
X186272Y1384297D03*
X189672D03*
Y1372385D03*
X186272D03*
Y1396583D03*
X189672D03*
X198512D03*
X189672Y1408495D03*
X186272D03*
X198512D03*
X212980Y390995D03*
Y405168D03*
Y394395D03*
X205680Y401482D03*
Y398082D03*
X212980Y408568D03*
Y419341D03*
Y422741D03*
X205680Y415655D03*
Y412255D03*
Y426428D03*
Y440602D03*
Y429828D03*
X212980Y433515D03*
Y436915D03*
X205680Y444002D03*
X212980Y469381D03*
Y472781D03*
X205680Y490641D03*
Y479868D03*
X212980Y483554D03*
X205680Y476468D03*
X212980Y486954D03*
X205680Y494041D03*
Y524002D03*
X212980Y516915D03*
Y513515D03*
X205680Y520602D03*
Y534775D03*
X212980Y527688D03*
X205680Y538175D03*
X212980Y531088D03*
X201912Y1348187D03*
Y1360099D03*
Y1384297D03*
Y1372385D03*
Y1396583D03*
Y1408495D03*
X213969Y1447453D03*
Y1461853D03*
Y1458453D03*
Y1450853D03*
X227249Y1447453D03*
Y1450853D03*
Y1458453D03*
Y1461853D03*
X240412Y114655D03*
Y111255D03*
X233112Y132515D03*
Y121742D03*
X240412Y125428D03*
X233112Y118342D03*
X240412Y128828D03*
X233112Y135915D03*
X241623Y1348187D03*
X245023D03*
Y1360099D03*
X241623D03*
X245023Y1372385D03*
X241623D03*
Y1384297D03*
X245023D03*
X264005Y467337D03*
Y470737D03*
X256705Y474424D03*
X264005Y484910D03*
X256705Y488597D03*
X264005Y481510D03*
X256705Y477824D03*
Y491997D03*
X264005Y514871D03*
X256705Y518558D03*
X264005Y511471D03*
X256705Y521958D03*
Y532731D03*
Y536131D03*
X264005Y525644D03*
Y529044D03*
Y561510D03*
X256705Y571997D03*
Y568597D03*
X264005Y564910D03*
X256705Y586171D03*
X264005Y575684D03*
Y579084D03*
X256705Y582771D03*
X264005Y589857D03*
X256705Y600344D03*
X264005Y593257D03*
Y604030D03*
X256705Y596944D03*
Y611117D03*
Y614517D03*
X264005Y607430D03*
X253863Y1348187D03*
X257263D03*
X253863Y1360099D03*
X257263D03*
X253863Y1372385D03*
X257263D03*
X253863Y1384297D03*
X257263D03*
X253863Y1396583D03*
X257263D03*
Y1408495D03*
X253863D03*
X269503Y1348187D03*
X278343D03*
X266103D03*
X278343Y1360099D03*
X266103D03*
X269503D03*
Y1372385D03*
X266103D03*
X278343D03*
X266103Y1384297D03*
X269503D03*
X278343D03*
Y1396583D03*
X269503D03*
X266103D03*
X278343Y1408495D03*
X269503D03*
X266103D03*
X280729Y111223D03*
Y114623D03*
Y125396D03*
X291131Y121735D03*
X280729Y128796D03*
X291131Y118335D03*
Y132509D03*
Y135909D03*
X281743Y1348187D03*
X293983D03*
X290583D03*
X281743Y1360099D03*
X293983D03*
X290583D03*
X293983Y1372385D03*
X281743D03*
X290583Y1384297D03*
X293983D03*
X290583Y1372385D03*
X281743Y1384297D03*
X293983Y1396583D03*
X290583D03*
X281743D03*
Y1408495D03*
X293983D03*
X290583D03*
X302823Y1348187D03*
X306223D03*
Y1360099D03*
X302823D03*
X306223Y1372385D03*
X302823D03*
X306223Y1384297D03*
X302823D03*
Y1396583D03*
X306223D03*
X302823Y1408495D03*
X306223D03*
X320993Y467306D03*
Y470706D03*
Y481479D03*
Y484879D03*
Y514839D03*
Y511439D03*
Y525613D03*
Y529013D03*
Y564879D03*
Y561479D03*
Y575652D03*
Y579052D03*
Y603999D03*
Y593225D03*
Y589825D03*
Y607399D03*
X327303Y1348187D03*
X315063D03*
X318463D03*
X327303Y1360099D03*
X315063D03*
X318463D03*
X315063Y1372385D03*
X318463Y1384297D03*
X315063D03*
X327303Y1372385D03*
X318463D03*
X327303Y1384297D03*
Y1396583D03*
X315063D03*
X318463D03*
X327303Y1408495D03*
X318463D03*
X315063D03*
X342774Y111255D03*
Y114655D03*
X335474Y118342D03*
Y132515D03*
X342774Y125428D03*
X335474Y121742D03*
X342774Y128828D03*
X335474Y135915D03*
X331395Y474418D03*
Y488591D03*
Y477818D03*
Y491991D03*
Y518552D03*
Y521952D03*
Y536125D03*
Y532725D03*
Y568591D03*
Y571991D03*
Y586165D03*
Y582765D03*
Y600338D03*
Y596938D03*
Y611111D03*
Y614511D03*
X339543Y1348187D03*
X342943D03*
X330703D03*
Y1360099D03*
X342943D03*
X339543D03*
Y1372385D03*
X342943D03*
X330703D03*
X342943Y1384297D03*
X339543D03*
X330703D03*
Y1396583D03*
X339543D03*
X342943D03*
X330703Y1408495D03*
X342943D03*
X339543D03*
X351783Y1348187D03*
X355183D03*
Y1360099D03*
X351783D03*
Y1372385D03*
X355183D03*
Y1384297D03*
X351783D03*
Y1396583D03*
X355183D03*
X351783Y1408495D03*
X355183D03*
X364023Y1348187D03*
X367423D03*
Y1360099D03*
X364023D03*
Y1372385D03*
X367423Y1384297D03*
X364023D03*
X367423Y1372385D03*
X364023Y1396583D03*
X367423D03*
X364023Y1408495D03*
X367423D03*
X383091Y111223D03*
Y114623D03*
X393493Y118335D03*
X383091Y125396D03*
Y128796D03*
X393493Y132509D03*
Y121735D03*
Y135909D03*
X392415Y792725D03*
X389015D03*
X440402Y1348187D03*
Y1360099D03*
Y1372385D03*
Y1384297D03*
X452642Y1348187D03*
X456042D03*
X443802D03*
X456042Y1360099D03*
X452642D03*
X443802D03*
Y1372385D03*
X452642D03*
X456042D03*
X452642Y1384297D03*
X456042D03*
X443802D03*
X452642Y1396583D03*
X456042D03*
X452642Y1408495D03*
X456042D03*
X468282Y1348187D03*
X464882D03*
X468282Y1360099D03*
X464882D03*
Y1372385D03*
X468282D03*
X464882Y1384297D03*
X468282D03*
Y1396583D03*
X464882D03*
Y1408495D03*
X468282D03*
X485475Y118342D03*
Y121742D03*
Y132515D03*
Y135915D03*
X489362Y1348187D03*
X480522D03*
X477122D03*
X480522Y1360099D03*
X477122D03*
X489362D03*
X477122Y1372385D03*
X480522D03*
X489362D03*
Y1384297D03*
X480522D03*
X477122D03*
X480522Y1396583D03*
X477122D03*
X489362D03*
X477122Y1408495D03*
X480522D03*
X489362D03*
X492775Y114655D03*
Y111255D03*
Y128828D03*
Y125428D03*
X492762Y1348187D03*
X501602D03*
X505002D03*
X501602Y1360099D03*
X505002D03*
X492762D03*
X505002Y1372385D03*
X492762D03*
X501602D03*
X492762Y1384297D03*
X505002D03*
X501602D03*
X505002Y1396583D03*
X492762D03*
X501602D03*
X505002Y1408495D03*
X501602D03*
X492762D03*
X517242Y1348187D03*
X513842D03*
Y1360099D03*
X517242D03*
Y1372385D03*
X513842D03*
X517242Y1384297D03*
X513842D03*
X517242Y1396583D03*
X513842D03*
X517242Y1408495D03*
X513842D03*
X533092Y114623D03*
Y111223D03*
Y128796D03*
Y125396D03*
X529482Y1348187D03*
X526082D03*
X538322D03*
Y1360099D03*
X529482D03*
X526082D03*
X529482Y1372385D03*
X538322Y1384297D03*
X529482D03*
X538322Y1372385D03*
X526082D03*
Y1384297D03*
Y1396583D03*
X538322D03*
X529482D03*
Y1408495D03*
X526082D03*
X538322D03*
X543494Y121735D03*
Y132509D03*
Y118335D03*
Y135909D03*
X549168Y781600D03*
X545768D03*
X553962Y1348187D03*
X541722D03*
X550562D03*
X553962Y1360099D03*
X550562D03*
X541722D03*
Y1372385D03*
X550562D03*
X541722Y1384297D03*
X553962D03*
X550562D03*
X553962Y1372385D03*
Y1396583D03*
X541722D03*
X550562D03*
X553962Y1408495D03*
X550562D03*
X541722D03*
X562802Y1348187D03*
X566202D03*
Y1360099D03*
X562802D03*
X566202Y1372385D03*
Y1384297D03*
X562802D03*
Y1372385D03*
X566202Y1396583D03*
X562802D03*
X566202Y1408495D03*
X562802D03*
X587837Y118342D03*
Y121742D03*
Y132515D03*
Y135915D03*
X595137Y111255D03*
Y114655D03*
Y125428D03*
Y128828D03*
X597776Y401513D03*
Y398113D03*
X595376Y412287D03*
Y426460D03*
Y415687D03*
Y440633D03*
Y429860D03*
Y444033D03*
Y469387D03*
Y472787D03*
Y483560D03*
Y486960D03*
Y513521D03*
Y516921D03*
Y531094D03*
Y527694D03*
X605778Y391001D03*
Y405174D03*
Y394401D03*
Y408574D03*
Y422747D03*
Y419347D03*
Y433521D03*
Y436921D03*
Y479899D03*
Y490673D03*
Y476499D03*
Y494073D03*
Y520633D03*
Y524033D03*
Y534806D03*
Y538206D03*
X635454Y114623D03*
Y111223D03*
Y128796D03*
Y125396D03*
X629688Y1396583D03*
X626288D03*
Y1408495D03*
X629688D03*
X645856Y118335D03*
Y132509D03*
Y121735D03*
Y135909D03*
X650768Y1348187D03*
Y1360099D03*
Y1384297D03*
Y1372385D03*
X638528D03*
X641928D03*
X638528Y1384297D03*
X641928D03*
Y1396583D03*
X638528D03*
X650768D03*
X638528Y1408495D03*
X641928D03*
X650768D03*
X670066Y390995D03*
Y405168D03*
X662766Y398082D03*
X670066Y408568D03*
Y394395D03*
X662766Y401482D03*
X670066Y422741D03*
Y419341D03*
X662766Y415655D03*
Y426428D03*
Y412255D03*
Y440602D03*
X670066Y433515D03*
X662766Y429828D03*
X670066Y436915D03*
X662766Y444002D03*
X670066Y469381D03*
Y472781D03*
X662766Y476468D03*
Y490641D03*
X670066Y483554D03*
Y486954D03*
X662766Y479868D03*
Y494041D03*
X670066Y516915D03*
X662766Y520602D03*
Y524002D03*
X670066Y513515D03*
Y527688D03*
X662766Y534775D03*
X670066Y531088D03*
X662766Y538175D03*
X666408Y1348187D03*
X663008D03*
X654168D03*
X666408Y1360099D03*
X663008D03*
X654168D03*
Y1384297D03*
Y1372385D03*
X663008D03*
X666408D03*
X663008Y1384297D03*
X666408D03*
Y1396583D03*
X663008D03*
X654168D03*
X666408Y1408495D03*
X663008D03*
X654168D03*
X678648Y1348187D03*
X675248D03*
X678648Y1360099D03*
X675248D03*
Y1384297D03*
X678648D03*
Y1372385D03*
X675248D03*
Y1396583D03*
X678648D03*
Y1408495D03*
X675248D03*
X697499Y114655D03*
Y111255D03*
X690199Y132515D03*
X697499Y125428D03*
Y128828D03*
X690199Y121742D03*
Y118342D03*
Y135915D03*
X690888Y1348187D03*
X687488D03*
X699728D03*
X687488Y1360099D03*
X690888D03*
X699728D03*
Y1372385D03*
Y1384297D03*
X690888Y1372385D03*
X687488D03*
Y1384297D03*
X690888D03*
Y1396583D03*
X687488D03*
X699728D03*
X687488Y1408495D03*
X690888D03*
X699728D03*
X713791Y474424D03*
Y488597D03*
Y477824D03*
Y491997D03*
Y518558D03*
Y521958D03*
Y536131D03*
Y532731D03*
Y571997D03*
Y568597D03*
Y582771D03*
Y586171D03*
Y596944D03*
Y600344D03*
Y611117D03*
Y614517D03*
X715368Y1348187D03*
X711968D03*
X703128D03*
X715368Y1360099D03*
X711968D03*
X703128D03*
Y1372385D03*
Y1384297D03*
X715368Y1372385D03*
X711968D03*
X715368Y1384297D03*
X711968D03*
X715368Y1396583D03*
X711968D03*
X703128D03*
X715368Y1408495D03*
X711968D03*
X703128D03*
X721091Y470737D03*
Y467337D03*
Y484910D03*
Y481510D03*
Y514871D03*
Y511471D03*
Y525644D03*
Y529044D03*
Y561510D03*
Y564910D03*
Y579084D03*
Y575684D03*
Y593257D03*
Y604030D03*
Y589857D03*
Y607430D03*
X727608Y1348187D03*
X724208D03*
Y1360099D03*
X727608D03*
X724208Y1372385D03*
Y1384297D03*
X727608D03*
Y1372385D03*
X724208Y1396489D03*
X727608D03*
X724208Y1408401D03*
X727608D03*
X737816Y114623D03*
Y111223D03*
X748218Y118335D03*
X737816Y128796D03*
X748218Y132509D03*
Y121735D03*
X737816Y125396D03*
X748218Y135909D03*
X739848Y1348187D03*
X736448D03*
X748688D03*
X736448Y1360099D03*
X739848D03*
X748688D03*
Y1372385D03*
Y1384297D03*
X739848Y1372385D03*
X736448D03*
X739848Y1384297D03*
X736448D03*
X739848Y1396489D03*
X736448D03*
X739848Y1408401D03*
X736448D03*
X760928Y1348187D03*
X764328D03*
X752088D03*
X764328Y1360099D03*
X760928D03*
X752088D03*
Y1372385D03*
Y1384297D03*
X764328Y1372385D03*
X760928D03*
X764328Y1384297D03*
X760928D03*
X778079Y467306D03*
Y470706D03*
Y481479D03*
Y484879D03*
Y514839D03*
Y511439D03*
Y529013D03*
Y525613D03*
Y561479D03*
Y564879D03*
Y575652D03*
Y579052D03*
Y589825D03*
Y593225D03*
Y603999D03*
Y607399D03*
X776568Y1348187D03*
X773168D03*
Y1360099D03*
X776568D03*
X799861Y114655D03*
Y111255D03*
X792561Y132515D03*
Y118342D03*
X799861Y128828D03*
X792561Y121742D03*
X799861Y125428D03*
X792561Y135915D03*
X788481Y474418D03*
Y477818D03*
Y488591D03*
Y491991D03*
Y518552D03*
Y521952D03*
Y532725D03*
Y536125D03*
Y571991D03*
Y568591D03*
Y586165D03*
Y582765D03*
Y600338D03*
Y596938D03*
Y614511D03*
Y611111D03*
X840178Y114623D03*
Y111223D03*
Y128796D03*
Y125396D03*
X850580Y118335D03*
Y132509D03*
Y121735D03*
Y135909D03*
X917882Y328216D03*
Y324816D03*
X915954Y344150D03*
X919354D03*
X927964Y344041D03*
X924564D03*
X919163Y848442D03*
Y851592D03*
X942561Y118342D03*
Y132515D03*
Y121742D03*
Y135915D03*
X942731Y324044D03*
X939331D03*
X940997Y331912D03*
Y335312D03*
X942700Y346363D03*
X939300D03*
X945982Y886737D03*
X949861Y111255D03*
Y114655D03*
Y125428D03*
Y128828D03*
X949382Y886737D03*
X990178Y114623D03*
Y111223D03*
Y128796D03*
Y125396D03*
X1011187Y-33526D03*
Y-30126D03*
X1000580Y121735D03*
Y118335D03*
Y132509D03*
Y135909D03*
X1052223Y111255D03*
Y114655D03*
X1044923Y118342D03*
X1052223Y125428D03*
Y128828D03*
X1044923Y132515D03*
Y121742D03*
Y135915D03*
X1054863Y401513D03*
Y398113D03*
X1052463Y412287D03*
Y415687D03*
Y426460D03*
Y440633D03*
Y429860D03*
Y444033D03*
Y469387D03*
Y472787D03*
Y486960D03*
Y483560D03*
Y513521D03*
Y516921D03*
Y531094D03*
Y527694D03*
X1058113Y1348187D03*
X1054713D03*
X1058113Y1360099D03*
X1054713D03*
X1058113Y1372385D03*
X1054713D03*
Y1384297D03*
X1058113D03*
X1062865Y391001D03*
Y408574D03*
Y405174D03*
Y394401D03*
Y422747D03*
Y419347D03*
Y436921D03*
Y433521D03*
Y476499D03*
Y479899D03*
Y490673D03*
Y494073D03*
Y520633D03*
Y524033D03*
Y534806D03*
Y538206D03*
X1066953Y1348187D03*
X1070353D03*
X1066953Y1360099D03*
X1070353D03*
X1066953Y1384297D03*
Y1372385D03*
X1070353D03*
Y1384297D03*
Y1396583D03*
X1066953D03*
Y1408495D03*
X1070353D03*
X1081187Y-72706D03*
Y-69306D03*
X1092540Y111223D03*
Y114623D03*
Y128796D03*
Y125396D03*
X1091433Y1348187D03*
X1082593D03*
X1079193D03*
X1091433Y1360099D03*
X1082593D03*
X1079193D03*
Y1372385D03*
X1082593D03*
Y1384297D03*
X1079193D03*
X1091433D03*
Y1372385D03*
Y1396583D03*
X1082593D03*
X1079193D03*
X1091433Y1408495D03*
X1082593D03*
X1079193D03*
X1102942Y118335D03*
Y132509D03*
Y121735D03*
Y135909D03*
X1094833Y1348187D03*
X1107073D03*
X1103673D03*
X1094833Y1360099D03*
X1103673D03*
X1107073D03*
Y1372385D03*
X1103673D03*
X1107073Y1384297D03*
X1103673D03*
X1094833D03*
Y1372385D03*
Y1396583D03*
X1107073D03*
X1103673D03*
X1094833Y1408495D03*
X1107073D03*
X1103673D03*
X1119853Y398082D03*
Y401482D03*
Y412255D03*
Y426428D03*
Y415655D03*
Y440602D03*
Y429828D03*
Y444002D03*
Y490641D03*
Y476468D03*
Y479868D03*
Y494041D03*
Y524002D03*
Y520602D03*
Y538175D03*
Y534775D03*
X1115913Y1348187D03*
X1119313D03*
X1115913Y1360099D03*
X1119313D03*
Y1384297D03*
X1115913Y1372385D03*
X1119313D03*
X1115913Y1384297D03*
Y1396583D03*
X1119313D03*
X1115913Y1408495D03*
X1119313D03*
X1127153Y390995D03*
Y408568D03*
Y405168D03*
Y394395D03*
Y422741D03*
Y419341D03*
Y436915D03*
Y433515D03*
Y472781D03*
Y469381D03*
Y486954D03*
Y483554D03*
Y516915D03*
Y513515D03*
Y527688D03*
Y531088D03*
X1140393Y1348187D03*
X1131553D03*
X1128153D03*
X1140393Y1360099D03*
X1131553D03*
X1128153D03*
Y1384297D03*
X1131553D03*
X1128153Y1372385D03*
X1131553D03*
X1140393Y1384297D03*
Y1372385D03*
Y1396583D03*
X1131553D03*
X1128153D03*
X1140393Y1408495D03*
X1128153D03*
X1131553D03*
X1154585Y114655D03*
Y111255D03*
Y128828D03*
X1147285Y118342D03*
Y121742D03*
Y132515D03*
X1154585Y125428D03*
X1147285Y135915D03*
X1143793Y1348187D03*
X1156033D03*
X1152633D03*
X1143793Y1360099D03*
X1152633D03*
X1156033D03*
Y1384297D03*
X1152633D03*
X1156033Y1372385D03*
X1152633D03*
X1143793D03*
Y1384297D03*
Y1396583D03*
X1156033D03*
X1152633D03*
X1143793Y1408495D03*
X1152633D03*
X1156033D03*
X1170878Y474424D03*
Y477824D03*
Y488597D03*
Y491997D03*
Y518558D03*
Y521958D03*
Y532731D03*
Y536131D03*
Y571997D03*
Y568597D03*
Y586171D03*
Y582771D03*
Y596944D03*
Y600344D03*
Y614517D03*
Y611117D03*
X1168273Y1348187D03*
X1164873D03*
Y1360099D03*
X1168273D03*
Y1384297D03*
X1164873D03*
X1168273Y1372385D03*
X1164873D03*
Y1396583D03*
X1168273D03*
Y1408495D03*
X1164873D03*
X1178178Y467337D03*
Y470737D03*
Y484910D03*
Y481510D03*
Y511471D03*
Y514871D03*
Y529044D03*
Y525644D03*
Y564910D03*
Y561510D03*
Y579084D03*
Y575684D03*
Y604030D03*
Y593257D03*
Y589857D03*
Y607430D03*
X1177113Y1348187D03*
X1180513D03*
X1177113Y1360099D03*
X1180513D03*
X1177113Y1384297D03*
X1180513D03*
X1177113Y1372385D03*
X1180513D03*
Y1396583D03*
X1177113D03*
Y1408495D03*
X1180513D03*
X1194902Y114623D03*
Y111223D03*
X1205304Y118335D03*
Y121735D03*
X1194902Y128796D03*
X1205304Y132509D03*
X1194902Y125396D03*
X1205304Y135909D03*
X1225405Y-72678D03*
Y-69278D03*
X1230761Y-33628D03*
Y-30228D03*
X1235166Y470706D03*
Y467306D03*
Y484879D03*
Y481479D03*
Y514839D03*
Y511439D03*
Y529013D03*
Y525613D03*
Y564879D03*
Y561479D03*
Y575652D03*
Y579052D03*
Y593225D03*
Y603999D03*
Y589825D03*
Y607399D03*
X1230326Y1348187D03*
X1233726D03*
X1230326Y1360099D03*
X1233726D03*
X1230326Y1372385D03*
X1233726D03*
X1230326Y1384297D03*
X1233726D03*
X1249647Y118342D03*
Y132515D03*
Y121742D03*
Y135915D03*
X1245568Y474418D03*
Y488591D03*
Y477818D03*
Y491991D03*
Y521952D03*
Y518552D03*
Y536125D03*
Y532725D03*
Y568591D03*
Y571991D03*
Y582765D03*
Y586165D03*
Y596938D03*
Y600338D03*
Y611111D03*
Y614511D03*
X1245966Y1348187D03*
X1242566D03*
X1254806D03*
Y1360099D03*
X1242566D03*
X1245966D03*
X1254806Y1372385D03*
X1242566D03*
X1245966D03*
X1242566Y1384297D03*
X1245966D03*
X1254806D03*
X1245966Y1396583D03*
X1254806D03*
X1242566D03*
X1254806Y1408495D03*
X1242566D03*
X1245966D03*
X1256947Y114655D03*
Y111255D03*
Y128828D03*
Y125428D03*
X1267046Y1348187D03*
X1270446D03*
X1258206D03*
Y1360099D03*
X1270446D03*
X1267046D03*
X1258206Y1372385D03*
X1270446D03*
X1267046D03*
X1270446Y1384297D03*
X1267046D03*
X1258206D03*
X1267046Y1396583D03*
X1270446D03*
X1258206D03*
Y1408495D03*
X1270446D03*
X1267046D03*
X1282686Y1348187D03*
X1279286D03*
Y1360099D03*
X1282686D03*
X1279286Y1372385D03*
X1282686D03*
Y1384297D03*
X1279286D03*
Y1396583D03*
X1282686D03*
X1279286Y1408495D03*
X1282686D03*
X1297687Y-33656D03*
Y-30256D03*
X1297264Y114623D03*
Y111223D03*
Y128796D03*
Y125396D03*
X1291526Y1348187D03*
X1294926D03*
X1291526Y1360099D03*
X1294926D03*
X1291526Y1372385D03*
X1294926D03*
X1291526Y1384297D03*
X1294926D03*
Y1396583D03*
X1291526D03*
Y1408495D03*
X1294926D03*
X1307666Y118335D03*
Y132509D03*
Y121735D03*
Y135909D03*
X1319406Y1348187D03*
X1316006D03*
X1307166D03*
X1303766D03*
X1319406Y1360099D03*
X1316006D03*
X1307166D03*
X1303766D03*
X1316006Y1372385D03*
X1307166D03*
X1303766D03*
Y1384297D03*
X1307166D03*
X1319406Y1372385D03*
X1316006Y1384297D03*
X1319406D03*
Y1396583D03*
X1316006D03*
X1303766D03*
X1307166D03*
X1316006Y1408495D03*
X1319406D03*
X1307166D03*
X1303766D03*
X1328246Y1348187D03*
X1331646D03*
X1328246Y1360099D03*
X1331646D03*
Y1384297D03*
Y1372385D03*
X1328246D03*
Y1384297D03*
X1331646Y1396583D03*
X1328246D03*
X1331646Y1408495D03*
X1328246D03*
X1337687Y-69306D03*
Y-72706D03*
X1343886Y1348187D03*
X1340486D03*
X1343886Y1360099D03*
X1340486D03*
X1343886Y1372385D03*
X1340486D03*
Y1384297D03*
X1343886D03*
X1340486Y1396583D03*
X1343886D03*
Y1408495D03*
X1340486D03*
X1356126Y1348187D03*
X1352726D03*
X1356126Y1360099D03*
X1352726D03*
Y1384297D03*
X1356126Y1372385D03*
Y1384297D03*
X1352726Y1372385D03*
X1356126Y1396583D03*
X1352726D03*
Y1408495D03*
X1356126D03*
X1399648Y132515D03*
Y121742D03*
Y118342D03*
Y135915D03*
X1406948Y111255D03*
Y114655D03*
Y128828D03*
Y125428D03*
X1447265Y111223D03*
Y114623D03*
Y125396D03*
Y128796D03*
X1457667Y118335D03*
Y121735D03*
Y132509D03*
Y135909D03*
X1464770Y1348187D03*
X1461370D03*
X1464770Y1360099D03*
X1461370D03*
X1464770Y1372385D03*
X1461370D03*
X1464770Y1384297D03*
X1461370D03*
X1481905Y-69278D03*
Y-72678D03*
X1477010Y1348187D03*
X1473610D03*
Y1360099D03*
X1477010D03*
X1473610Y1372385D03*
X1477010D03*
X1473610Y1384297D03*
X1477010D03*
Y1396583D03*
X1473610D03*
Y1408495D03*
X1477010D03*
X1489250Y1348187D03*
X1485850D03*
X1498090D03*
Y1360099D03*
X1485850D03*
X1489250D03*
Y1372385D03*
X1485850D03*
X1498090D03*
X1485850Y1384297D03*
X1498090D03*
X1489250D03*
X1498090Y1396583D03*
X1485850D03*
X1489250D03*
X1498090Y1408495D03*
X1489250D03*
X1485850D03*
X1509310Y114655D03*
Y111255D03*
X1502010Y121742D03*
X1509310Y125428D03*
Y128828D03*
X1502010Y118342D03*
Y132515D03*
Y135915D03*
X1511950Y401513D03*
Y398113D03*
X1509550Y412287D03*
Y415687D03*
Y426460D03*
Y440633D03*
Y429860D03*
Y444033D03*
Y472787D03*
Y469387D03*
Y483560D03*
Y486960D03*
Y516921D03*
Y513521D03*
Y527694D03*
Y531094D03*
X1513730Y1348187D03*
X1510330D03*
X1501490D03*
X1510330Y1360099D03*
X1501490D03*
X1513730D03*
X1510330Y1372385D03*
X1513730D03*
X1501490D03*
Y1384297D03*
X1513730D03*
X1510330D03*
Y1396583D03*
X1513730D03*
X1501490D03*
X1510330Y1408495D03*
X1513730D03*
X1501490D03*
X1517261Y-33758D03*
Y-30358D03*
X1519952Y391001D03*
Y394401D03*
Y408574D03*
Y405174D03*
Y422747D03*
Y419347D03*
Y436921D03*
Y433521D03*
Y479899D03*
Y476499D03*
Y490673D03*
Y494073D03*
Y520633D03*
Y524033D03*
Y534806D03*
Y538206D03*
X1525970Y1348187D03*
X1522570D03*
Y1360099D03*
X1525970D03*
Y1372385D03*
X1522570D03*
X1525970Y1384297D03*
X1522570D03*
Y1396583D03*
X1525970D03*
Y1408495D03*
X1522570D03*
X1538210Y1348187D03*
X1547050D03*
X1534810D03*
X1538210Y1360099D03*
X1534810D03*
X1547050D03*
X1538210Y1372385D03*
X1534810D03*
X1547050D03*
Y1384297D03*
X1534810D03*
X1538210D03*
Y1396583D03*
X1534810D03*
X1547050D03*
X1538210Y1408495D03*
X1534810D03*
X1547050D03*
X1549627Y111223D03*
Y114623D03*
Y128796D03*
X1560029Y132509D03*
Y121735D03*
Y118335D03*
X1549627Y125396D03*
X1560029Y135909D03*
X1550450Y1348187D03*
X1559290D03*
X1562690D03*
X1559290Y1360099D03*
X1562690D03*
X1550450D03*
X1562690Y1372385D03*
X1559290D03*
X1550450D03*
X1562690Y1384297D03*
X1559290D03*
X1550450D03*
Y1396583D03*
X1562690D03*
X1559290D03*
Y1408495D03*
X1562690D03*
X1550450D03*
X1576940Y398082D03*
Y401482D03*
Y415655D03*
Y412255D03*
Y426428D03*
Y440602D03*
Y429828D03*
Y444002D03*
Y476468D03*
Y490641D03*
Y479868D03*
Y494041D03*
Y520602D03*
Y524002D03*
Y534775D03*
Y538175D03*
X1574930Y1348187D03*
X1571530D03*
X1574930Y1360099D03*
X1571530D03*
X1574930Y1372385D03*
X1571530D03*
Y1384297D03*
X1574930D03*
X1571530Y1396583D03*
X1574930D03*
X1571530Y1408495D03*
X1574930D03*
X1592187Y-69306D03*
Y-72706D03*
X1582187Y-33786D03*
Y-30386D03*
X1584240Y390995D03*
Y408568D03*
Y405168D03*
Y394395D03*
Y419341D03*
Y422741D03*
Y433515D03*
Y436915D03*
Y472781D03*
Y469381D03*
Y483554D03*
Y486954D03*
Y516915D03*
Y513515D03*
Y531088D03*
Y527688D03*
X1587170Y1348187D03*
X1583770D03*
X1587170Y1360099D03*
X1583770D03*
X1587170Y1372385D03*
X1583770D03*
Y1384297D03*
X1587170D03*
X1583770Y1396583D03*
X1587170D03*
X1583770Y1408495D03*
X1587170D03*
X1611672Y111255D03*
Y114655D03*
X1604372Y118342D03*
X1611672Y125428D03*
X1604372Y121742D03*
X1611672Y128828D03*
X1604372Y132515D03*
Y135915D03*
X1611398Y1348187D03*
Y1360099D03*
Y1384297D03*
Y1372385D03*
X1627965Y474424D03*
Y488597D03*
Y477824D03*
Y491997D03*
Y521958D03*
Y518558D03*
Y536131D03*
Y532731D03*
Y571997D03*
Y568597D03*
Y582771D03*
Y586171D03*
Y596944D03*
Y600344D03*
Y614517D03*
Y611117D03*
X1614798Y1348187D03*
X1623638D03*
X1627038D03*
X1614798Y1360099D03*
X1623638D03*
X1627038D03*
Y1372385D03*
X1623638D03*
X1627038Y1384297D03*
X1623638D03*
X1614798Y1372385D03*
Y1384297D03*
X1627038Y1396583D03*
X1623638D03*
X1627038Y1408495D03*
X1623638D03*
X1635265Y470737D03*
Y467337D03*
Y484910D03*
Y481510D03*
Y514871D03*
Y511471D03*
Y529044D03*
Y525644D03*
Y564910D03*
Y561510D03*
Y575684D03*
Y579084D03*
Y593257D03*
Y604030D03*
Y589857D03*
Y607430D03*
X1639278Y1348187D03*
X1635878D03*
X1639278Y1360099D03*
X1635878D03*
Y1384297D03*
X1639278D03*
Y1372385D03*
X1635878D03*
X1639278Y1396583D03*
X1635878D03*
Y1408495D03*
X1639278D03*
X1651989Y114623D03*
Y111223D03*
Y125396D03*
Y128796D03*
X1660358Y1348187D03*
X1651518D03*
X1648118D03*
X1660358Y1360099D03*
X1651518D03*
X1648118D03*
Y1372385D03*
X1651518D03*
X1648118Y1384297D03*
X1651518D03*
X1660358D03*
Y1372385D03*
Y1396583D03*
X1651518D03*
X1648118D03*
X1660358Y1408495D03*
X1648118D03*
X1651518D03*
X1662391Y118335D03*
Y121735D03*
Y132509D03*
Y135909D03*
X1663758Y1348187D03*
X1672598D03*
X1675998D03*
X1663758Y1360099D03*
X1675998D03*
X1672598D03*
X1675998Y1372385D03*
X1672598D03*
Y1384297D03*
X1675998D03*
X1663758D03*
Y1372385D03*
Y1396583D03*
X1675998D03*
X1672598D03*
X1663758Y1408495D03*
X1675998D03*
X1672598D03*
X1692253Y467306D03*
Y470706D03*
Y484879D03*
Y481479D03*
Y511439D03*
Y514839D03*
Y529013D03*
Y525613D03*
Y561479D03*
Y564879D03*
Y575652D03*
Y579052D03*
Y593225D03*
Y603999D03*
Y589825D03*
Y607399D03*
X1688238Y1348187D03*
X1684838D03*
X1688238Y1360099D03*
X1684838D03*
Y1384297D03*
X1688238D03*
X1684838Y1372385D03*
X1688238D03*
X1684838Y1396583D03*
X1688238D03*
Y1408495D03*
X1684838D03*
X1706734Y118342D03*
Y132515D03*
Y121742D03*
Y135915D03*
X1702655Y474418D03*
Y477818D03*
Y488591D03*
Y491991D03*
Y521952D03*
Y518552D03*
Y536125D03*
Y532725D03*
Y571991D03*
Y568591D03*
Y586165D03*
Y582765D03*
Y600338D03*
Y596938D03*
Y611111D03*
Y614511D03*
X1709318Y1348187D03*
X1700478D03*
X1697078D03*
X1709318Y1360099D03*
X1697078D03*
X1700478D03*
X1697078Y1372385D03*
X1700478D03*
X1697078Y1384297D03*
X1700478D03*
X1709318D03*
Y1372385D03*
Y1396583D03*
X1700478D03*
X1697078D03*
X1709318Y1408495D03*
X1697078D03*
X1700478D03*
X1714034Y111255D03*
Y114655D03*
Y125428D03*
Y128828D03*
X1712718Y1348187D03*
X1721558D03*
X1724958D03*
X1712718Y1360099D03*
X1724958D03*
X1721558D03*
Y1372385D03*
X1724958D03*
Y1384297D03*
X1721558D03*
X1712718Y1372385D03*
Y1384297D03*
Y1396583D03*
X1721558D03*
X1724958D03*
X1712718Y1408495D03*
X1721558D03*
X1724958D03*
X1736405Y-69278D03*
Y-72678D03*
X1733798Y1348187D03*
X1737198D03*
X1733798Y1360099D03*
X1737198D03*
Y1384297D03*
X1733798D03*
Y1372385D03*
X1737198D03*
Y1396583D03*
X1733798D03*
X1737198Y1408495D03*
X1733798D03*
X1754351Y111223D03*
Y114623D03*
Y128796D03*
Y125396D03*
X1764753Y121735D03*
Y118335D03*
Y132509D03*
Y135909D03*
X1801761Y-33888D03*
Y-30488D03*
G54D40*
G01X63745Y880067D02*
X66342D01*
G01X59962Y897500D02*
X64175D01*
G01X59962Y901500D02*
X64632D01*
G01X71928Y876608D02*
Y873683D01*
G01X68778Y873821D02*
Y876608D01*
G01X96443Y890299D02*
X101576D01*
X102320Y891043D01*
G01X118668Y884845D02*
X122042D01*
X122887Y884000D01*
G01X118668Y888845D02*
X122042D01*
X122887Y888000D01*
G01X193525Y602400D02*
X191125D01*
G01X193525Y598400D02*
X191125D01*
G01X193525Y594400D02*
X191125D01*
G01X193525Y606400D02*
X191125D01*
G01X193525Y614400D02*
X191125D01*
G01X193525Y610400D02*
X191125D01*
G01X200961Y544967D02*
X201141D01*
X203280Y547106D01*
G01X212460Y557800D02*
Y560500D01*
G01X209429Y625300D02*
X211331Y623398D01*
X216150D01*
G01X220500Y543925D02*
X223925D01*
G01X220500Y547075D02*
X219546Y548029D01*
Y551894D01*
G01X224000Y547075D02*
X220500D01*
G01X228024Y607774D02*
X222878D01*
X222646Y607542D01*
G01X240249Y628328D02*
X232285D01*
X230754Y629859D01*
Y633125D01*
G01X220255Y629749D02*
X221263Y630757D01*
Y632578D01*
G01X219445Y623543D02*
X227803D01*
G01X219445D02*
Y628939D01*
X220255Y629749D01*
G01X219300Y623398D02*
X219445Y623543D01*
G01X223952Y1217027D02*
X223279Y1217700D01*
X220259D01*
X219881Y1217322D01*
G01X256475Y422088D02*
X242518D01*
X240934Y423672D01*
Y427029D01*
G01Y431029D02*
Y427029D01*
G01Y435029D02*
Y431029D01*
G01X243593Y599506D02*
X247333D01*
G01X236686Y602656D02*
X243593D01*
G01D02*
X247503D01*
X247536Y602689D01*
G01X237449Y616063D02*
X241967D01*
G01X238234Y638243D02*
X241084D01*
G01X251116Y427017D02*
X255000D01*
G01X251084Y431029D02*
X254692D01*
G01X251084Y435029D02*
X253758D01*
G01X274425Y388000D02*
Y390500D01*
G01X269682Y451628D02*
X266714D01*
X266405Y451319D01*
G01X273245Y463479D02*
Y461057D01*
X275588Y458714D01*
G01X271938Y442606D02*
X274949D01*
G01X271938Y446606D02*
X274866D01*
G01X270095Y463479D02*
X267161Y462264D01*
X266229D01*
G01X275873Y463479D02*
X273245D01*
G01X284075Y384500D02*
Y381500D01*
G01X282247Y467367D02*
Y470136D01*
G01X292814Y1174310D02*
X291444Y1175680D01*
Y1176475D01*
G01X306858Y389912D02*
X309258D01*
G01X306858Y385912D02*
X309258D01*
G01X306858Y393924D02*
X309258D01*
G01X306858Y405924D02*
X309258D01*
G01X306858Y401924D02*
X309258D01*
G01X306858Y409924D02*
X309258D01*
G01X298507Y448630D02*
Y445908D01*
G01X302457Y448630D02*
Y445787D01*
G01X372501Y1123695D02*
Y1150595D01*
X369448Y1153648D01*
Y1166519D01*
X366133Y1169834D01*
Y1170767D01*
G01X386415Y1321645D02*
X391691D01*
G01D02*
Y1326715D01*
G01X391757Y1377875D02*
X394657D01*
G01X400064Y1297965D02*
X399716Y1297617D01*
Y1295198D01*
G01X401433Y1313443D02*
X398584D01*
G01X408523Y1330219D02*
Y1332967D01*
G01X404657Y1330243D02*
Y1332967D01*
G01X395959Y1354976D02*
Y1352153D01*
G01X399959Y1354976D02*
Y1352153D01*
G01X400879Y1403393D02*
X400531Y1403741D01*
X398112D01*
G01X425773Y1268547D02*
Y1269601D01*
X423848Y1271526D01*
X421777D01*
X420830Y1272473D01*
Y1273658D01*
G01D02*
Y1275385D01*
X422656Y1277211D01*
X425874D01*
G01X425582Y1288843D02*
Y1291743D01*
G01X412779Y1365059D02*
X413907Y1363931D01*
Y1362934D01*
X414280Y1362561D01*
G01X425283Y1366972D02*
Y1364023D01*
G01X416357Y1402024D02*
X418924D01*
X419100Y1402200D01*
G01X415823Y1559346D02*
Y1567946D01*
X417461Y1569584D01*
G01X471876Y937236D02*
Y942333D01*
X468416Y945793D01*
Y973714D01*
X463917Y978213D01*
X448980D01*
X432678Y994515D01*
Y1016186D01*
G01X427997Y1125892D02*
Y1127741D01*
X429348Y1129092D01*
G01X431822Y1125907D02*
Y1127805D01*
X432838Y1128821D01*
G01X441078Y1266785D02*
X441220Y1266927D01*
Y1271776D01*
G01X436325Y1266785D02*
X436191Y1266919D01*
Y1271753D01*
G01X431114Y1272701D02*
Y1270803D01*
X431661Y1270256D01*
Y1268547D01*
G01X441220Y1271776D02*
Y1277056D01*
X441044Y1277232D01*
G01X436191Y1271753D02*
Y1277132D01*
X436291Y1277232D01*
G01X431114Y1277510D02*
Y1272701D01*
G01X438398Y1309865D02*
X439395D01*
X440896Y1311366D01*
G01X436485Y1322369D02*
X439434D01*
G01X434266Y1378453D02*
X436002Y1380189D01*
Y1382252D01*
G01X433133Y1394934D02*
X435881D01*
G01X433157Y1398800D02*
X435881D01*
G01X456472Y1271860D02*
X457051Y1271281D01*
Y1267471D01*
X456472Y1266892D01*
G01X451377Y1271840D02*
Y1266872D01*
G01X446246Y1271785D02*
Y1266817D01*
G01X456438Y1277339D02*
X456472Y1277305D01*
Y1271860D01*
G01X451343Y1277319D02*
X451377Y1277285D01*
Y1271840D01*
G01X446212Y1277264D02*
X446246Y1277230D01*
Y1271785D01*
G01X448481Y1293045D02*
X451304D01*
G01X448481Y1297045D02*
X451304D01*
G01X459360Y996755D02*
Y1002180D01*
G01X460377Y1026774D02*
Y1028168D01*
X462427Y1030218D01*
G01X461677Y1271882D02*
Y1266914D01*
G01X466975D02*
Y1271882D01*
X467007Y1271914D01*
G01X472592Y1266882D02*
Y1271775D01*
X472624Y1271807D01*
G01X461643Y1277361D02*
X461677Y1277327D01*
Y1271882D01*
G01X466973Y1277361D02*
Y1271948D01*
X467007Y1271914D01*
G01X472590Y1277361D02*
Y1271841D01*
X472624Y1271807D01*
G01X489406Y797558D02*
X491068Y795896D01*
Y795025D01*
G01X490050Y804497D02*
X486246D01*
G01X478101Y1266882D02*
Y1271775D01*
X478133Y1271807D01*
G01X489121Y1266882D02*
Y1271559D01*
X489153Y1271591D01*
G01X483503Y1266882D02*
Y1271667D01*
X483535Y1271699D01*
G01X478099Y1277361D02*
Y1271841D01*
X478133Y1271807D01*
G01X489119Y1277361D02*
Y1271625D01*
X489153Y1271591D01*
G01X483501Y1277361D02*
Y1271733D01*
X483535Y1271699D01*
G01X503311Y712755D02*
Y715652D01*
G01Y708755D02*
X500714D01*
G01X505791Y720491D02*
X502832D01*
G01X506166Y793224D02*
Y796149D01*
G01X501074Y800757D02*
X501558D01*
X506166Y796149D01*
G01X497357Y1126012D02*
Y1127389D01*
X498727Y1128759D01*
G01X493532Y1125987D02*
Y1127390D01*
X495236Y1129094D01*
G01X494901Y1273083D02*
Y1268556D01*
G01X500302D02*
Y1273125D01*
X500334Y1273157D01*
G01X505728Y1268556D02*
X506028Y1268856D01*
Y1273540D01*
X506026Y1273542D01*
G01X494899Y1279035D02*
Y1273085D01*
X494901Y1273083D01*
G01X500300Y1279035D02*
Y1273191D01*
X500334Y1273157D01*
G01X506026Y1279035D02*
Y1273542D01*
G01X515381Y685811D02*
X514827Y686365D01*
X511990D01*
G01X509791Y720491D02*
Y722031D01*
X508237Y723585D01*
G01X509316Y796149D02*
Y793224D01*
G01X521178Y814001D02*
X521193D01*
X523741Y816549D01*
G01X515511Y803973D02*
X518157D01*
G01X515511Y811973D02*
X518565D01*
G01X525741Y821074D02*
X522747D01*
X522604Y820931D01*
X521565D01*
G01X517832Y831662D02*
Y834558D01*
G01X525741Y824224D02*
X522918D01*
X522481Y824661D01*
G01X514682Y834590D02*
Y831662D01*
G01X520685Y880067D02*
X523272D01*
G01X516902Y897500D02*
X521115D01*
G01X516902Y901500D02*
X521572D01*
G01X522939Y1268641D02*
X518576Y1273004D01*
G01X519131Y1268640D02*
X518470Y1269301D01*
X513417D01*
X511876Y1270842D01*
Y1272083D01*
G01X518576Y1273004D02*
X517332Y1274248D01*
Y1277845D01*
G01X522765D02*
X525712Y1274898D01*
Y1272992D01*
G01X511876Y1272083D02*
Y1277845D01*
G01X532248Y684222D02*
X534673D01*
X534940Y684489D01*
G01X542084Y681459D02*
X539111D01*
G01X536354Y708711D02*
Y711650D01*
X535387Y712617D01*
G01X537023Y718317D02*
X538911D01*
X540379Y719785D01*
G01X532304Y797889D02*
Y795978D01*
X531260Y794934D01*
G01X534166Y792649D02*
X532741D01*
X532423Y792331D01*
X531501D01*
G01X528741Y815724D02*
X531666D01*
G01X532304Y803389D02*
Y806649D01*
G01X531313Y812850D02*
X531037Y812574D01*
X528741D01*
G01D02*
X526916Y810749D01*
X523741D01*
G01X532316Y833649D02*
Y831064D01*
X532279Y831027D01*
G01X532316Y836149D02*
Y833649D01*
G01X534000Y843000D02*
X532316Y841316D01*
Y840649D01*
G01X531959Y849830D02*
X534632D01*
G01X528868Y876608D02*
Y873683D01*
G01X525718Y873821D02*
Y876608D01*
G01X530453Y1268707D02*
X532812Y1271066D01*
Y1273169D01*
G01X525712Y1272992D02*
Y1269694D01*
X526725Y1268681D01*
G01X532812Y1273169D02*
X528136Y1277845D01*
G01X556174Y787840D02*
Y786706D01*
X554357Y784889D01*
G01X555279Y796389D02*
X558241D01*
G01X556174Y790990D02*
Y793591D01*
X556326Y793743D01*
G01X545741Y801724D02*
Y804149D01*
G01X541129Y830889D02*
Y828335D01*
G01X544279Y835389D02*
Y830889D01*
G01D02*
X545915D01*
X546855Y829949D01*
G01X541129Y835389D02*
Y838865D01*
G01X548665Y844743D02*
X547071Y843149D01*
X546241D01*
G01X553383Y890299D02*
X558516D01*
X559260Y891043D01*
G01X570241Y806224D02*
X567316D01*
G01X557604Y801389D02*
X558844D01*
X561061Y803606D01*
G01X557604Y806889D02*
X561001D01*
G01X570241Y803074D02*
X567625D01*
X567559Y803008D01*
G01X570241Y827724D02*
X567316D01*
G01X570241Y824574D02*
X567646D01*
X567559Y824661D01*
G01X558241Y843724D02*
Y845341D01*
X559196Y846296D01*
G01X558241Y840574D02*
X560813D01*
G01X566231Y844721D02*
X568990D01*
G01X562328Y957307D02*
X564403Y959382D01*
X566103D01*
G01X577825Y961804D02*
X568525D01*
X566103Y959382D01*
G01X562328Y957307D02*
Y952582D01*
G01D02*
X563103Y951807D01*
G01X556493Y1118351D02*
X562129D01*
X563403Y1119625D01*
Y1179995D01*
X564627Y1181219D01*
X568169D01*
X570556Y1183606D01*
Y1192723D01*
X568532Y1194747D01*
Y1200001D01*
G01X583501Y814123D02*
X581001D01*
G01Y810973D02*
X583501D01*
G01X577501Y826623D02*
Y829069D01*
G01X588001Y826623D02*
Y829624D01*
G01X579827Y884000D02*
X578982Y884845D01*
X575608D01*
G01X579827Y888000D02*
X578982Y888845D01*
X575608D01*
G01X650611Y602400D02*
X648211D01*
G01X650611Y598400D02*
X648211D01*
G01X650611Y594400D02*
X648211D01*
G01X650611Y606400D02*
X648211D01*
G01X650611Y614400D02*
X648211D01*
G01X650611Y610400D02*
X648211D01*
G01X658047Y544967D02*
X658227D01*
X660366Y547106D01*
G01X669546Y557800D02*
Y560500D01*
G01X677586Y543925D02*
X681011D01*
G01X681086Y547075D02*
X677586D01*
G01D02*
X676632Y548029D01*
Y551894D01*
G01X681039Y1217027D02*
Y1217652D01*
X679499Y1219192D01*
X678838D01*
G01X700094Y766471D02*
X702691D01*
G01X700094Y753471D02*
X702691D01*
G01X700094Y762971D02*
X702691D01*
G01X700094Y756971D02*
X702691D01*
G01X700080Y771159D02*
X702677D01*
G01X700080Y780659D02*
X702677D01*
G01X700080Y775159D02*
X702677D01*
G01X700080Y784659D02*
X702677D01*
G01X731511Y388000D02*
Y390500D01*
G01X726768Y451628D02*
X723800D01*
X723491Y451319D01*
G01X730331Y463479D02*
Y461057D01*
X732674Y458714D01*
G01X729024Y442606D02*
X732035D01*
G01X729024Y446606D02*
X731952D01*
G01X727181Y463479D02*
X724247Y462264D01*
X723315D01*
G01X732959Y463479D02*
X730331D01*
G01X741161Y384500D02*
Y381500D01*
G01X739333Y467367D02*
Y470136D01*
G01X749901Y1174310D02*
X748531Y1175680D01*
Y1176475D01*
G01X763944Y389912D02*
X766344D01*
G01X763944Y385912D02*
X766344D01*
G01X763944Y377912D02*
X766344D01*
G01X763944Y381912D02*
X766344D01*
G01X763944Y393924D02*
X766344D01*
G01X763944Y405924D02*
X766344D01*
G01X763944Y401924D02*
X766344D01*
G01X763944Y397912D02*
X766344D01*
G01X763944Y409924D02*
X766344D01*
G01X759543Y448630D02*
Y445787D01*
G01X755593Y448630D02*
Y445908D01*
G01X789050Y1026150D02*
X788448Y1025548D01*
X785148D01*
X783659Y1024059D01*
Y1022487D01*
G01X780117Y1442282D02*
Y1442252D01*
X780126Y1442243D01*
Y1440205D01*
X779353Y1439432D01*
X777749D01*
G01X791686Y1022487D02*
Y1025440D01*
G01X787631Y1022487D02*
X791686D01*
G01X799631D02*
Y1025440D01*
G01X795631Y1022487D02*
Y1025440D01*
G01X823220Y1170767D02*
X821661Y1172326D01*
X807677D01*
X802732Y1167381D01*
X790738D01*
X787887Y1170232D01*
Y1174500D01*
G01X807673Y1022487D02*
X803673D01*
G01X811673D02*
X807673D01*
G01X815673D02*
X811673D01*
G01X819673D02*
X815673D01*
G01X803673D02*
Y1025440D01*
G01X825335Y1137129D02*
X824300Y1138164D01*
X804777D01*
X803453Y1136840D01*
Y1134729D01*
G01X803059Y1429135D02*
X800703Y1426779D01*
G01X845784Y705489D02*
X829784D01*
G01X823234Y867680D02*
X820668D01*
X819269Y869079D01*
X816969D01*
G01D02*
X816878Y869170D01*
Y872721D01*
X816969Y872812D01*
G01Y876605D02*
X817459D01*
X823234Y870830D01*
G01X818422Y893885D02*
Y895110D01*
X817152Y896380D01*
G01X825146Y969573D02*
X828423Y966296D01*
Y964731D01*
G01X829494Y969632D02*
X831034D01*
X832423Y968243D01*
Y964669D01*
G01X823673Y1022487D02*
X819673D01*
G01X827673D02*
X823673D01*
G01X831673D02*
X827673D01*
G01X838685Y832987D02*
X839584Y833886D01*
X841161D01*
X842734Y835459D01*
G01Y839459D02*
Y835459D01*
G01X840689Y847531D02*
Y843490D01*
G01D02*
X838220D01*
X838189Y843459D01*
G01X840286Y855397D02*
X840224Y855459D01*
X837183D01*
G01X836644Y857937D02*
X837183Y857398D01*
Y855459D01*
G01X839790Y887490D02*
X837290D01*
G01X839883Y883459D02*
Y887397D01*
X839790Y887490D01*
G01X839789Y891503D02*
Y892405D01*
X842827Y895443D01*
G01X833898Y1451993D02*
Y1455821D01*
X835474Y1457397D01*
G01X896953Y272012D02*
X893379D01*
X890421Y274970D01*
Y299289D01*
X891354Y300222D01*
Y333202D01*
X880966Y343590D01*
Y354091D01*
X878609Y356448D01*
Y366603D01*
X891236Y379230D01*
Y384161D01*
X891251Y384176D01*
Y387484D01*
G01X875916Y808965D02*
Y813465D01*
G01Y803315D02*
X874925Y802324D01*
Y800746D01*
G01X900049Y551863D02*
X899049Y550863D01*
X896449D01*
G01X894949Y553963D02*
X893949Y552963D01*
Y550363D01*
G01X882949Y560463D02*
Y557363D01*
G01X894449Y603938D02*
Y606363D01*
G01X887949Y605763D02*
Y608863D01*
G01X912462Y687770D02*
X907381D01*
X906251Y686640D01*
X900250D01*
X896234Y690656D01*
G01X891916Y808965D02*
Y813465D01*
G01X887916Y803315D02*
Y800815D01*
G01X916898Y312228D02*
X914239D01*
X913057Y311046D01*
G01X900874Y556363D02*
X899707D01*
X898156Y554812D01*
G01X899916Y803315D02*
Y800815D01*
G01X909416Y813465D02*
Y811147D01*
X909785Y810778D01*
G01X900576Y884516D02*
X900793Y884299D01*
Y880463D01*
X900267Y879937D01*
G01X899693Y895207D02*
Y894824D01*
X900809Y893708D01*
Y892672D01*
X900592Y892455D01*
G01D02*
X900683Y892364D01*
Y890071D01*
X900788Y889966D01*
Y888695D01*
X900571Y888478D01*
G01X903286Y911912D02*
Y913793D01*
X904833Y915340D01*
G01X920142Y308501D02*
X920048Y308595D01*
Y312228D01*
G01X915949Y566463D02*
Y563363D01*
G01X915712Y613792D02*
X914949Y613029D01*
Y609763D01*
G01X913716Y803315D02*
Y800815D01*
G01X925755Y834381D02*
X927149D01*
X928612Y835844D01*
G01X920628Y925701D02*
Y928101D01*
G01X928628Y925701D02*
Y928101D01*
G01X916628Y925701D02*
Y928101D01*
G01X924628Y925701D02*
Y928101D01*
G01X950239Y1409555D02*
X948269Y1411525D01*
Y1411526D01*
X927453D01*
X925909Y1413070D01*
G01X914370Y1464583D02*
X917784Y1461169D01*
X919525D01*
X925529Y1455165D01*
Y1446440D01*
X923559Y1444470D01*
Y1415420D01*
X925909Y1413070D01*
G01X952035Y1401223D02*
X955271Y1404459D01*
Y1407653D01*
X955285Y1407667D01*
Y1412628D01*
X953073Y1414840D01*
X930936D01*
X926617Y1419159D01*
Y1442210D01*
X931731Y1447324D01*
X954456D01*
X957306Y1444474D01*
X964983D01*
G01X938938Y1443901D02*
X933629D01*
X929624Y1439896D01*
Y1421373D01*
X932857Y1418140D01*
X954440D01*
X958585Y1413995D01*
Y1389437D01*
G01X937428Y205148D02*
X946385D01*
X949443Y208206D01*
G01X931124Y834381D02*
Y831500D01*
X931624Y831000D01*
X932000D01*
G01X935124Y834381D02*
Y831382D01*
G01X932628Y925701D02*
Y928101D01*
G01X936628Y925701D02*
Y928101D01*
G01X949130Y923108D02*
X949928Y923906D01*
Y927015D01*
X950567Y927654D01*
G01X949130Y923108D02*
X952906D01*
X952957Y923057D01*
G01X949058Y923036D02*
X949130Y923108D01*
G01X957358Y923116D02*
X956879Y923595D01*
Y925342D01*
X954567Y927654D01*
G01X951832Y1371654D02*
X951851Y1371635D01*
X973558D01*
X980228Y1364965D01*
X982259D01*
X985324Y1361900D01*
Y1361881D01*
G01X949469Y1379528D02*
X952417D01*
G01X958585Y1389437D02*
Y1383131D01*
X954982Y1379528D01*
X952417D01*
G01X949385Y1375591D02*
X952385D01*
G01X952035Y1401223D02*
X949547Y1398735D01*
Y1386985D01*
X946969Y1384407D01*
Y1378007D01*
X949385Y1375591D01*
G01X950239Y1409555D02*
X952180Y1407614D01*
Y1407087D01*
G01X977771Y880067D02*
X979559D01*
X980529Y879097D01*
G01X974408Y897500D02*
X978201D01*
G01X974408Y901500D02*
X975934D01*
X977283Y902849D01*
X979592D01*
G01X987168Y1444240D02*
X984140D01*
X980784Y1447596D01*
X966241D01*
X964983Y1446338D01*
Y1444474D01*
G01X994920Y331854D02*
X993920Y332854D01*
Y335454D01*
G01X997020Y336954D02*
X996020Y337954D01*
X993420D01*
G01X980081Y363457D02*
Y366523D01*
X980045Y366559D01*
G01X993034Y768775D02*
X1001114D01*
X1003990Y765899D01*
G01X992000Y786575D02*
X1004883D01*
X1006053Y787745D01*
G01X985954Y876608D02*
X987549Y878203D01*
X988231D01*
G01X979891Y876589D02*
X982785D01*
X982804Y876608D01*
G01X1011279Y1444512D02*
X1007443D01*
X1004321Y1447634D01*
X988232D01*
X987260Y1446662D01*
Y1444332D01*
X987168Y1444240D01*
G01X1004933Y314535D02*
X1006792Y316394D01*
X1009116D01*
G01X999678Y330982D02*
Y331897D01*
X997921Y333654D01*
G01X1003520Y348954D02*
X1000420D01*
G01X1007719Y956397D02*
X1006019D01*
X1004994Y955372D01*
G01D02*
X1004719Y955097D01*
Y948822D01*
G01X1030370Y954222D02*
Y956698D01*
X1031674Y958002D01*
Y959886D01*
X1029094Y962466D01*
X1013788D01*
X1007719Y956397D01*
G01X1006222Y980337D02*
X1004132D01*
X1002332Y982137D01*
Y996449D01*
X1011371Y1005488D01*
Y1007808D01*
X1008759Y1010420D01*
Y1023900D01*
G01X1016798Y890299D02*
X1016754Y890255D01*
X1013902D01*
G01X1011279Y1444512D02*
Y1446238D01*
X1012754Y1447713D01*
X1030634D01*
X1033751Y1444596D01*
X1036945D01*
G01X1030300Y881400D02*
X1030937D01*
X1032694Y883157D01*
Y884845D01*
G01X1037709Y886209D02*
X1035073Y888845D01*
X1032694D01*
G01X1036945Y1444596D02*
Y1446666D01*
X1038069Y1447790D01*
X1049077D01*
X1051281Y1445586D01*
X1051527D01*
G01X1052820Y316954D02*
X1074708D01*
X1077602Y314060D01*
G01X1048820Y343954D02*
X1045966Y346808D01*
G01X1046995Y337454D02*
Y339710D01*
X1046674Y340031D01*
G01X1051527Y1445586D02*
X1054664D01*
X1059448Y1440802D01*
Y1438501D01*
G01X1091865Y1533457D02*
X1093393D01*
X1095250Y1531600D01*
G01X1107698Y598400D02*
X1105298D01*
G01X1107698Y602400D02*
X1105298D01*
G01X1107698Y594400D02*
X1105298D01*
G01X1107698Y614400D02*
X1105298D01*
G01X1107698Y606400D02*
X1105298D01*
G01X1107698Y610400D02*
X1105298D01*
G01X1098225Y1513398D02*
X1095080D01*
G01X1115134Y544967D02*
X1115314D01*
X1117453Y547106D01*
G01X1134673Y543925D02*
X1138098D01*
G01X1138173Y547075D02*
X1134673D01*
G01D02*
X1133719Y548029D01*
Y551894D01*
G01X1126633Y557800D02*
Y560500D01*
G01X1139617Y775434D02*
X1145428D01*
X1149345Y771517D01*
G01X1145910Y803642D02*
X1138456D01*
X1127081Y792267D01*
Y770378D01*
X1128600Y768859D01*
G01X1138125Y1217027D02*
Y1217100D01*
X1137425Y1217800D01*
X1134532D01*
X1134054Y1217322D01*
G01X1171445Y422088D02*
X1156691D01*
X1155107Y423672D01*
Y427029D01*
G01Y431029D02*
Y427029D01*
G01Y435029D02*
Y431029D01*
G01X1149345Y771517D02*
X1150446Y770416D01*
X1152749D01*
X1153433Y771100D01*
Y772243D01*
G01X1145910Y797142D02*
Y794217D01*
G01X1152442Y788431D02*
Y789831D01*
X1151277Y790996D01*
G01X1154652Y791056D02*
X1155592Y790116D01*
Y788431D01*
G01X1160913Y786870D02*
X1159352Y788431D01*
X1155592D01*
G01X1145910Y810142D02*
Y811567D01*
X1146985Y812642D01*
G01X1145910Y803642D02*
Y806642D01*
G01Y800642D02*
Y803642D01*
G01X1165257Y431029D02*
X1168902D01*
G01X1165257Y435029D02*
X1167931D01*
G01X1165289Y427017D02*
X1169173D01*
G01X1160197Y794335D02*
Y792756D01*
X1161291Y791662D01*
G01X1169697Y794335D02*
Y791935D01*
G01X1164197Y794335D02*
Y792335D01*
X1164925Y791607D01*
G01X1188598Y388000D02*
Y390500D01*
G01X1183855Y451628D02*
X1180887D01*
X1180578Y451319D01*
G01X1186111Y442606D02*
X1189122D01*
G01X1186111Y446606D02*
X1188739D01*
G01X1184268Y463479D02*
X1181334Y462264D01*
X1180402D01*
G01X1187418Y463479D02*
Y461057D01*
X1189761Y458714D01*
G01X1190046Y463479D02*
X1187418D01*
G01X1173697Y794335D02*
Y791911D01*
G01X1183431Y871238D02*
Y868340D01*
G01X1187431Y871238D02*
Y868340D01*
G01X1176577Y888899D02*
Y885974D01*
G01X1177431Y881888D02*
X1178291D01*
X1179858Y883455D01*
G01X1179727Y888899D02*
Y886197D01*
G01X1183750Y891385D02*
X1181037D01*
X1179727Y890075D01*
Y888899D01*
G01X1187151Y923459D02*
Y921000D01*
G01X1177186Y933609D02*
Y935686D01*
X1178000Y936500D01*
G01X1181151Y933609D02*
Y935651D01*
X1182000Y936500D01*
G01X1187951Y959596D02*
Y962649D01*
X1187200Y963400D01*
G01X1182779Y968668D02*
X1190308D01*
X1191219Y967757D01*
G01X1189219Y989714D02*
X1193219D01*
G01X1198248Y384500D02*
Y381500D01*
G01X1196420Y467367D02*
Y470136D01*
G01X1192431Y881888D02*
Y884120D01*
X1192152Y884399D01*
G01X1195118Y936296D02*
Y933609D01*
G01X1191151Y936296D02*
Y933609D01*
G01X1197219Y943214D02*
X1193219D01*
G01D02*
Y940703D01*
G01X1201294Y953789D02*
Y952349D01*
X1199615Y950670D01*
G01X1196219Y959596D02*
Y955714D01*
X1198144Y953789D01*
G01D02*
Y952825D01*
X1196352Y951033D01*
G01X1198144Y982789D02*
X1196219Y980864D01*
Y976722D01*
G01X1201294Y982789D02*
X1201794Y983289D01*
Y985289D01*
G01X1198644D02*
Y983289D01*
X1198144Y982789D01*
G01X1193219Y989714D02*
Y988605D01*
X1191928Y987314D01*
G01X1206987Y1174310D02*
X1205617Y1175680D01*
Y1176475D01*
G01X1221031Y389912D02*
X1223431D01*
G01X1221031Y385912D02*
X1223431D01*
G01X1221031Y381912D02*
X1223431D01*
G01X1221031Y377912D02*
X1223431D01*
G01X1221031Y393924D02*
X1223431D01*
G01X1221031Y405924D02*
X1223431D01*
G01X1221031Y401924D02*
X1223431D01*
G01X1221031Y397912D02*
X1223431D01*
G01X1221031Y409924D02*
X1223431D01*
G01X1212680Y448630D02*
Y445908D01*
G01X1216630Y448630D02*
Y445787D01*
G01X1249363Y1173065D02*
X1249938D01*
X1254039Y1168964D01*
X1259642D01*
X1262171Y1171493D01*
X1279580D01*
X1280306Y1170767D01*
G01X1262075Y324075D02*
Y324845D01*
X1260737Y326845D01*
X1260655Y327257D01*
G01X1279292Y905173D02*
X1281491D01*
X1283494Y907176D01*
G01X1289547Y928047D02*
Y930694D01*
X1285103Y935138D01*
X1276049D01*
G01X1301314Y484882D02*
X1331529D01*
X1339049Y477362D01*
Y471334D01*
G01X1294410Y791545D02*
X1353555D01*
X1360290Y798280D01*
X1374067D01*
X1378000Y802213D01*
Y816425D01*
G01X1287889Y885651D02*
Y881802D01*
G01X1296879Y911478D02*
X1296970Y911569D01*
Y913862D01*
X1296879Y913953D01*
Y915879D01*
X1298000Y917000D01*
G01X1302925Y944000D02*
X1299064D01*
X1298090Y943026D01*
Y940852D01*
G01X1311699Y1245696D02*
X1307167D01*
G01X1314618Y1280207D02*
Y1273854D01*
X1314604Y1273840D01*
G01X1306805Y1279545D02*
X1313956D01*
X1314618Y1280207D01*
G01X1426000Y717000D02*
X1423863D01*
X1421848Y714985D01*
Y695492D01*
X1419306Y692950D01*
X1342928D01*
X1335478Y685500D01*
X1335000D01*
G01D02*
X1332768Y687732D01*
Y714863D01*
X1330925Y716706D01*
Y728425D01*
X1335000Y732500D01*
G01X1320072Y1280152D02*
X1323951D01*
X1324886Y1279217D01*
Y1278962D01*
G01D02*
Y1277470D01*
X1321256Y1273840D01*
X1319999D01*
G01X1330582D02*
X1332907Y1276165D01*
Y1278568D01*
G01D02*
Y1281974D01*
X1330594Y1284287D01*
G01X1335873D02*
X1336936Y1283224D01*
Y1278376D01*
G01D02*
Y1274840D01*
X1335936Y1273840D01*
G01X1325478D02*
X1328903Y1277265D01*
Y1278838D01*
G01D02*
Y1280828D01*
X1325444Y1284287D01*
G01X1341137D02*
X1341226Y1284198D01*
Y1278592D01*
G01D02*
Y1273840D01*
G01X1346371Y1284287D02*
X1346362Y1284278D01*
Y1278700D01*
G01D02*
Y1273840D01*
G01X1351668Y1284287D02*
X1351673Y1284282D01*
Y1278700D01*
G01D02*
Y1273840D01*
G01X1370384Y1002180D02*
X1369027D01*
X1367444Y1003763D01*
G01X1362269Y1284287D02*
X1362308Y1284248D01*
Y1278862D01*
G01D02*
Y1273840D01*
G01X1367681Y1284287D02*
X1367828Y1284140D01*
Y1278862D01*
G01D02*
Y1273840D01*
G01X1356871Y1284287D02*
X1356856Y1284272D01*
Y1278862D01*
G01D02*
Y1273840D01*
G01X1367681Y1290087D02*
X1362269D01*
G01X1373032Y1290043D02*
X1367725D01*
X1367681Y1290087D01*
G01X1382858Y561000D02*
Y559082D01*
X1383556Y558384D01*
Y558338D01*
G01X1382858Y565000D02*
Y569000D01*
G01D02*
Y571177D01*
X1383608Y571927D01*
G01X1382858Y607500D02*
Y605582D01*
X1383556Y604884D01*
Y604838D01*
G01X1382858Y615500D02*
Y617677D01*
X1383608Y618427D01*
G01X1382858Y611500D02*
Y615500D01*
G01X1373534Y996755D02*
Y1002180D01*
G01X1374551Y1026774D02*
Y1028168D01*
X1376601Y1030218D01*
G01X1377390Y1254164D02*
Y1257392D01*
X1378397Y1258399D01*
X1378578D01*
G01X1380936Y1270898D02*
Y1265930D01*
G01X1380311Y1276377D02*
X1380936Y1275752D01*
Y1270898D01*
G01X1373032Y1284243D02*
Y1278566D01*
G01D02*
Y1274687D01*
X1372152Y1273807D01*
G01X1368775Y1422900D02*
X1372300D01*
G01X1386295Y921075D02*
X1388980D01*
G01X1396296Y1270918D02*
Y1265950D01*
G01X1386122Y1270954D02*
Y1265986D01*
G01X1391272Y1270920D02*
Y1265952D01*
G01X1395671Y1276397D02*
X1396296Y1275772D01*
Y1270918D01*
G01X1400803Y1277849D02*
Y1274849D01*
X1401428Y1274224D01*
Y1270918D01*
G01X1385497Y1276433D02*
X1386122Y1275808D01*
Y1270954D01*
G01X1390647Y1276399D02*
X1391272Y1275774D01*
Y1270920D01*
G01X1405214Y961181D02*
Y965074D01*
G01X1410581Y1028267D02*
X1413080Y1030766D01*
X1420740D01*
G01X1407954Y1126037D02*
Y1127767D01*
X1409425Y1129238D01*
G01X1411829Y1126014D02*
Y1127546D01*
X1413177Y1128894D01*
G01X1401428Y1270918D02*
Y1265950D01*
G01X1411184Y1268685D02*
Y1270781D01*
X1409066Y1272899D01*
G01X1406916Y1268685D02*
X1405066Y1270535D01*
Y1272899D01*
G01X1415181Y1268685D02*
Y1270784D01*
X1413066Y1272899D01*
G01X1412392Y1277962D02*
Y1277177D01*
X1409066Y1273851D01*
Y1272899D01*
G01X1405066D02*
Y1275786D01*
X1407232Y1277952D01*
G01X1418280Y1273336D02*
X1413503D01*
X1413066Y1272899D01*
G01X1431075Y897500D02*
X1435288D01*
G01X1431075Y901500D02*
X1435745D01*
G01X1419451Y1268629D02*
X1420798Y1269976D01*
X1421492D01*
X1424852Y1273336D01*
G01X1436439Y1268710D02*
X1435066Y1270083D01*
X1433589D01*
X1430336Y1273336D01*
G01X1446817Y1335846D02*
Y1340400D01*
X1421562Y1365655D01*
Y1416231D01*
X1430374Y1425043D01*
Y1492474D01*
G01X1420877Y1494706D02*
X1428142D01*
X1430374Y1492474D01*
G01X1443041Y876608D02*
Y873683D01*
G01X1434858Y880067D02*
X1437703D01*
G01X1439891Y873821D02*
Y876608D01*
G01X1443575Y927000D02*
X1446022D01*
G01X1440411Y1268685D02*
Y1269176D01*
X1436251Y1273336D01*
G01X1447361Y1273222D02*
Y1270314D01*
X1445732Y1268685D01*
X1444381D01*
G01X1442192Y1273336D02*
X1447247D01*
X1447361Y1273222D01*
G01X1454809Y931848D02*
X1451005D01*
G01X1467556Y890299D02*
X1472689D01*
X1473433Y891043D01*
G01X1474075Y923500D02*
Y920575D01*
G01X1470925Y923500D02*
Y920575D01*
G01X1465833Y928108D02*
X1466317D01*
X1470925Y923500D01*
G01X1480270Y939324D02*
X1483324D01*
G01X1480270Y931324D02*
X1482921D01*
G01X1479441Y959013D02*
Y961941D01*
G01X1482705Y1200001D02*
Y1190948D01*
X1485102Y1188551D01*
Y1182462D01*
X1483829Y1181189D01*
X1479483D01*
X1477533Y1179239D01*
Y1120553D01*
X1475634Y1118654D01*
X1471374D01*
G01X1497488Y876339D02*
Y873839D01*
G01X1487107Y884617D02*
X1485357Y882867D01*
Y881208D01*
X1484988Y880839D01*
G01D02*
X1483673Y882154D01*
X1482566D01*
G01X1484988Y870339D02*
X1482387Y872940D01*
G01X1491107Y884617D02*
X1493383D01*
X1494000Y884000D01*
G01X1496500Y919000D02*
X1497500Y920000D01*
X1498925D01*
G01X1497063Y925240D02*
Y923063D01*
X1496000Y922000D01*
G01X1488500Y943900D02*
X1485100D01*
G01X1493500Y943075D02*
X1496425D01*
G01X1497063Y930740D02*
Y934000D01*
G01X1493500Y939925D02*
X1491675Y938100D01*
X1488500D01*
G01X1496072Y940201D02*
X1495796Y939925D01*
X1493500D01*
G01X1482591Y959013D02*
Y961909D01*
G01X1490500Y948425D02*
X1487925D01*
X1486500Y947000D01*
G01X1497038Y958378D02*
X1497075Y958415D01*
Y961000D01*
G01D02*
Y963500D01*
G01X1490500Y951575D02*
X1487677D01*
X1487240Y952012D01*
G01X1496718Y977181D02*
X1497235D01*
X1498973Y975443D01*
G01D02*
Y969898D01*
X1497075Y968000D01*
G01X1500638Y873839D02*
Y876339D01*
G01X1510500Y929075D02*
Y931500D01*
G01X1505888Y958240D02*
Y962740D01*
G01X1509038D02*
Y958240D01*
G01D02*
X1511462D01*
X1512161Y957541D01*
G01X1505888Y962740D02*
Y965964D01*
G01X1513424Y972094D02*
X1511830Y970500D01*
X1511000D01*
G01X1520933Y915191D02*
Y914382D01*
X1523053Y912262D01*
G01X1520038Y923740D02*
X1523000D01*
G01X1522363Y928740D02*
X1525740D01*
G01X1520933Y918341D02*
Y920942D01*
X1521085Y921094D01*
G01X1535000Y933575D02*
X1530906D01*
X1528087Y936394D01*
G01X1522363Y934240D02*
Y937692D01*
X1522209Y937846D01*
G01X1535000Y930425D02*
X1529489D01*
X1527267Y932647D01*
G01X1535000Y955075D02*
X1533089Y956986D01*
X1530174D01*
G01X1535000Y951925D02*
X1532405D01*
X1531352Y952978D01*
X1529128D01*
G01X1523000Y971075D02*
X1525522D01*
G01X1523000Y967925D02*
X1525008D01*
X1525583Y968500D01*
G01X1533244Y971501D02*
X1532583D01*
X1531103Y972981D01*
X1530767D01*
G01X1564785Y598400D02*
X1562385D01*
G01X1564785Y602400D02*
X1562385D01*
G01X1564785Y594400D02*
X1562385D01*
G01X1564785Y614400D02*
X1562385D01*
G01X1564785Y606400D02*
X1562385D01*
G01X1564785Y610400D02*
X1562385D01*
G01X1560297Y1418806D02*
X1577765D01*
X1592020Y1433061D01*
G01X1572221Y544967D02*
X1572401D01*
X1574540Y547106D01*
G01X1591760Y543925D02*
X1595185D01*
G01X1591760Y547075D02*
X1590806Y548029D01*
Y551894D01*
G01X1595260Y547075D02*
X1591760D01*
G01X1583720Y557800D02*
Y560500D01*
G01X1596752Y1219192D02*
X1595212Y1217652D01*
Y1217027D01*
G01X1589817Y1446488D02*
X1596836D01*
G01X1600333Y1440504D02*
X1599344Y1439515D01*
X1599341Y1439514D01*
X1593289D01*
X1589817Y1442986D01*
Y1446488D01*
G01X1591775Y1473090D02*
X1589255D01*
X1586339Y1470174D01*
Y1449966D01*
X1589817Y1446488D01*
G01X1605430Y1468023D02*
X1598894D01*
X1593827Y1473090D01*
X1591775D01*
G01X1591333Y1501980D02*
Y1473532D01*
X1591775Y1473090D01*
G01X1608500Y1515000D02*
Y1513500D01*
X1606500Y1511500D01*
X1592500D01*
X1591925Y1512075D01*
G01D02*
X1589075D01*
X1587802Y1510802D01*
Y1503699D01*
X1589521Y1501980D01*
X1591333D01*
G01X1815618Y1298744D02*
X1826573Y1309699D01*
Y1408949D01*
X1816294Y1419228D01*
X1621609D01*
X1600333Y1440504D01*
G01X1628636Y422088D02*
X1613778D01*
X1612194Y423672D01*
Y427029D01*
G01X1622344Y431029D02*
X1625952D01*
G01X1622376Y427017D02*
X1626260D01*
G01X1622344Y435029D02*
X1625018D01*
G01X1612194Y431029D02*
Y427029D01*
G01Y435029D02*
Y431029D01*
G01X1640942Y451628D02*
X1637974D01*
X1637665Y451319D01*
G01X1643198Y442606D02*
X1646209D01*
G01X1643198Y446606D02*
X1645826D01*
G01X1641355Y463479D02*
X1638421Y462264D01*
X1637489D01*
G01X1644505Y463479D02*
Y461057D01*
X1646848Y458714D01*
G01X1645685Y388000D02*
Y390500D01*
G01X1655335Y384500D02*
Y381500D01*
G01X1653507Y467367D02*
Y470136D01*
G01X1647133Y463479D02*
X1644505D01*
G01X1669767Y448630D02*
Y445908D01*
G01X1673717Y448630D02*
Y445787D01*
G01X1664074Y1174310D02*
X1662704Y1175680D01*
Y1176475D01*
G01X1678118Y385912D02*
X1680518D01*
G01X1678118Y389912D02*
X1680518D01*
G01X1678118Y377912D02*
X1680518D01*
G01X1678118Y381912D02*
X1680518D01*
G01X1678118Y393924D02*
X1680518D01*
G01X1678118Y405924D02*
X1680518D01*
G01X1678118Y401924D02*
X1680518D01*
G01X1678118Y397912D02*
X1680518D01*
G01X1678118Y409924D02*
X1680518D01*
G01X1737393Y1170767D02*
X1735975Y1172185D01*
X1719915D01*
X1716258Y1168528D01*
X1705894D01*
X1703400Y1171022D01*
Y1174400D01*
X80290Y1345691D03*
Y1350683D03*
X75334Y1345691D03*
Y1350683D03*
X80290Y1357603D03*
Y1362595D03*
X75334Y1357603D03*
Y1362595D03*
X80290Y1381801D03*
Y1369889D03*
Y1374881D03*
X75334Y1381801D03*
Y1374881D03*
Y1369889D03*
X80290Y1386793D03*
X75334D03*
X87574Y1345691D03*
Y1350683D03*
X99814D03*
Y1345691D03*
X92530D03*
Y1350683D03*
X87574Y1362595D03*
Y1357603D03*
X99814Y1362595D03*
Y1357603D03*
X92530Y1362595D03*
Y1357603D03*
X87574Y1374881D03*
Y1369795D03*
Y1381801D03*
X99814D03*
Y1374881D03*
Y1369889D03*
X92530Y1374881D03*
Y1369795D03*
Y1381801D03*
X87574Y1399079D03*
Y1393993D03*
Y1386793D03*
X99814Y1399079D03*
Y1394087D03*
Y1386793D03*
X92530Y1393993D03*
Y1399079D03*
Y1386793D03*
X87574Y1410991D03*
Y1405999D03*
X99814Y1410991D03*
Y1405999D03*
X92530Y1410991D03*
Y1405999D03*
X104770Y1350683D03*
Y1345691D03*
X112054D03*
Y1350683D03*
X117010Y1345691D03*
Y1350683D03*
X104770Y1362595D03*
Y1357603D03*
X112054Y1362595D03*
Y1357603D03*
X117010Y1362595D03*
Y1357603D03*
Y1369889D03*
Y1374881D03*
Y1381801D03*
X104770D03*
Y1374881D03*
Y1369889D03*
X112054D03*
Y1374881D03*
Y1381801D03*
X104770Y1399079D03*
Y1394087D03*
Y1386793D03*
X112054Y1399079D03*
Y1394087D03*
Y1386793D03*
X117010Y1394087D03*
Y1399079D03*
Y1386793D03*
X104770Y1410991D03*
Y1405999D03*
X112054Y1410991D03*
Y1405999D03*
X117010Y1410991D03*
Y1405999D03*
X124294Y1350683D03*
Y1345691D03*
X129250Y1350683D03*
Y1345691D03*
X124294Y1362595D03*
Y1357603D03*
X129250D03*
Y1362595D03*
X124294Y1374881D03*
Y1369889D03*
Y1381801D03*
X129250Y1374881D03*
Y1369889D03*
Y1381801D03*
X124294Y1394087D03*
Y1399079D03*
Y1386793D03*
X129250Y1394087D03*
Y1399079D03*
Y1386793D03*
X124294Y1405999D03*
Y1410991D03*
X129250Y1405999D03*
Y1410991D03*
X141490Y1345691D03*
Y1350683D03*
X136534D03*
Y1345691D03*
X148774Y1350683D03*
Y1345691D03*
X141490Y1357603D03*
Y1362595D03*
X136534D03*
Y1357603D03*
X148774D03*
Y1362595D03*
X141490Y1369889D03*
Y1374881D03*
Y1381801D03*
X136534Y1369889D03*
Y1381801D03*
Y1374881D03*
X148774Y1369889D03*
Y1381801D03*
Y1374881D03*
X141490Y1386793D03*
Y1394087D03*
Y1399079D03*
X136534D03*
Y1394087D03*
Y1386793D03*
X148774Y1394087D03*
Y1399079D03*
Y1386793D03*
X141490Y1405999D03*
Y1410991D03*
X136534D03*
Y1405999D03*
X148774D03*
Y1410991D03*
X161014Y1345691D03*
Y1350683D03*
X153730Y1345691D03*
Y1350683D03*
X165970Y1345691D03*
Y1350683D03*
X161014Y1362595D03*
Y1357603D03*
X153730Y1362595D03*
Y1357603D03*
X165970Y1362595D03*
Y1357603D03*
X161014Y1381801D03*
Y1369889D03*
Y1374881D03*
X153730Y1369889D03*
Y1381801D03*
Y1374881D03*
X165970D03*
Y1381801D03*
Y1369889D03*
X161014Y1394087D03*
Y1386793D03*
X153730Y1394087D03*
Y1386793D03*
X165970Y1394087D03*
Y1386793D03*
X161014Y1399079D03*
X153730D03*
X165970D03*
X161014Y1410991D03*
Y1405999D03*
X153730D03*
Y1410991D03*
X165970D03*
Y1405999D03*
X173254Y1345691D03*
Y1350683D03*
X178210Y1345691D03*
Y1350683D03*
X173254Y1362595D03*
Y1357603D03*
X178210D03*
Y1362595D03*
X173254Y1374881D03*
Y1369889D03*
Y1381801D03*
X178210Y1374881D03*
Y1369889D03*
Y1381801D03*
X173254Y1394087D03*
Y1386793D03*
X178210Y1394087D03*
Y1386793D03*
X173254Y1399079D03*
X178210D03*
X173254Y1405999D03*
Y1410991D03*
X178210Y1405999D03*
Y1410991D03*
X185494Y1345597D03*
Y1350683D03*
X190450Y1345597D03*
Y1350683D03*
X197734Y1345691D03*
Y1350683D03*
X185494Y1362595D03*
Y1357603D03*
X197734Y1362595D03*
Y1357603D03*
X190450Y1362595D03*
Y1357603D03*
X185494Y1374881D03*
Y1381801D03*
Y1369889D03*
X197734D03*
Y1381801D03*
Y1374881D03*
X190450Y1369889D03*
Y1374881D03*
Y1381801D03*
X185494Y1393993D03*
Y1386793D03*
X190450Y1393993D03*
Y1386793D03*
X197734Y1394087D03*
Y1386793D03*
X185494Y1399079D03*
X190450D03*
X197734D03*
X185494Y1410991D03*
Y1405999D03*
X190450Y1410991D03*
Y1405999D03*
X197734D03*
Y1410991D03*
X202690Y1345597D03*
Y1350683D03*
Y1362595D03*
Y1357603D03*
Y1369889D03*
Y1381801D03*
Y1374881D03*
Y1394087D03*
Y1386793D03*
Y1399079D03*
Y1405999D03*
Y1410991D03*
X211473Y1446675D03*
Y1451631D03*
Y1462631D03*
Y1457675D03*
X216465Y1446675D03*
X229745D03*
X224753D03*
X216465Y1451631D03*
Y1462631D03*
Y1457675D03*
X224753Y1462631D03*
X229745Y1457675D03*
X224753D03*
X229745Y1451631D03*
Y1462631D03*
X224753Y1451631D03*
X240845Y1345691D03*
Y1350683D03*
X245801Y1345691D03*
Y1350683D03*
X240845Y1357603D03*
Y1362595D03*
X245801Y1357603D03*
Y1362595D03*
X240845Y1381801D03*
Y1374881D03*
Y1369889D03*
X245801Y1381801D03*
Y1374881D03*
Y1369889D03*
X240845Y1386793D03*
X245801D03*
X258041Y1350683D03*
Y1345691D03*
X253085Y1350683D03*
Y1345691D03*
X258041Y1362595D03*
X253085D03*
X258041Y1357603D03*
X253085D03*
X258041Y1381801D03*
Y1369795D03*
Y1374881D03*
X253085Y1381801D03*
Y1369795D03*
Y1374881D03*
Y1393993D03*
Y1399079D03*
X258041Y1386793D03*
Y1399079D03*
Y1393993D03*
X253085Y1386793D03*
X258041Y1405999D03*
Y1410991D03*
X253085Y1405999D03*
Y1410991D03*
X277565Y1350683D03*
Y1345691D03*
X265325D03*
Y1350683D03*
X270281Y1345691D03*
Y1350683D03*
X277565Y1362595D03*
X265325D03*
X270281D03*
X277565Y1357603D03*
X265325D03*
X270281D03*
X277565Y1381801D03*
Y1374881D03*
Y1369889D03*
X265325D03*
Y1374881D03*
Y1381801D03*
X270281Y1369889D03*
Y1374881D03*
Y1381801D03*
X277565Y1386793D03*
Y1394087D03*
Y1399079D03*
X265325Y1394087D03*
Y1399079D03*
Y1386793D03*
X270281Y1399079D03*
Y1394087D03*
Y1386793D03*
X265325Y1405999D03*
Y1410991D03*
X270281Y1405999D03*
Y1410991D03*
X277565Y1405999D03*
Y1410991D03*
X282521Y1345691D03*
X289805Y1350683D03*
Y1345691D03*
X294761Y1350683D03*
Y1345691D03*
X282521Y1350683D03*
X289805Y1362595D03*
X294761D03*
X282521D03*
X289805Y1357603D03*
X294761D03*
X282521D03*
X289805Y1374881D03*
Y1369889D03*
Y1381801D03*
X294761Y1374881D03*
Y1369889D03*
Y1381801D03*
X282521D03*
Y1374881D03*
Y1369889D03*
X289805Y1394087D03*
Y1399079D03*
Y1386793D03*
X294761Y1394087D03*
Y1399079D03*
Y1386793D03*
X282521D03*
Y1399079D03*
Y1394087D03*
X289805Y1405999D03*
Y1410991D03*
X294761Y1405999D03*
Y1410991D03*
X282521Y1405999D03*
Y1410991D03*
X302045Y1345691D03*
Y1350683D03*
X307001D03*
Y1345691D03*
X302045Y1362595D03*
X307001D03*
X302045Y1357603D03*
X307001D03*
X302045Y1374881D03*
Y1381801D03*
Y1369889D03*
X307001Y1374881D03*
Y1369889D03*
Y1381801D03*
X302045Y1386793D03*
Y1394087D03*
Y1399079D03*
X307001Y1386793D03*
Y1399079D03*
Y1394087D03*
X302045Y1405999D03*
Y1410991D03*
X307001Y1405999D03*
Y1410991D03*
X319241Y1350683D03*
Y1345691D03*
X314285D03*
Y1350683D03*
X326525Y1345691D03*
Y1350683D03*
X319241Y1362595D03*
X314285D03*
X326525D03*
X319241Y1357603D03*
X314285D03*
X326525D03*
X319241Y1374881D03*
Y1381801D03*
Y1369889D03*
X314285Y1374881D03*
Y1381801D03*
Y1369889D03*
X326525Y1381801D03*
Y1369889D03*
Y1374881D03*
X319241Y1386793D03*
Y1399079D03*
Y1394087D03*
X314285Y1386793D03*
Y1399079D03*
Y1394087D03*
X326525Y1399079D03*
Y1394087D03*
Y1386793D03*
X319241Y1410991D03*
Y1405999D03*
X314285Y1410991D03*
Y1405999D03*
X326525Y1410991D03*
Y1405999D03*
X338765Y1350683D03*
Y1345691D03*
X331481D03*
Y1350683D03*
X343721Y1345691D03*
Y1350683D03*
X331481Y1362595D03*
X343721D03*
X338765D03*
X331481Y1357603D03*
X343721D03*
X338765D03*
X331481Y1374881D03*
Y1381801D03*
Y1369889D03*
X343721Y1381801D03*
Y1369889D03*
Y1374881D03*
X338765Y1381801D03*
Y1369889D03*
Y1374881D03*
X331481Y1399079D03*
Y1394087D03*
Y1386793D03*
X343721D03*
Y1394087D03*
Y1399079D03*
X338765Y1386793D03*
Y1394087D03*
Y1399079D03*
X331481Y1410991D03*
Y1405999D03*
X343721Y1410991D03*
Y1405999D03*
X338765Y1410991D03*
Y1405999D03*
X355961Y1350683D03*
X351005Y1345597D03*
Y1350683D03*
X355961Y1345597D03*
X351005Y1362595D03*
X355961D03*
X351005Y1357603D03*
X355961D03*
X351005Y1374881D03*
Y1381801D03*
Y1369889D03*
X355961Y1381801D03*
Y1374881D03*
Y1369889D03*
X351005Y1399079D03*
Y1393993D03*
Y1386793D03*
X355961D03*
Y1399079D03*
Y1393993D03*
X351005Y1410991D03*
Y1405999D03*
X355961D03*
Y1410991D03*
X363245Y1345691D03*
Y1350683D03*
X368201Y1345691D03*
Y1350683D03*
X363245Y1362595D03*
X368201D03*
X363245Y1357603D03*
X368201D03*
X363245Y1369889D03*
Y1381801D03*
Y1374881D03*
X368201D03*
Y1381801D03*
Y1369889D03*
X363245Y1399079D03*
Y1394087D03*
Y1386793D03*
X368201D03*
Y1394087D03*
Y1399079D03*
X363245Y1405999D03*
Y1410991D03*
X368201D03*
Y1405999D03*
X393094Y1423600D03*
X408523Y1332967D03*
X404657D03*
X395894Y1423600D03*
X439624Y1345691D03*
Y1350683D03*
Y1357603D03*
Y1362595D03*
Y1381801D03*
Y1369889D03*
Y1374881D03*
Y1386793D03*
X435881Y1394934D03*
Y1398800D03*
X456820Y1345691D03*
X451864D03*
Y1350683D03*
X456820D03*
X444580Y1345691D03*
Y1350683D03*
X456820Y1362595D03*
Y1357603D03*
X451864Y1362595D03*
Y1357603D03*
X444580D03*
Y1362595D03*
X456820Y1374881D03*
X451864D03*
X444580Y1369889D03*
X456820Y1369795D03*
X451864D03*
X444580Y1374881D03*
Y1381801D03*
X456820D03*
X451864D03*
X456820Y1399079D03*
X451864Y1393993D03*
Y1399079D03*
X456820Y1393993D03*
Y1386793D03*
X451864D03*
X444580D03*
X456820Y1405999D03*
X451864D03*
Y1410991D03*
X456820D03*
X454125Y1461182D03*
Y1465913D03*
Y1481267D03*
Y1476536D03*
Y1491890D03*
Y1496621D03*
Y1511976D03*
Y1507245D03*
Y1578898D03*
Y1568275D03*
Y1563544D03*
Y1583629D03*
Y1594253D03*
Y1609607D03*
Y1598984D03*
Y1614338D03*
X469060Y1345691D03*
Y1350683D03*
X464104Y1345691D03*
Y1350683D03*
X469060Y1357603D03*
Y1362595D03*
X464104D03*
Y1357603D03*
Y1381801D03*
X469060D03*
X464104Y1369889D03*
X469060D03*
X464104Y1374881D03*
X469060D03*
Y1386793D03*
X464104D03*
X469060Y1399079D03*
X464104Y1394087D03*
X469060D03*
X464104Y1399079D03*
Y1405999D03*
X469060D03*
X464104Y1410991D03*
X469060D03*
X471448Y1461182D03*
Y1465913D03*
X462786Y1465513D03*
X471448Y1481267D03*
X462786Y1480867D03*
X471448Y1476536D03*
X462786Y1470244D03*
X471448Y1496621D03*
X462786Y1496221D03*
X471448Y1491890D03*
X462786Y1485598D03*
X471448Y1511976D03*
Y1507245D03*
X462786Y1511576D03*
Y1500952D03*
Y1516307D03*
X471448Y1568275D03*
Y1563544D03*
X462786Y1567875D03*
Y1572606D03*
X471448Y1578898D03*
Y1594253D03*
Y1583629D03*
X462786Y1583229D03*
Y1587960D03*
X471448Y1598984D03*
X462786Y1598584D03*
Y1603315D03*
X471448Y1609607D03*
Y1614338D03*
X462786Y1613938D03*
Y1618669D03*
X488584Y1345691D03*
Y1350683D03*
X481300Y1345691D03*
X476344D03*
X481300Y1350683D03*
X476344D03*
X488584Y1357603D03*
Y1362595D03*
X481300D03*
Y1357603D03*
X476344Y1362595D03*
Y1357603D03*
X488584Y1381801D03*
X481300D03*
X488584Y1374881D03*
Y1369889D03*
X481300D03*
Y1374881D03*
X476344Y1381801D03*
Y1369889D03*
Y1374881D03*
X488584Y1386793D03*
X481300D03*
Y1399079D03*
X476344Y1394087D03*
Y1399079D03*
X488584Y1394087D03*
X481300D03*
X488584Y1399079D03*
X476344Y1386793D03*
Y1410991D03*
X481300Y1405999D03*
X476344D03*
X488584D03*
Y1410991D03*
X481300D03*
X480109Y1465513D03*
X488771Y1465913D03*
Y1461182D03*
X480109Y1470244D03*
X488771Y1476536D03*
Y1481267D03*
X480109Y1480867D03*
Y1496221D03*
X488771Y1491890D03*
X480109Y1485598D03*
X488771Y1496621D03*
Y1511976D03*
X480109Y1511576D03*
Y1500952D03*
X488771Y1507245D03*
X480109Y1516307D03*
X488771Y1578898D03*
Y1568275D03*
Y1563544D03*
X480109Y1567875D03*
Y1572606D03*
X488771Y1583629D03*
X480109Y1583229D03*
Y1587960D03*
X488771Y1594253D03*
Y1609607D03*
Y1598984D03*
X480109Y1598584D03*
Y1603315D03*
X488771Y1614338D03*
X480109Y1613938D03*
Y1618669D03*
X500824Y1350683D03*
Y1345691D03*
X505780Y1350683D03*
Y1345691D03*
X493540D03*
Y1350683D03*
X505780Y1362595D03*
Y1357603D03*
X500824Y1362595D03*
Y1357603D03*
X493540Y1362595D03*
Y1357603D03*
Y1381801D03*
Y1374881D03*
Y1369889D03*
X505780Y1381801D03*
Y1374881D03*
Y1369889D03*
X500824D03*
Y1381801D03*
Y1374881D03*
Y1394087D03*
X505780Y1399079D03*
X500824D03*
X505780Y1394087D03*
X493540Y1386793D03*
Y1394087D03*
Y1399079D03*
X505780Y1386793D03*
X500824D03*
X505780Y1410991D03*
X500824D03*
X505780Y1405999D03*
X500824D03*
X493540D03*
Y1410991D03*
X497432Y1465513D03*
X506093Y1465913D03*
Y1461182D03*
X497432Y1480867D03*
X506093Y1481267D03*
X497432Y1470244D03*
X506093Y1476536D03*
X497432Y1496221D03*
Y1485598D03*
X506093Y1491890D03*
Y1496621D03*
Y1511976D03*
X497432Y1500952D03*
X506093Y1507245D03*
X497432Y1511576D03*
Y1516307D03*
X506093Y1578898D03*
X497432Y1567875D03*
Y1572606D03*
X506093Y1568275D03*
Y1563544D03*
X497432Y1587960D03*
X506093Y1583629D03*
Y1594253D03*
X497432Y1583229D03*
X506093Y1598984D03*
Y1609607D03*
X497432Y1598584D03*
Y1603315D03*
Y1613938D03*
Y1618669D03*
X506093Y1614338D03*
X515573Y692515D03*
X518299Y692384D03*
X520799D03*
X513064Y1345691D03*
X518020Y1350683D03*
X513064D03*
X518020Y1345691D03*
Y1357603D03*
X513064Y1362595D03*
Y1357603D03*
X518020Y1362595D03*
X513064Y1369889D03*
Y1381801D03*
Y1374881D03*
X518020Y1369889D03*
Y1381801D03*
Y1374881D03*
Y1394087D03*
Y1399079D03*
X513064Y1394087D03*
Y1399079D03*
Y1386793D03*
X518020D03*
Y1405999D03*
Y1410991D03*
X513064D03*
Y1405999D03*
X514755Y1465513D03*
Y1480867D03*
Y1470244D03*
Y1485598D03*
Y1496221D03*
Y1511576D03*
Y1500952D03*
Y1516307D03*
Y1567875D03*
Y1572606D03*
Y1583229D03*
Y1587960D03*
Y1603315D03*
Y1598584D03*
Y1613938D03*
Y1618669D03*
X529493Y692443D03*
Y697443D03*
Y699943D03*
X529501Y702622D03*
X526993Y692443D03*
X529493Y694943D03*
X524493Y692443D03*
X525304Y1345691D03*
X530260D03*
X537544Y1350683D03*
X525304D03*
X530260D03*
X537544Y1345691D03*
Y1357603D03*
X525304Y1362595D03*
X530260D03*
X525304Y1357603D03*
X530260D03*
X537544Y1362595D03*
Y1374881D03*
X525304Y1369889D03*
Y1381801D03*
Y1374881D03*
X530260Y1369889D03*
Y1381801D03*
Y1374881D03*
X537544Y1369889D03*
Y1381801D03*
Y1399079D03*
Y1394087D03*
X530260D03*
Y1399079D03*
X525304Y1394087D03*
Y1399079D03*
X537544Y1386793D03*
X525304D03*
X530260D03*
X537544Y1410991D03*
Y1405999D03*
X530260D03*
X525304D03*
X530260Y1410991D03*
X525304D03*
X554740Y1345597D03*
X542500Y1345691D03*
X549784Y1345597D03*
X542500Y1350683D03*
X549784D03*
X554740D03*
Y1362595D03*
Y1357603D03*
X542500Y1362595D03*
X549784D03*
X542500Y1357603D03*
X549784D03*
X554740Y1381801D03*
Y1374881D03*
X542500D03*
X549784Y1369889D03*
Y1381801D03*
Y1374881D03*
X542500Y1369889D03*
Y1381801D03*
X554740Y1369889D03*
Y1399079D03*
Y1393993D03*
X542500Y1399079D03*
X549784Y1393993D03*
Y1399079D03*
X542500Y1394087D03*
X554740Y1386793D03*
X549784D03*
X542500D03*
X554740Y1410991D03*
Y1405999D03*
X542500Y1410991D03*
X549784D03*
X542500Y1405999D03*
X549784D03*
X562024Y1350683D03*
Y1345691D03*
X566980D03*
Y1350683D03*
X562024Y1357603D03*
X566980D03*
Y1362595D03*
X562024D03*
Y1369889D03*
Y1381801D03*
Y1374881D03*
X566980Y1369889D03*
Y1381801D03*
Y1374881D03*
Y1399079D03*
Y1394087D03*
X562024Y1399079D03*
Y1394087D03*
X566980Y1386793D03*
X562024D03*
X566980Y1410991D03*
X562024D03*
X566980Y1405999D03*
X562024D03*
X630466Y1394087D03*
X625510Y1399079D03*
Y1394087D03*
X630466Y1399079D03*
X625510Y1405999D03*
X630466D03*
X625510Y1410991D03*
X630466D03*
X649990Y1350683D03*
Y1345691D03*
Y1357603D03*
Y1362595D03*
Y1381801D03*
X642706Y1374881D03*
Y1381801D03*
Y1369889D03*
X649990Y1374881D03*
Y1369889D03*
X637750Y1374881D03*
Y1381801D03*
Y1369889D03*
X649990Y1399079D03*
Y1394087D03*
X642706Y1386793D03*
X649990D03*
X637750Y1399079D03*
X642706Y1394087D03*
X637750D03*
X642706Y1399079D03*
X637750Y1386793D03*
X649990Y1405999D03*
Y1410991D03*
X637750D03*
X642706D03*
Y1405999D03*
X637750D03*
X654946Y1350683D03*
X662230D03*
X667186D03*
Y1345691D03*
X654946D03*
X662230D03*
X654946Y1357603D03*
Y1362595D03*
X662230Y1357603D03*
Y1362595D03*
X667186Y1357603D03*
Y1362595D03*
X662230Y1369889D03*
X667186Y1374881D03*
Y1381801D03*
Y1369889D03*
X662230Y1374881D03*
Y1381801D03*
X654946D03*
Y1369889D03*
Y1374881D03*
X667186Y1399079D03*
Y1393993D03*
X662230D03*
Y1399079D03*
X655046D03*
Y1394087D03*
X667186Y1386793D03*
X662230D03*
X654946D03*
X667186Y1410991D03*
Y1405999D03*
X662230D03*
Y1410991D03*
X655046Y1405999D03*
Y1410991D03*
X679426Y1350683D03*
X674470Y1345691D03*
X679426D03*
X674470Y1350683D03*
Y1357603D03*
Y1362595D03*
X679426Y1357603D03*
Y1362595D03*
Y1374881D03*
X674470D03*
Y1381801D03*
X679426D03*
Y1369889D03*
X674470D03*
X679426Y1399079D03*
X674470Y1394087D03*
X679426D03*
X674470Y1399079D03*
Y1386793D03*
X679426D03*
X674470Y1405999D03*
X679426D03*
X674470Y1410991D03*
X679426D03*
X698950Y1350683D03*
Y1345597D03*
X686710Y1350683D03*
X691666D03*
X686710Y1345691D03*
X691666D03*
X698950Y1362595D03*
Y1357603D03*
X686710D03*
Y1362595D03*
X691666Y1357603D03*
Y1362595D03*
X698950Y1374881D03*
Y1381801D03*
Y1369889D03*
X691666D03*
Y1374881D03*
Y1381801D03*
X686710Y1374881D03*
Y1369889D03*
Y1381801D03*
X698950Y1399079D03*
Y1394087D03*
X686710D03*
Y1399079D03*
X691666Y1394087D03*
Y1399079D03*
X698950Y1386793D03*
X691666D03*
X686710D03*
X698950Y1405999D03*
Y1410991D03*
X686710D03*
X691666D03*
X686710Y1405999D03*
X691666D03*
X716146Y1350683D03*
X711190D03*
X716146Y1345691D03*
X711190D03*
X703906Y1350683D03*
Y1345597D03*
X716146Y1357603D03*
X711190D03*
Y1362595D03*
X716146D03*
X703906Y1357603D03*
Y1362595D03*
X716146Y1374881D03*
Y1381801D03*
Y1369889D03*
X711190D03*
Y1374881D03*
Y1381801D03*
X703906D03*
Y1369889D03*
Y1374881D03*
X716146Y1399079D03*
X711190D03*
X716146Y1393993D03*
X711190D03*
X703906Y1394087D03*
Y1399079D03*
X716146Y1386793D03*
X711190D03*
X703906D03*
X716146Y1405999D03*
X711190D03*
X716146Y1410991D03*
X711190D03*
X703906Y1405999D03*
Y1410991D03*
X723430Y1350683D03*
X728386Y1345691D03*
X723430D03*
X728386Y1350683D03*
Y1357603D03*
Y1362595D03*
X723430Y1357603D03*
Y1362595D03*
X728386Y1381801D03*
Y1374881D03*
Y1369889D03*
X723430D03*
Y1381801D03*
Y1374881D03*
X728386Y1386793D03*
X723430D03*
X728386Y1398985D03*
Y1393993D03*
X723430Y1398985D03*
Y1393993D03*
X728386Y1410897D03*
Y1405905D03*
X723430Y1410897D03*
Y1405905D03*
X747910Y1345691D03*
Y1350683D03*
X735670D03*
X740626D03*
X735670Y1345691D03*
X740626D03*
X747910Y1357603D03*
Y1362595D03*
X735670Y1357603D03*
Y1362595D03*
X740626Y1357603D03*
Y1362595D03*
X747910Y1374881D03*
Y1381801D03*
Y1369889D03*
X740626Y1381801D03*
Y1369889D03*
Y1374881D03*
X735670Y1381801D03*
Y1369889D03*
Y1374881D03*
X747910Y1386793D03*
X735670Y1393993D03*
X740626D03*
Y1398985D03*
X735670D03*
X740626Y1386793D03*
X735670D03*
Y1405905D03*
Y1410897D03*
X740626Y1405905D03*
Y1410897D03*
X765106Y1350683D03*
Y1345597D03*
X760150D03*
Y1350683D03*
X752866Y1345691D03*
Y1350683D03*
X765106Y1362595D03*
Y1357603D03*
X760150D03*
Y1362595D03*
X752866Y1357603D03*
Y1362595D03*
X765106Y1374881D03*
Y1381801D03*
Y1369889D03*
X760150Y1374881D03*
Y1381801D03*
Y1369889D03*
X752866Y1374881D03*
Y1381801D03*
Y1369889D03*
X765106Y1386793D03*
X760150D03*
X752866D03*
X772390Y1350683D03*
X777346D03*
Y1345691D03*
X772390D03*
Y1357603D03*
Y1362595D03*
X777346Y1357603D03*
Y1362595D03*
X878220Y848442D03*
Y845293D03*
Y835844D03*
Y851592D03*
X877800Y876500D03*
X897118Y848442D03*
X881370Y835844D03*
X893968Y845293D03*
X884519Y848442D03*
X897118Y842143D03*
X893968D03*
X887669Y848442D03*
X886093Y835318D03*
X897118Y845293D03*
X893968Y838994D03*
X890818Y842143D03*
X893968Y835846D03*
X887669Y845293D03*
X890818D03*
X893968Y848442D03*
X884519Y845293D03*
X881370D03*
X884519Y842143D03*
X887669D03*
X881370Y848442D03*
X890818D03*
X897118Y857891D03*
Y864189D03*
Y854742D03*
X893968Y864189D03*
Y857891D03*
Y854742D03*
X887669Y851592D03*
X890818Y854742D03*
X887669D03*
X897118Y851592D03*
X890818Y864189D03*
Y857891D03*
X887669Y864189D03*
X884519Y854742D03*
Y851592D03*
Y857891D03*
X887669D03*
X890818Y851592D03*
X893967Y851591D03*
X881370Y851592D03*
X897118Y873638D03*
Y870488D03*
Y867338D03*
X893968Y870488D03*
Y873638D03*
Y867338D03*
X887669Y876787D03*
Y867338D03*
X890818Y870488D03*
X887669D03*
X897118Y876787D03*
X890818Y867338D03*
X881370D03*
X897118Y879937D03*
X884519Y873638D03*
X887669D03*
X884519Y876787D03*
X890818Y879937D03*
X881370Y876787D03*
X887669Y879937D03*
X884519Y867338D03*
X890818Y873638D03*
X893968Y876787D03*
Y879937D03*
X890818Y876787D03*
X884519Y879937D03*
Y870488D03*
X881370D03*
Y883086D03*
X884585Y886354D03*
X885126Y889742D03*
X881370Y886236D03*
X912864Y848442D03*
Y845293D03*
Y842143D03*
X909714Y845293D03*
Y842143D03*
Y838994D03*
X906565Y848442D03*
X900267D03*
X906565Y838994D03*
X900267Y838992D03*
X909714Y848442D03*
X906565Y842143D03*
X900267Y845293D03*
Y842143D03*
X906565Y845293D03*
X900266Y835844D03*
X900267Y864189D03*
X909714Y854742D03*
X906565Y857891D03*
X909714D03*
X906565Y864189D03*
X909714D03*
X906565Y854742D03*
X900267Y857891D03*
Y854742D03*
X912864Y851592D03*
Y864189D03*
Y857891D03*
Y854742D03*
X900267Y851592D03*
X906565D03*
X909714D03*
Y873638D03*
Y870488D03*
X906565Y873638D03*
Y870488D03*
Y867338D03*
X900267Y873638D03*
Y870488D03*
Y867338D03*
X909714D03*
X912864Y870488D03*
Y867338D03*
X909714Y876787D03*
X900267Y879937D03*
Y876787D03*
X906565D03*
X912864Y873638D03*
Y879937D03*
X909714D03*
X906565D03*
X912864Y876787D03*
X928612Y835844D03*
X922313Y845293D03*
X916014Y848442D03*
Y842143D03*
X919163Y845293D03*
X922313Y842143D03*
X916014Y845293D03*
X919163Y835844D03*
Y838994D03*
Y842143D03*
X925462Y845293D03*
X922313Y851592D03*
X929611Y858669D03*
X919163Y854742D03*
Y857891D03*
X922313Y854742D03*
X916014Y857891D03*
Y854742D03*
Y851592D03*
Y864189D03*
X925462Y851592D03*
X922313Y864189D03*
Y857891D03*
X925462D03*
X928612Y864189D03*
X919163D03*
X925462D03*
X916014Y870488D03*
X925462Y873638D03*
X922313Y876787D03*
X928612Y870488D03*
X925462D03*
X916014Y873638D03*
X922313D03*
X916014Y876787D03*
X928612Y873638D03*
X925462Y876787D03*
X928612D03*
Y879937D03*
X916014D03*
X922313D03*
X919163D03*
X925462D03*
X916014Y867338D03*
X919163Y873638D03*
Y870488D03*
X922313D03*
X919163Y876787D03*
X922313Y867338D03*
X919163D03*
X925462D03*
X922313Y883086D03*
Y886236D03*
X925462D03*
X919163Y883086D03*
X928612Y886236D03*
X925462Y883086D03*
X928612D03*
X1058891Y1345691D03*
Y1350683D03*
X1053935Y1345691D03*
Y1350683D03*
X1058891Y1362595D03*
X1053935D03*
X1058891Y1357603D03*
X1053935D03*
X1058891Y1381801D03*
Y1374881D03*
Y1369889D03*
X1053935Y1381801D03*
Y1374881D03*
Y1369889D03*
X1058891Y1386793D03*
X1053935D03*
X1066175Y1350683D03*
Y1345691D03*
X1071131Y1350683D03*
Y1345691D03*
X1066175Y1357603D03*
Y1362595D03*
X1071131Y1357603D03*
Y1362595D03*
X1066175Y1381801D03*
Y1369795D03*
Y1374881D03*
X1071131Y1381801D03*
Y1369795D03*
Y1374881D03*
X1066175Y1393993D03*
Y1399079D03*
Y1386793D03*
X1071131Y1399079D03*
Y1393993D03*
Y1386793D03*
X1066175Y1405999D03*
Y1410991D03*
X1071131Y1405999D03*
Y1410991D03*
X1090655Y1350683D03*
Y1345691D03*
X1083371D03*
Y1350683D03*
X1078415Y1345691D03*
Y1350683D03*
X1090655Y1357603D03*
Y1362595D03*
X1083371Y1357603D03*
Y1362595D03*
X1078415D03*
Y1357603D03*
X1090655Y1381801D03*
Y1374881D03*
Y1369889D03*
X1083371D03*
Y1374881D03*
Y1381801D03*
X1078415Y1369889D03*
Y1374881D03*
Y1381801D03*
X1090655Y1394087D03*
Y1399079D03*
Y1386793D03*
X1083371D03*
Y1399079D03*
Y1394087D03*
X1078415Y1386793D03*
Y1394087D03*
Y1399079D03*
X1090655Y1405999D03*
Y1410991D03*
X1083371Y1405999D03*
Y1410991D03*
X1078415Y1405999D03*
Y1410991D03*
X1107851Y1345691D03*
X1102895Y1350683D03*
Y1345691D03*
X1107851Y1350683D03*
X1095611D03*
Y1345691D03*
X1107851Y1357603D03*
X1102895Y1362595D03*
Y1357603D03*
X1107851Y1362595D03*
X1095611Y1357603D03*
Y1362595D03*
X1107851Y1369889D03*
Y1374881D03*
Y1381801D03*
X1102895Y1374881D03*
Y1369889D03*
Y1381801D03*
X1095611D03*
Y1374881D03*
Y1369889D03*
X1107851Y1386793D03*
Y1394087D03*
Y1399079D03*
X1102895Y1386793D03*
Y1394087D03*
Y1399079D03*
X1095611D03*
Y1394087D03*
Y1386793D03*
X1107851Y1405999D03*
Y1410991D03*
X1102895Y1405999D03*
Y1410991D03*
X1095611Y1405999D03*
Y1410991D03*
X1115135Y1345691D03*
Y1350683D03*
X1120091Y1345691D03*
Y1350683D03*
X1115135Y1357603D03*
Y1362595D03*
X1120091Y1357603D03*
Y1362595D03*
X1115135Y1374881D03*
Y1381801D03*
Y1369889D03*
X1120091D03*
Y1374881D03*
Y1381801D03*
X1115135Y1394087D03*
Y1399079D03*
Y1386793D03*
X1120091Y1399079D03*
Y1394087D03*
Y1386793D03*
X1115135Y1405999D03*
Y1410991D03*
X1120091Y1405999D03*
Y1410991D03*
X1139615Y1350683D03*
Y1345691D03*
X1132331D03*
Y1350683D03*
X1127375D03*
Y1345691D03*
X1139615Y1357603D03*
Y1362595D03*
X1132331D03*
Y1357603D03*
X1127375D03*
Y1362595D03*
X1139615Y1374881D03*
Y1369889D03*
Y1381801D03*
X1132331Y1369889D03*
Y1381801D03*
Y1374881D03*
X1127375Y1369889D03*
Y1381801D03*
Y1374881D03*
X1139615Y1394087D03*
Y1399079D03*
Y1386793D03*
X1132331D03*
Y1394087D03*
Y1399079D03*
X1127375Y1386793D03*
Y1394087D03*
Y1399079D03*
X1139615Y1405999D03*
Y1410991D03*
X1132331Y1405999D03*
Y1410991D03*
X1127375Y1405999D03*
Y1410991D03*
X1156811Y1350683D03*
Y1345691D03*
X1151855D03*
Y1350683D03*
X1144571D03*
Y1345691D03*
X1156811Y1357603D03*
Y1362595D03*
X1151855D03*
Y1357603D03*
X1144571D03*
Y1362595D03*
X1156811Y1374881D03*
Y1369889D03*
Y1381801D03*
X1151855Y1374881D03*
Y1369889D03*
Y1381801D03*
X1144571Y1369889D03*
Y1381801D03*
Y1374881D03*
X1156811Y1386793D03*
Y1399079D03*
Y1394087D03*
X1151855Y1386793D03*
Y1399079D03*
Y1394087D03*
X1144571D03*
Y1399079D03*
Y1386793D03*
X1156811Y1405999D03*
Y1410991D03*
X1151855Y1405999D03*
Y1410991D03*
X1144571Y1405999D03*
Y1410991D03*
X1169051Y1345597D03*
Y1350683D03*
X1164095D03*
Y1345597D03*
X1169051Y1357603D03*
Y1362595D03*
X1164095Y1357603D03*
Y1362595D03*
X1169051Y1381801D03*
Y1374881D03*
Y1369889D03*
X1164095D03*
Y1381801D03*
Y1374881D03*
X1169051Y1393993D03*
Y1399079D03*
Y1386793D03*
X1164095Y1393993D03*
Y1399079D03*
Y1386793D03*
X1169051Y1410991D03*
Y1405999D03*
X1164095D03*
Y1410991D03*
X1181291Y1350683D03*
Y1345691D03*
X1176335D03*
Y1350683D03*
X1181291Y1362595D03*
Y1357603D03*
X1176335Y1362595D03*
Y1357603D03*
X1181291Y1369889D03*
Y1381801D03*
Y1374881D03*
X1176335Y1369889D03*
Y1381801D03*
Y1374881D03*
X1181291Y1386793D03*
Y1399079D03*
Y1394087D03*
X1176335Y1386793D03*
Y1399079D03*
Y1394087D03*
X1181291Y1405999D03*
Y1410991D03*
X1176335Y1405999D03*
Y1410991D03*
X1229548Y1350683D03*
Y1345691D03*
X1234504D03*
Y1350683D03*
X1229548Y1362595D03*
Y1357603D03*
X1234504D03*
Y1362595D03*
X1229548Y1369889D03*
Y1374881D03*
Y1381801D03*
X1234504Y1369889D03*
Y1374881D03*
Y1381801D03*
X1229548Y1386793D03*
X1234504D03*
X1254028Y1350683D03*
Y1345691D03*
X1241788D03*
Y1350683D03*
X1246744Y1345691D03*
Y1350683D03*
X1254028Y1357603D03*
Y1362595D03*
X1241788D03*
Y1357603D03*
X1246744Y1362595D03*
Y1357603D03*
X1254028Y1381801D03*
Y1374881D03*
Y1369889D03*
X1241788Y1374881D03*
Y1369795D03*
Y1381801D03*
X1246744Y1374881D03*
Y1369795D03*
Y1381801D03*
X1254028Y1386793D03*
Y1399079D03*
Y1394087D03*
X1241788Y1399079D03*
Y1393993D03*
Y1386793D03*
X1246744Y1393993D03*
Y1399079D03*
Y1386793D03*
X1254028Y1410991D03*
Y1405999D03*
X1241788Y1410991D03*
Y1405999D03*
X1246744Y1410991D03*
Y1405999D03*
X1266268Y1345691D03*
Y1350683D03*
X1258984D03*
Y1345691D03*
X1266268Y1362595D03*
Y1357603D03*
X1258984Y1362595D03*
Y1357603D03*
X1266268Y1369889D03*
Y1374881D03*
Y1381801D03*
X1258984D03*
Y1369889D03*
Y1374881D03*
X1266268Y1399079D03*
Y1394087D03*
Y1386793D03*
X1258984Y1394087D03*
Y1386793D03*
Y1399079D03*
X1266268Y1410991D03*
Y1405999D03*
X1258984D03*
Y1410991D03*
X1283464Y1345691D03*
Y1350683D03*
X1278508Y1345691D03*
Y1350683D03*
X1271224Y1345691D03*
Y1350683D03*
X1283464Y1362595D03*
Y1357603D03*
X1278508D03*
Y1362595D03*
X1271224D03*
Y1357603D03*
X1283464Y1381801D03*
Y1369889D03*
Y1374881D03*
X1278508Y1381801D03*
Y1369889D03*
Y1374881D03*
X1271224Y1369889D03*
Y1374881D03*
Y1381801D03*
X1283464Y1386793D03*
Y1399079D03*
Y1394087D03*
X1278508Y1386793D03*
Y1399079D03*
Y1394087D03*
X1271224D03*
Y1399079D03*
Y1386793D03*
X1283464Y1410991D03*
Y1405999D03*
X1278508Y1410991D03*
Y1405999D03*
X1271224Y1410991D03*
Y1405999D03*
X1302988Y1345691D03*
Y1350683D03*
X1290748D03*
Y1345691D03*
X1295704Y1350683D03*
Y1345691D03*
X1302988Y1362595D03*
Y1357603D03*
X1290748Y1362595D03*
Y1357603D03*
X1295704Y1362595D03*
Y1357603D03*
X1302988Y1374881D03*
Y1381801D03*
Y1369889D03*
X1290748D03*
Y1381801D03*
Y1374881D03*
X1295704Y1381801D03*
Y1374881D03*
Y1369889D03*
X1302988Y1386793D03*
Y1399079D03*
Y1394087D03*
X1290748Y1399079D03*
Y1394087D03*
Y1386793D03*
X1295704Y1394087D03*
Y1399079D03*
Y1386793D03*
X1302988Y1410991D03*
Y1405999D03*
X1290748Y1410991D03*
Y1405999D03*
X1295704Y1410991D03*
Y1405999D03*
X1313756Y829871D03*
X1316906D03*
Y842470D03*
Y833021D03*
Y848769D03*
X1313756Y833021D03*
Y836170D03*
X1316906Y839320D03*
X1310555Y848675D03*
X1313756Y848769D03*
X1316906Y836170D03*
X1313756Y842470D03*
Y858218D03*
X1316906Y855068D03*
X1313756Y855066D03*
X1316906Y858218D03*
Y867665D03*
Y883413D03*
Y892862D03*
X1309856Y899161D03*
X1305761D03*
X1313756D03*
X1315228Y1345691D03*
Y1350683D03*
X1307944D03*
Y1345691D03*
X1315228Y1362595D03*
Y1357603D03*
X1307944D03*
Y1362595D03*
X1315228Y1381801D03*
Y1369889D03*
Y1374881D03*
X1307944D03*
Y1381801D03*
Y1369889D03*
X1315228Y1399079D03*
Y1394087D03*
Y1386793D03*
X1307944D03*
Y1399079D03*
Y1394087D03*
X1315228Y1410991D03*
Y1405999D03*
X1307944Y1410991D03*
Y1405999D03*
X1335803Y829871D03*
X1323205D03*
X1332654Y836170D03*
X1326355Y839320D03*
X1335803D03*
X1329504Y833021D03*
X1332654Y842470D03*
X1329504Y845619D03*
X1332654D03*
X1326355Y836170D03*
X1335803Y842470D03*
X1329504Y836170D03*
X1335803Y845619D03*
Y848769D03*
X1329504Y839320D03*
X1323205Y836170D03*
X1335803D03*
X1329504Y842470D03*
X1335803Y833021D03*
X1323205D03*
X1320055Y845619D03*
X1326355D03*
X1320055Y836170D03*
X1326355Y842470D03*
X1320055Y848769D03*
X1323205Y845619D03*
X1332654Y848769D03*
X1320055Y839320D03*
X1326355Y848769D03*
X1323205D03*
X1329504D03*
X1323204Y839319D03*
X1332654Y839320D03*
X1320055Y842470D03*
X1323205D03*
Y861367D03*
X1335803Y851918D03*
X1329504Y855068D03*
Y858218D03*
X1320055Y851918D03*
X1332654Y855068D03*
X1326355D03*
Y858218D03*
X1329504Y861367D03*
X1323205Y858218D03*
X1320055D03*
X1332654Y861367D03*
X1329504Y851918D03*
X1323205D03*
X1326355Y861367D03*
X1320055Y855068D03*
X1332654Y858218D03*
X1335803Y855068D03*
Y858218D03*
Y861367D03*
X1320055D03*
X1323204Y855067D03*
X1326355Y851918D03*
X1332654D03*
X1335803Y877114D03*
X1326355Y880263D03*
X1329504Y877114D03*
X1335803Y880263D03*
X1326355Y867665D03*
Y870814D03*
X1323205D03*
X1320055D03*
X1329504Y867665D03*
X1326355Y873964D03*
X1332654Y880263D03*
X1329504D03*
X1332654Y877114D03*
X1326355D03*
X1329504Y870814D03*
X1320055Y873964D03*
X1332654Y870814D03*
X1323204Y873965D03*
X1332654Y867665D03*
X1320055Y880263D03*
Y867665D03*
X1323205Y880263D03*
Y877114D03*
X1320055D03*
X1335803Y867665D03*
Y873964D03*
Y870814D03*
X1332654Y873964D03*
X1329504D03*
X1335802Y896011D03*
X1326355Y886562D03*
X1323205D03*
X1326355Y889712D03*
X1335803Y883413D03*
X1329504Y892862D03*
X1332654Y889712D03*
X1335803Y892862D03*
Y889712D03*
X1326355Y892862D03*
X1329504Y889712D03*
X1320055Y892862D03*
X1323205D03*
X1329504Y886562D03*
X1332654Y883413D03*
X1320055Y886562D03*
X1326355Y883413D03*
X1323205D03*
X1332654Y892862D03*
X1320055Y883413D03*
X1332654Y886562D03*
X1335803D03*
X1320055Y889712D03*
X1323204Y889713D03*
X1329504Y883413D03*
X1332424Y1345691D03*
Y1350683D03*
X1327468D03*
Y1345691D03*
X1320184Y1350683D03*
Y1345691D03*
X1332424Y1362595D03*
Y1357603D03*
X1327468D03*
Y1362595D03*
X1320184D03*
Y1357603D03*
X1332424Y1381801D03*
Y1369889D03*
Y1374881D03*
X1327468Y1381801D03*
Y1369889D03*
Y1374881D03*
X1320184Y1381801D03*
Y1374881D03*
Y1369889D03*
X1332424Y1386793D03*
Y1394087D03*
Y1399079D03*
X1327468Y1386793D03*
Y1394087D03*
Y1399079D03*
X1320184D03*
Y1394087D03*
Y1386793D03*
X1332424Y1410991D03*
Y1405999D03*
X1327468Y1410991D03*
Y1405999D03*
X1320184Y1410991D03*
Y1405999D03*
X1351550Y839320D03*
X1342103Y845619D03*
X1345252Y836170D03*
X1338953Y845619D03*
X1345252Y833021D03*
X1342103Y836170D03*
X1351550D03*
X1342103Y842470D03*
X1345252Y845619D03*
X1342103Y839320D03*
X1338953Y848769D03*
X1338952Y839319D03*
X1345252Y842470D03*
X1342103Y848769D03*
X1338953Y842470D03*
X1345252Y848769D03*
X1338953Y836170D03*
X1351550Y842470D03*
Y848769D03*
Y845619D03*
X1345252Y839320D03*
X1351550Y855068D03*
X1345252D03*
X1342103D03*
Y861367D03*
X1338953D03*
Y858218D03*
X1338952Y855067D03*
X1351550Y858218D03*
X1345252D03*
Y861367D03*
X1342103Y858218D03*
X1351550Y861367D03*
X1338953Y851918D03*
X1342103D03*
X1345252D03*
X1351550D03*
X1338953Y870814D03*
X1342103Y867665D03*
X1338953D03*
X1351550Y873964D03*
X1345252D03*
X1342103D03*
X1338952Y873965D03*
X1338953Y880263D03*
X1351550D03*
X1345252D03*
X1342103Y870814D03*
X1345252D03*
Y867665D03*
X1351550Y870814D03*
Y867665D03*
X1338953Y877114D03*
X1345252D03*
X1351550D03*
X1342103Y880263D03*
X1345252Y892862D03*
X1338953Y883413D03*
X1345252Y889712D03*
Y886562D03*
X1342103Y883413D03*
X1345252D03*
X1338952Y889713D03*
X1338953Y892862D03*
X1342103Y886562D03*
Y892862D03*
Y889712D03*
X1338953Y886562D03*
X1351550Y883413D03*
Y889712D03*
Y886562D03*
Y892862D03*
X1351948Y1350683D03*
Y1345691D03*
X1339708Y1345597D03*
Y1350683D03*
X1344664Y1345597D03*
Y1350683D03*
X1351948Y1357603D03*
Y1362595D03*
X1339708D03*
Y1357603D03*
X1344664Y1362595D03*
Y1357603D03*
X1351948Y1374881D03*
Y1381801D03*
Y1369889D03*
X1339708Y1374881D03*
Y1381801D03*
Y1369889D03*
X1344664D03*
Y1374881D03*
Y1381801D03*
X1351948Y1386793D03*
Y1394087D03*
Y1399079D03*
X1339708D03*
Y1393993D03*
Y1386793D03*
X1344664Y1393993D03*
Y1399079D03*
Y1386793D03*
X1351948Y1410991D03*
Y1405999D03*
X1339708Y1410991D03*
Y1405999D03*
X1344664Y1410991D03*
Y1405999D03*
X1364148Y829871D03*
X1367298D03*
X1359425Y829000D03*
X1364148Y836170D03*
X1354699Y842470D03*
Y848769D03*
X1357849D03*
X1364148Y845619D03*
X1354699Y836170D03*
X1357849Y833021D03*
X1367298Y845619D03*
X1364148Y842470D03*
X1357850Y839319D03*
X1357849Y836170D03*
X1360999Y842470D03*
X1354699Y845619D03*
X1357849D03*
X1360999Y839320D03*
X1367298Y842470D03*
X1360999Y848769D03*
Y845619D03*
X1367298Y833021D03*
X1354699Y839320D03*
X1360999Y836170D03*
X1367298Y848769D03*
X1364148Y839320D03*
X1357849Y842470D03*
X1364148Y833021D03*
X1367298Y836170D03*
Y839320D03*
X1364148Y848769D03*
X1354699Y855068D03*
X1357849Y861367D03*
X1354699D03*
X1357849Y858218D03*
X1357850Y855067D03*
X1360999Y851918D03*
X1364148D03*
X1367298Y861367D03*
X1364148Y858218D03*
Y855068D03*
Y861367D03*
X1367298Y858218D03*
Y851918D03*
X1354699Y858218D03*
X1367298Y855068D03*
X1360999D03*
Y858218D03*
Y861367D03*
X1354699Y851918D03*
X1357849D03*
X1360999Y877114D03*
X1357850Y873965D03*
X1354699Y873964D03*
X1357849Y870814D03*
Y867665D03*
X1354699D03*
X1364148D03*
X1367298Y877114D03*
X1364148Y870814D03*
X1367298Y873964D03*
X1364148D03*
Y877114D03*
X1367298Y870814D03*
X1364148Y880263D03*
X1367298D03*
X1357849D03*
X1360999D03*
X1367298Y867665D03*
X1354699Y870814D03*
X1357849Y877114D03*
X1354699Y880263D03*
X1360999Y867665D03*
Y870814D03*
Y873964D03*
X1364148Y896011D03*
X1367298Y883413D03*
X1354699Y892862D03*
X1360999D03*
X1367298D03*
X1360999Y883413D03*
X1357850Y889713D03*
X1364148Y889712D03*
X1357849Y883413D03*
X1367298Y889712D03*
X1354699D03*
X1357849Y886562D03*
X1364148D03*
X1357849Y892862D03*
X1360999Y889712D03*
X1354699Y883413D03*
X1360999Y886562D03*
X1364148Y892862D03*
Y883413D03*
X1367298Y886562D03*
X1354699D03*
X1356904Y1345691D03*
Y1350683D03*
Y1357603D03*
Y1362595D03*
Y1381801D03*
Y1369889D03*
Y1374881D03*
Y1386793D03*
Y1394087D03*
Y1399079D03*
Y1410991D03*
Y1405999D03*
X1383046Y829871D03*
X1370447D03*
X1379896Y842470D03*
X1370447Y839320D03*
X1383046Y845619D03*
X1379896D03*
X1373597D03*
Y842470D03*
X1370447Y848769D03*
X1379896D03*
Y839320D03*
X1373597Y848769D03*
X1376747D03*
X1373597Y833021D03*
X1370447D03*
X1373597Y836170D03*
X1370447D03*
X1373598Y839319D03*
X1370447Y842470D03*
Y845619D03*
X1383046Y842470D03*
X1376747Y836170D03*
Y842470D03*
X1379896Y833021D03*
X1383046Y839320D03*
X1376747Y845619D03*
Y839320D03*
X1379896Y858218D03*
Y855068D03*
Y861367D03*
X1376747Y858218D03*
Y851918D03*
X1373597Y861367D03*
X1376747Y855068D03*
X1373597Y858218D03*
X1376747Y861367D03*
X1383046Y851918D03*
X1373597D03*
X1373598Y855067D03*
X1379896Y851918D03*
X1370447D03*
Y858218D03*
X1383046D03*
Y861367D03*
X1370447Y855068D03*
Y861367D03*
Y867665D03*
X1379896Y870814D03*
X1383046Y873964D03*
X1376747Y880263D03*
X1370447Y877114D03*
X1373598Y873965D03*
X1370447Y873964D03*
X1379896Y877114D03*
X1373597Y880263D03*
X1383046Y877114D03*
X1370447Y880263D03*
X1376747Y873964D03*
X1383046Y880263D03*
X1370447Y870814D03*
X1376747D03*
X1373597D03*
X1376747Y867665D03*
Y877114D03*
X1373597Y867665D03*
X1379896D03*
X1383046Y870814D03*
X1379896Y880263D03*
X1373597Y877114D03*
X1379896Y873964D03*
X1370447Y886562D03*
X1379896Y883413D03*
X1383046Y892862D03*
X1379896Y886562D03*
X1370447Y883413D03*
X1373598Y889713D03*
X1376747Y886562D03*
X1383046Y883413D03*
X1376747Y889712D03*
X1383046D03*
X1379896D03*
X1373597Y883413D03*
Y886562D03*
X1370447Y892862D03*
X1376747D03*
X1370447Y889712D03*
X1373597Y892862D03*
X1383046Y886562D03*
X1379896Y892862D03*
X1376747Y883413D03*
X1383046Y899161D03*
X1460592Y1345691D03*
Y1350683D03*
X1465548Y1345691D03*
Y1350683D03*
X1460592Y1357603D03*
Y1362595D03*
X1465548Y1357603D03*
Y1362595D03*
X1460592Y1381801D03*
Y1374881D03*
Y1369889D03*
X1465548Y1381801D03*
Y1374881D03*
Y1369889D03*
X1460592Y1386793D03*
X1465548D03*
X1477788Y1350683D03*
Y1345691D03*
X1472832Y1350683D03*
Y1345691D03*
X1477788Y1357603D03*
Y1362595D03*
X1472832Y1357603D03*
Y1362595D03*
X1477788Y1381801D03*
Y1369795D03*
Y1374881D03*
X1472832Y1381801D03*
Y1369795D03*
Y1374881D03*
X1477788Y1386793D03*
Y1399079D03*
Y1393993D03*
X1472832Y1386793D03*
Y1393993D03*
Y1399079D03*
X1477788Y1405999D03*
Y1410991D03*
X1472832Y1405999D03*
Y1410991D03*
X1497312Y1350683D03*
Y1345691D03*
X1485072D03*
Y1350683D03*
X1490028Y1345691D03*
Y1350683D03*
X1497312Y1357603D03*
Y1362595D03*
X1485072D03*
Y1357603D03*
X1490028D03*
Y1362595D03*
X1485072Y1369889D03*
Y1374881D03*
Y1381801D03*
X1490028Y1369889D03*
Y1374881D03*
Y1381801D03*
X1497312D03*
Y1374881D03*
Y1369889D03*
Y1386793D03*
Y1394087D03*
Y1399079D03*
X1485072Y1394087D03*
Y1399079D03*
Y1386793D03*
X1490028Y1399079D03*
Y1394087D03*
Y1386793D03*
X1497312Y1405999D03*
Y1410991D03*
X1485072Y1405999D03*
Y1410991D03*
X1490028Y1405999D03*
Y1410991D03*
X1509552Y1350683D03*
Y1345691D03*
X1514508Y1350683D03*
Y1345691D03*
X1502268Y1350683D03*
Y1345691D03*
X1509552Y1362595D03*
Y1357603D03*
X1514508D03*
Y1362595D03*
X1502268Y1357603D03*
Y1362595D03*
X1509552Y1374881D03*
Y1369889D03*
Y1381801D03*
X1514508Y1374881D03*
Y1369889D03*
Y1381801D03*
X1502268D03*
Y1374881D03*
Y1369889D03*
X1509552Y1394087D03*
Y1399079D03*
Y1386793D03*
X1514508Y1394087D03*
Y1399079D03*
Y1386793D03*
X1502268D03*
Y1399079D03*
Y1394087D03*
X1509552Y1405999D03*
Y1410991D03*
X1514508Y1405999D03*
Y1410991D03*
X1502268Y1405999D03*
Y1410991D03*
X1526748Y1345691D03*
Y1350683D03*
X1521792Y1345691D03*
Y1350683D03*
X1526748Y1357603D03*
Y1362595D03*
X1521792Y1357603D03*
Y1362595D03*
X1526748Y1369889D03*
Y1374881D03*
Y1381801D03*
X1521792Y1374881D03*
Y1381801D03*
Y1369889D03*
X1526748Y1386793D03*
Y1399079D03*
Y1394087D03*
X1521792Y1386793D03*
Y1394087D03*
Y1399079D03*
X1526748Y1405999D03*
Y1410991D03*
X1521792Y1405999D03*
Y1410991D03*
X1546272Y1350683D03*
Y1345691D03*
X1534032Y1350683D03*
Y1345691D03*
X1538988D03*
Y1350683D03*
X1546272Y1357603D03*
Y1362595D03*
X1534032Y1357603D03*
Y1362595D03*
X1538988D03*
Y1357603D03*
X1546272Y1374881D03*
Y1369889D03*
Y1381801D03*
X1534032Y1369889D03*
Y1381801D03*
Y1374881D03*
X1538988Y1369889D03*
Y1381801D03*
Y1374881D03*
X1546272Y1386793D03*
Y1394087D03*
Y1399079D03*
X1534032Y1394087D03*
Y1399079D03*
Y1386793D03*
X1538988Y1394087D03*
Y1399079D03*
Y1386793D03*
X1546272Y1405999D03*
Y1410991D03*
X1534032Y1405999D03*
Y1410991D03*
X1538988Y1405999D03*
Y1410991D03*
X1558512Y1345691D03*
Y1350683D03*
X1563468D03*
Y1345691D03*
X1551228Y1350683D03*
Y1345691D03*
X1563468Y1362595D03*
X1551228Y1357603D03*
Y1362595D03*
X1558512D03*
Y1357603D03*
X1563468D03*
X1558512Y1374881D03*
Y1369889D03*
Y1381801D03*
X1563468Y1374881D03*
Y1369889D03*
Y1381801D03*
X1551228Y1369889D03*
Y1381801D03*
Y1374881D03*
X1558512Y1399079D03*
Y1394087D03*
Y1386793D03*
X1563468Y1399079D03*
Y1394087D03*
Y1386793D03*
X1551228D03*
Y1394087D03*
Y1399079D03*
X1558512Y1405999D03*
Y1410991D03*
X1563468Y1405999D03*
Y1410991D03*
X1551228Y1405999D03*
Y1410991D03*
X1575708Y1345597D03*
X1570752Y1350683D03*
Y1345597D03*
X1575708Y1350683D03*
X1570752Y1357603D03*
Y1362595D03*
X1575708D03*
Y1357603D03*
Y1381801D03*
Y1374881D03*
Y1369889D03*
X1570752D03*
Y1381801D03*
Y1374881D03*
X1575708Y1386793D03*
Y1399079D03*
Y1393993D03*
X1570752Y1386793D03*
Y1393993D03*
Y1399079D03*
X1575708Y1405999D03*
Y1410991D03*
X1570752Y1405999D03*
Y1410991D03*
X1587948Y1350683D03*
Y1345691D03*
X1582992D03*
Y1350683D03*
X1587948Y1362595D03*
Y1357603D03*
X1582992Y1362595D03*
Y1357603D03*
Y1369889D03*
Y1381801D03*
Y1374881D03*
X1587948Y1369889D03*
Y1381801D03*
Y1374881D03*
X1582992Y1399079D03*
Y1394087D03*
Y1386793D03*
X1587948Y1399079D03*
Y1394087D03*
Y1386793D03*
X1582992Y1405999D03*
Y1410991D03*
X1587948Y1405999D03*
Y1410991D03*
X1610620Y1345691D03*
Y1350683D03*
Y1357603D03*
Y1362595D03*
Y1381801D03*
Y1374881D03*
Y1369889D03*
Y1386793D03*
X1615576Y1345691D03*
Y1350683D03*
X1622860D03*
Y1345691D03*
X1627816Y1350683D03*
Y1345691D03*
X1615576Y1357603D03*
Y1362595D03*
X1622860Y1357603D03*
Y1362595D03*
X1627816Y1357603D03*
Y1362595D03*
X1622860Y1381801D03*
Y1369795D03*
Y1374881D03*
X1627816Y1381801D03*
Y1369795D03*
Y1374881D03*
X1615576Y1381801D03*
Y1374881D03*
Y1369889D03*
Y1386793D03*
X1622860D03*
Y1393993D03*
Y1399079D03*
X1627816Y1386793D03*
Y1399079D03*
Y1393993D03*
X1622860Y1405999D03*
Y1410991D03*
X1627816Y1405999D03*
Y1410991D03*
X1640056Y1345691D03*
Y1350683D03*
X1635100Y1345691D03*
Y1350683D03*
X1640056Y1357603D03*
Y1362595D03*
X1635100D03*
Y1357603D03*
X1640056Y1369889D03*
Y1374881D03*
Y1381801D03*
X1635100Y1369889D03*
Y1374881D03*
Y1381801D03*
X1640056Y1399079D03*
Y1394087D03*
Y1386793D03*
X1635100Y1394087D03*
Y1399079D03*
Y1386793D03*
Y1405999D03*
Y1410991D03*
X1640056Y1405999D03*
Y1410991D03*
X1647340Y1350683D03*
Y1345691D03*
X1652296Y1350683D03*
Y1345691D03*
X1659580Y1350683D03*
Y1345691D03*
X1647340Y1357603D03*
Y1362595D03*
X1652296Y1357603D03*
Y1362595D03*
X1659580D03*
Y1357603D03*
X1647340Y1381801D03*
Y1374881D03*
Y1369889D03*
X1652296Y1381801D03*
Y1374881D03*
Y1369889D03*
X1659580Y1374881D03*
Y1369889D03*
Y1381801D03*
X1647340Y1386793D03*
Y1394087D03*
Y1399079D03*
X1652296Y1386793D03*
Y1399079D03*
Y1394087D03*
X1659580D03*
Y1399079D03*
Y1386793D03*
X1647340Y1405999D03*
Y1410991D03*
X1652296Y1405999D03*
Y1410991D03*
X1659580Y1405999D03*
Y1410991D03*
X1664536Y1350683D03*
Y1345691D03*
X1671820D03*
Y1350683D03*
X1676776Y1345691D03*
Y1350683D03*
X1664536Y1357603D03*
Y1362595D03*
X1671820Y1357603D03*
Y1362595D03*
X1676776Y1357603D03*
Y1362595D03*
X1664536Y1374881D03*
Y1369889D03*
Y1381801D03*
X1671820Y1374881D03*
Y1381801D03*
Y1369889D03*
X1676776D03*
Y1374881D03*
Y1381801D03*
X1664536Y1394087D03*
Y1399079D03*
Y1386793D03*
X1671820D03*
Y1394087D03*
Y1399079D03*
X1676776Y1386793D03*
Y1399079D03*
Y1394087D03*
X1664536Y1405999D03*
Y1410991D03*
X1671820Y1405999D03*
Y1410991D03*
X1676776Y1405999D03*
Y1410991D03*
X1689016Y1345691D03*
Y1350683D03*
X1684060D03*
Y1345691D03*
X1689016Y1362595D03*
Y1357603D03*
X1684060D03*
Y1362595D03*
X1689016Y1369889D03*
Y1381801D03*
Y1374881D03*
X1684060Y1369889D03*
Y1381801D03*
Y1374881D03*
X1689016Y1394087D03*
Y1399079D03*
Y1386793D03*
X1684060Y1394087D03*
Y1399079D03*
Y1386793D03*
X1689016Y1405999D03*
Y1410991D03*
X1684060Y1405999D03*
Y1410991D03*
X1696300Y1350683D03*
Y1345691D03*
X1701256Y1350683D03*
Y1345691D03*
X1708540D03*
Y1350683D03*
X1696300Y1357603D03*
Y1362595D03*
X1701256Y1357603D03*
Y1362595D03*
X1708540D03*
Y1357603D03*
X1696300Y1374881D03*
Y1369889D03*
Y1381801D03*
X1701256Y1369889D03*
Y1381801D03*
Y1374881D03*
X1708540D03*
Y1369889D03*
Y1381801D03*
X1696300Y1386793D03*
Y1394087D03*
Y1399079D03*
X1701256Y1386793D03*
Y1394087D03*
Y1399079D03*
X1708540D03*
Y1394087D03*
Y1386793D03*
X1696300Y1405999D03*
Y1410991D03*
X1701256Y1405999D03*
Y1410991D03*
X1708540Y1405999D03*
Y1410991D03*
X1713496Y1350683D03*
Y1345691D03*
X1720780Y1350683D03*
Y1345597D03*
X1725736Y1350683D03*
Y1345597D03*
X1713496Y1357603D03*
Y1362595D03*
X1720780Y1357603D03*
Y1362595D03*
X1725736Y1357603D03*
Y1362595D03*
X1713496Y1374881D03*
Y1369889D03*
Y1381801D03*
X1720780Y1369889D03*
Y1381801D03*
Y1374881D03*
X1725736Y1381801D03*
Y1374881D03*
Y1369889D03*
X1713496Y1399079D03*
Y1394087D03*
Y1386793D03*
X1720780D03*
Y1393993D03*
Y1399079D03*
X1725736Y1386793D03*
Y1399079D03*
Y1393993D03*
X1713496Y1405999D03*
Y1410991D03*
X1720780Y1405999D03*
Y1410991D03*
X1725736Y1405999D03*
Y1410991D03*
X1737976Y1350683D03*
Y1345691D03*
X1733020D03*
Y1350683D03*
X1737976Y1362595D03*
Y1357603D03*
X1733020Y1362595D03*
Y1357603D03*
X1737976Y1369889D03*
Y1374881D03*
X1733020Y1369889D03*
Y1381801D03*
Y1374881D03*
X1737976Y1381801D03*
Y1399079D03*
Y1394087D03*
Y1386793D03*
X1733020Y1399079D03*
Y1394087D03*
Y1386793D03*
X1737976Y1405999D03*
Y1410991D03*
X1733020Y1405999D03*
Y1410991D03*
G54D13*
X11011Y79720D03*
X10292Y94236D03*
X12786Y87903D03*
X10131Y115473D03*
X19855Y133000D03*
X15948Y141267D03*
X16909Y153263D03*
X12247Y166341D03*
X17313Y166937D03*
X21909Y153263D03*
X22335Y166721D03*
X18320Y195176D03*
X15139Y201683D03*
X22599Y228646D03*
X18206Y244571D03*
X15586Y249108D03*
X18206Y264571D03*
X8335Y280663D03*
X14807Y282181D03*
X15586Y269108D03*
X15499Y288542D03*
X14197Y1014205D03*
X20346Y1069466D03*
X21200Y1091800D03*
X12599Y1438143D03*
X16304Y1468196D03*
X15889Y1494254D03*
X10089D03*
X26588Y97667D03*
X35442D03*
X35048Y103411D03*
X26565Y177448D03*
X32507Y180517D03*
X32585Y199248D03*
X27340Y230556D03*
X36185Y230117D03*
X31595Y227824D03*
X25549Y256394D03*
X29116Y281129D03*
X37117Y279991D03*
X25549Y276394D03*
X34359Y541135D03*
X34732Y534909D03*
X34425Y546553D03*
X34448Y552726D03*
X36494Y616905D03*
X36306Y622285D03*
X27686Y625311D03*
X36692Y633724D03*
X36575Y627713D03*
X28818Y682139D03*
X30479Y1006509D03*
X36024Y1069703D03*
X31631Y1198651D03*
X29880Y1441702D03*
X25674Y1486291D03*
X45988Y90512D03*
X51026Y242913D03*
X48596Y451419D03*
X49643Y464419D03*
X41643Y464919D03*
X43948Y492108D03*
X44563Y482165D03*
X43804Y500202D03*
X45256Y495993D03*
X40362Y610548D03*
X54192Y633473D03*
X42172Y633716D03*
X49192Y628078D03*
X47179Y633736D03*
X42192Y641817D03*
X47949Y822718D03*
X53549Y843118D03*
X52077Y905295D03*
X42470Y1006738D03*
X47314Y1072228D03*
X41172Y1079064D03*
X55188Y1205179D03*
X51023Y1201416D03*
X48842Y1211109D03*
X53479Y1216256D03*
X39452Y1250932D03*
X64829Y92874D03*
X55871Y99961D03*
X70656Y117775D03*
X69607Y135361D03*
X66780Y169454D03*
X59280D03*
X65189Y223661D03*
X65737Y445603D03*
X57857Y446071D03*
X67670Y464818D03*
X58224Y465004D03*
X63154Y462371D03*
X61330Y544895D03*
X63859Y590801D03*
X63684Y597130D03*
X67684Y605637D03*
X66510Y628242D03*
X58181Y627908D03*
X68598Y859415D03*
X59104Y880162D03*
X63969Y869475D03*
X63930Y874694D03*
X63745Y887763D03*
X71528Y913190D03*
X59962Y910251D03*
X55699Y1072761D03*
X61588Y1074481D03*
X62109Y1084656D03*
Y1079656D03*
Y1091656D03*
X60269Y1198820D03*
X63094Y1207604D03*
X55596Y1210466D03*
X65478Y1541980D03*
X64747Y1555890D03*
X69816Y1592527D03*
X60554Y1612002D03*
X66291Y1633801D03*
X82661Y143740D03*
X80041Y148277D03*
X83272Y157842D03*
X80502Y177616D03*
X81083Y172190D03*
X74939Y188727D03*
X72061Y208695D03*
X71696Y226141D03*
X75438Y265701D03*
X85541Y266114D03*
X80525Y265896D03*
X83014Y281982D03*
X77073Y281716D03*
X83819Y290755D03*
X85812Y558161D03*
X78133Y566597D03*
X87243Y564892D03*
X78733Y578405D03*
X84159Y578986D03*
X83684Y596729D03*
X72515Y596089D03*
X77734Y596782D03*
X78129Y656900D03*
X82648Y670679D03*
X73914Y660107D03*
X84845Y659857D03*
X82562Y680037D03*
X78735Y683426D03*
X74700Y842890D03*
X86061Y874859D03*
X80593Y946082D03*
X87632Y1007522D03*
X87000Y1597855D03*
X74909Y1593009D03*
X71910Y1625009D03*
X78291Y1625743D03*
X83689Y1624736D03*
X91224Y141247D03*
X95711Y143518D03*
X94811Y152373D03*
X103456Y157370D03*
X98826Y172665D03*
X98763Y178560D03*
X98653Y183834D03*
X98943Y200864D03*
X92898Y192490D03*
X98173Y190185D03*
X98966Y207037D03*
X99032Y212455D03*
X88098Y231021D03*
X103841Y228631D03*
X89900Y281307D03*
X95943Y377953D03*
X88875Y840940D03*
X90000Y871389D03*
X103770Y868206D03*
X91278Y892822D03*
X96395Y905405D03*
X103692Y900295D03*
X91387Y905295D03*
X103836Y988813D03*
X95836D03*
X94398Y1006648D03*
X91765Y1018307D03*
X88007Y1013678D03*
X88479Y1023731D03*
X100594Y1035088D03*
X103124Y1165091D03*
X119582Y102249D03*
X118307Y110784D03*
X113307D03*
X117886Y124663D03*
X112864Y124879D03*
X107798Y124283D03*
X119230Y138838D03*
X107540Y192665D03*
X117501Y201683D03*
X107572Y208864D03*
X117948Y249108D03*
X117539Y547918D03*
X120250Y758841D03*
X109591Y796905D03*
X110887Y884000D03*
X111836Y988813D03*
X119836D03*
X110409Y1024094D03*
X108971Y1109564D03*
Y1147364D03*
X109415Y1202103D03*
X118533Y1207737D03*
X112048Y1214372D03*
X107803Y1218169D03*
X128950Y97667D03*
X122867Y125107D03*
X131481Y143762D03*
X125381Y148717D03*
X120682Y195176D03*
X134947Y199248D03*
X129702Y230556D03*
X133957Y227824D03*
X120568Y244571D03*
X127911Y256394D03*
X126131Y359511D03*
X125753Y365856D03*
X122437Y860775D03*
X123387Y892000D03*
X135836Y988813D03*
X127836D03*
X124079Y1021954D03*
X120617Y1029427D03*
X124925Y1102091D03*
X130380Y1105091D03*
X124925Y1114691D03*
Y1127291D03*
X130380Y1117691D03*
X124925Y1139891D03*
X130380Y1130291D03*
X130434Y1144964D03*
X130380Y1155491D03*
X124925Y1152491D03*
X130434Y1170164D03*
X124925Y1165091D03*
Y1177691D03*
X131000Y1180266D03*
X136104Y1214835D03*
X135757Y1221407D03*
X135448Y1229402D03*
Y1234921D03*
X126433Y1230407D03*
X137410Y103411D03*
X137804Y97667D03*
X148600Y90650D03*
X138547Y230117D03*
X148061Y378600D03*
X140431Y546805D03*
X147925Y615600D03*
X149469Y634190D03*
X152658Y645389D03*
X136862Y857244D03*
X151836Y988813D03*
X143836D03*
X142026Y1012354D03*
X136571Y1009354D03*
Y1021954D03*
X142026Y1024954D03*
X144640Y1039439D03*
X150952Y1040115D03*
X139862Y1224472D03*
X167191Y92874D03*
X153912Y90615D03*
X161642Y169454D03*
X167551Y223661D03*
X164496Y309405D03*
X161715Y546062D03*
X159836Y988813D03*
X155836Y997860D03*
X153693Y1051037D03*
X156299Y1143390D03*
X165649Y1159350D03*
Y1151870D03*
X167507Y1146271D03*
X168986Y1170092D03*
X167519Y1164960D03*
X170278Y120467D03*
X185023Y143740D03*
X182403Y148277D03*
X171402Y156497D03*
X169142Y169454D03*
X182864Y177616D03*
X183445Y172190D03*
X177301Y188727D03*
X174423Y208695D03*
X174058Y226141D03*
X177800Y265701D03*
X182887Y265896D03*
X179435Y281716D03*
X178689Y1135036D03*
X169389Y1155610D03*
X182478Y1194917D03*
X193007Y100625D03*
X186026Y97475D03*
X193586Y141247D03*
X198073Y143518D03*
X197173Y152373D03*
X201015Y183834D03*
X201125Y178560D03*
X201188Y172665D03*
X195260Y192490D03*
X200535Y190185D03*
X201305Y200864D03*
X201394Y212455D03*
X201328Y207037D03*
X187903Y266114D03*
X192262Y281307D03*
X185376Y281982D03*
X186181Y290755D03*
X185328Y545528D03*
X198940Y551040D03*
X186184Y1135040D03*
X193700Y1217322D03*
X205848Y60513D03*
X214389Y86012D03*
X210482Y94279D03*
X215669Y110784D03*
X210160Y124283D03*
X215226Y124879D03*
X209902Y196665D03*
X209934Y208864D03*
X214983Y218085D03*
X206203Y228631D03*
X204675Y382109D03*
X215500Y544000D03*
X204674Y551683D03*
X208500Y595500D03*
X203500Y606929D03*
X208000Y604567D03*
X203460Y618400D03*
X203741Y612592D03*
X209158Y610072D03*
X209094Y616317D03*
X212401Y1209842D03*
X216141Y1213582D03*
X204921Y1217322D03*
X212401D03*
X221944Y102249D03*
X231312Y97667D03*
X220669Y110784D03*
X225229Y125107D03*
X220248Y124663D03*
X227743Y148717D03*
X221592Y138838D03*
X223044Y195176D03*
X219863Y201683D03*
X232064Y230556D03*
X227323Y228646D03*
X220310Y249108D03*
X222930Y244571D03*
X233417Y253198D03*
X233258Y359186D03*
X228267Y404718D03*
Y412718D03*
X223500Y568000D03*
X221693Y594982D03*
X220333Y617930D03*
X218458Y608776D03*
X225825Y635684D03*
X232998Y1058763D03*
X230321Y1050045D03*
X224169Y1055975D03*
X225001Y1062847D03*
X224780Y1478149D03*
X217985Y1483055D03*
X225765Y1471985D03*
X233313Y1476699D03*
X221899Y1488800D03*
X218021Y1494724D03*
X222843Y1498442D03*
X233180Y1486442D03*
X233166Y1491454D03*
X226135Y1502442D03*
X230758Y1505046D03*
X226971Y1514578D03*
X227552Y1530675D03*
X232622Y1531104D03*
X226971Y1522578D03*
X219981Y1530797D03*
X223322Y1518578D03*
X222119Y1539941D03*
X227882Y1540816D03*
X233753Y1539752D03*
X239772Y103411D03*
X240166Y97667D03*
X237309Y199248D03*
X240909Y230117D03*
X236319Y227824D03*
X234986Y336161D03*
X236264Y342494D03*
X242396Y499906D03*
X245362Y546712D03*
X246695Y626359D03*
X250102Y656321D03*
X235790Y754332D03*
X248556Y824003D03*
X246311Y819000D03*
X238400Y836900D03*
X250165Y1055787D03*
X240597Y1053324D03*
X234976Y1481676D03*
X243535Y1511473D03*
X245500Y1517033D03*
X237633Y1511909D03*
X244600Y1531700D03*
X240808Y1519942D03*
X235687Y1522578D03*
X237580Y1528604D03*
X245937Y1524237D03*
X239949Y1541327D03*
X244912Y1539389D03*
X250962Y90650D03*
X256274Y90615D03*
X260595Y99961D03*
X264004Y169454D03*
X265011Y403307D03*
X260111Y443585D03*
X252695Y442956D03*
X257999Y433003D03*
X261965Y458455D03*
X262526Y451108D03*
X252542Y507084D03*
X252688Y636364D03*
X256303Y812254D03*
X255289Y824340D03*
X252305Y831018D03*
X265733Y1064608D03*
X250876Y1532782D03*
X255909Y1542043D03*
X250790Y1539759D03*
X275615Y75385D03*
X269553Y92874D03*
X274613Y132920D03*
X271504Y169454D03*
X279663Y188727D03*
X276785Y208695D03*
X276420Y226141D03*
X269913Y223661D03*
X280162Y265701D03*
X281797Y281716D03*
X277575Y395084D03*
X278784Y435158D03*
X278529Y440489D03*
X282230Y458572D03*
X275123Y847874D03*
X279945Y859855D03*
X275400Y894200D03*
X281800Y929400D03*
X290113Y23188D03*
X289631Y28281D03*
X295369Y100625D03*
X288388Y97475D03*
X287385Y143740D03*
X284765Y148277D03*
X285807Y172190D03*
X285226Y177616D03*
X297622Y192490D03*
X290265Y266114D03*
X285249Y265896D03*
X294624Y281307D03*
X287738Y281982D03*
X288543Y290755D03*
X297719Y339559D03*
X291396Y350223D03*
X288500Y388000D03*
X292358Y393858D03*
X298000Y391496D03*
X295699Y382047D03*
X296000Y403500D03*
X298000Y409000D03*
X294000Y398583D03*
X286100Y1128100D03*
X290944Y1142519D03*
X287204Y1149999D03*
X296450Y1178467D03*
X296012Y1185514D03*
X307916Y60529D03*
X312844Y94279D03*
X312522Y124283D03*
X300435Y143518D03*
X299535Y152373D03*
X303377Y183834D03*
X303550Y172665D03*
X303487Y178560D03*
X302897Y190185D03*
X303667Y200864D03*
X312296Y208864D03*
X303756Y212455D03*
X303690Y207037D03*
X308565Y228631D03*
X315079Y314890D03*
X312263Y324518D03*
X299000Y377912D03*
Y386500D03*
X299088Y397912D03*
X309645Y1142519D03*
X308588Y1263349D03*
X322847Y19806D03*
X321840Y14408D03*
X322113Y26187D03*
X316751Y86012D03*
X324306Y102249D03*
X318031Y110784D03*
X323031D03*
X327591Y125107D03*
X322610Y124663D03*
X317588Y124879D03*
X330105Y148717D03*
X323954Y138838D03*
X325406Y195176D03*
X322225Y201683D03*
X329685Y228646D03*
X322672Y249108D03*
X325292Y244571D03*
X318508Y324322D03*
X315944Y332584D03*
X316067Y347937D03*
X321416Y348015D03*
X318500Y356519D03*
X327456Y550065D03*
X331240Y1221062D03*
X331015Y1232283D03*
X320624Y1284448D03*
X325683Y1287953D03*
X333674Y97667D03*
X342134Y103411D03*
X342528Y97667D03*
X336205Y143762D03*
X339671Y199248D03*
X343271Y230117D03*
X338681Y227824D03*
X334426Y230556D03*
X340988Y244297D03*
X332635Y256394D03*
X347058Y399918D03*
X346645Y418996D03*
X346390Y431730D03*
X344500Y746300D03*
X333985Y1017945D03*
X341077Y1018056D03*
X340500Y1147500D03*
X335190Y1173065D03*
X342009Y1176100D03*
X339776Y1187962D03*
X344657Y1195059D03*
X333500Y1202200D03*
X344064Y1203115D03*
X345307Y1221197D03*
X334899Y1224512D03*
X343175Y1237535D03*
X337884Y1233951D03*
X358636Y90615D03*
X353324Y90650D03*
X362957Y99961D03*
X359486Y385123D03*
X349311Y385644D03*
X354486Y385123D03*
X353894Y406060D03*
X353320Y454214D03*
X353663Y449045D03*
X353367Y459330D03*
X358754Y462060D03*
X363100Y750000D03*
X358696Y775504D03*
X358207Y836462D03*
X352545Y1142666D03*
X360877Y1157404D03*
X354420Y1157544D03*
X352931Y1167768D03*
X357950D03*
X357083Y1185205D03*
X361792Y1187310D03*
X348432Y1187215D03*
X348125Y1180175D03*
X359197Y1197626D03*
X360659Y1209789D03*
X362332Y1230265D03*
X355318Y1228760D03*
X359287Y1633665D03*
X353242Y1634202D03*
X379613Y75385D03*
X371915Y92874D03*
X373866Y169454D03*
X366366D03*
X379147Y208695D03*
X372275Y223661D03*
X378782Y226141D03*
X373264Y379429D03*
X378875Y379088D03*
X370486Y373903D03*
X366486Y385123D03*
X370160Y391569D03*
X368587Y409016D03*
X378927Y406739D03*
X367564Y456034D03*
Y461034D03*
X373703Y782555D03*
X365691Y815127D03*
X371507Y815303D03*
X370214Y943812D03*
X379928Y949774D03*
X379245Y956643D03*
X378875Y961862D03*
X378928Y967812D03*
X366429Y1185238D03*
X366222Y1180235D03*
X387948Y27288D03*
X390750Y97475D03*
X385679Y147729D03*
X387588Y177616D03*
X388169Y172190D03*
X382025Y188727D03*
X387611Y265896D03*
X382524Y265701D03*
X392627Y266114D03*
X384159Y281716D03*
X390100Y281982D03*
X390905Y290755D03*
X384173Y379028D03*
X381237Y371076D03*
X394237Y379591D03*
X396373Y407104D03*
X393893Y413611D03*
X393833Y423944D03*
X393646Y474382D03*
X385634Y472020D03*
X385694Y477318D03*
X385293Y466409D03*
X385131Y487382D03*
X381875Y740341D03*
X380331Y782627D03*
X392584Y875845D03*
X384856Y947987D03*
X383710Y1007283D03*
X382465Y1012430D03*
X392234Y1369579D03*
Y1364501D03*
X389466Y1497520D03*
X383259Y1487792D03*
X382896Y1494984D03*
X390449Y1491362D03*
X391740Y1545629D03*
Y1540529D03*
X395296Y1561024D03*
X391740Y1550729D03*
Y1555829D03*
X410789Y22627D03*
X397731Y100625D03*
X405912Y172665D03*
X405739Y183834D03*
X405849Y178560D03*
X399984Y192490D03*
X405259Y190185D03*
X406029Y200864D03*
X406118Y212455D03*
X406052Y207037D03*
X410927Y228631D03*
X396986Y281307D03*
X410086Y336795D03*
X409655Y331589D03*
X410688Y344736D03*
X409994Y351045D03*
X411007Y356743D03*
X405801Y475560D03*
X405301Y467560D03*
X404468Y864407D03*
X406770Y869767D03*
X405466Y881299D03*
X397431Y870654D03*
X401108Y878487D03*
X405179Y959051D03*
X397252Y962861D03*
X396671Y968287D03*
X401063Y1233428D03*
X405063Y1225428D03*
X409063Y1233428D03*
X404324Y1271889D03*
X403798Y1305859D03*
X412663Y1321462D03*
X398456Y1330464D03*
X405294Y1367752D03*
X408773Y1399659D03*
X399373Y1555855D03*
X410034Y1555416D03*
X405496Y1561024D03*
X400396D03*
X410596D03*
X422450Y30483D03*
X414145Y27486D03*
X413904Y32569D03*
X414739Y186778D03*
X414658Y208864D03*
X422988Y323627D03*
X426457Y317115D03*
X426830Y359026D03*
X418435Y351552D03*
X416574Y357528D03*
X421413Y359053D03*
X426647Y452987D03*
X421267Y452799D03*
X414910Y448931D03*
X418801Y474513D03*
X424731Y508152D03*
X427693Y498943D03*
X424993Y728291D03*
X422430Y834800D03*
X425062Y883981D03*
X419987Y1098518D03*
X423340Y1104335D03*
X417063Y1225428D03*
X425063Y1237428D03*
X420830Y1273658D03*
X420922Y1320604D03*
X417305Y1355108D03*
X422875Y1362304D03*
X428084Y1378718D03*
X424376Y1390794D03*
X415421Y1532278D03*
X421454Y1544625D03*
X422539Y1534361D03*
X426701Y1541947D03*
X437386Y143740D03*
X434766Y148277D03*
X436666Y322583D03*
X434927Y317228D03*
X443424Y332988D03*
X440538Y355372D03*
X438098Y442114D03*
X437835Y435101D03*
X432270Y431112D03*
X432440Y440101D03*
X432075Y452718D03*
X438086Y452601D03*
X438078Y447121D03*
X438396Y511493D03*
X443144Y628667D03*
X441162Y638313D03*
X443091Y1026266D03*
X429063Y1225428D03*
X441220Y1271776D03*
X436191Y1271753D03*
X437644Y1296834D03*
X432644D03*
X435705Y1302380D03*
X441153Y1319961D03*
X438549Y1329943D03*
X433318Y1357671D03*
X431127Y1365203D03*
X450436Y143518D03*
X449536Y152373D03*
X446566Y337917D03*
X450852Y372054D03*
X459414Y468689D03*
X459757Y463520D03*
X459461Y473805D03*
X459929Y491669D03*
X460537Y501905D03*
X459952Y496842D03*
X459645Y509486D03*
X447279Y637031D03*
X447921Y630789D03*
X453552Y631779D03*
X460498Y870334D03*
X459360Y996755D03*
Y1012325D03*
X459885Y1018860D03*
X451140Y1021793D03*
X450875Y1028416D03*
X455591Y1015825D03*
X452091Y1039880D03*
X459700Y1032266D03*
X452115Y1098518D03*
X455468Y1104335D03*
X457510Y1224106D03*
X459560Y1239245D03*
X460567Y1230219D03*
X456472Y1271860D03*
X451377Y1271840D03*
X446246Y1271785D03*
X448349Y1314391D03*
X474307Y102249D03*
X474058Y116594D03*
X473032Y110784D03*
X468032D03*
X477592Y125107D03*
X462523Y124283D03*
X467589Y124879D03*
X472611Y124663D03*
X473955Y138838D03*
X475407Y195176D03*
X472226Y201683D03*
X475293Y244571D03*
X472673Y249108D03*
X467335Y359944D03*
X469530Y366754D03*
X473658Y470509D03*
Y475509D03*
X468558Y491669D03*
X468850Y545586D03*
X464776Y636506D03*
X461626Y648827D03*
X474540Y927341D03*
X475018Y992568D03*
X467345Y996480D03*
X464891Y1019069D03*
X473954Y1027202D03*
X464385Y1038534D03*
X471755Y1038665D03*
X470610Y1033783D03*
X475588Y1043055D03*
X470978Y1046591D03*
X469772Y1224717D03*
X469053Y1238094D03*
X467507Y1230974D03*
X461677Y1271882D03*
X467007Y1271914D03*
X472624Y1271807D03*
X463290Y1297035D03*
X492135Y103411D03*
X492529Y97667D03*
X483675D03*
X486206Y143762D03*
X480106Y148717D03*
X489672Y199248D03*
X493272Y230117D03*
X484427Y230556D03*
X488682Y227824D03*
X479686Y228646D03*
X490989Y244297D03*
X482636Y256394D03*
X492817Y357111D03*
X491843Y351089D03*
X490885Y373589D03*
X491053Y365423D03*
X491289Y391589D03*
X490885Y382570D03*
X488438Y418417D03*
X481485Y439900D03*
Y431917D03*
X489485Y431417D03*
X492736Y478982D03*
Y491982D03*
X491818Y534909D03*
X491445Y541135D03*
X482905Y544726D03*
X491534Y552726D03*
X491511Y546553D03*
X493392Y622285D03*
X493580Y616905D03*
X493661Y627713D03*
X493778Y633724D03*
X483059Y662649D03*
X481742Y657477D03*
X482476Y798164D03*
X490706Y859339D03*
X491616Y938771D03*
X479613Y952189D03*
X480711Y999941D03*
X477857Y1004375D03*
X488794Y1024081D03*
X479735Y1032551D03*
X485633Y1036155D03*
X477765Y1093432D03*
X485574Y1098518D03*
X488927Y1104335D03*
X478133Y1271807D03*
X489153Y1271591D03*
X483535Y1271699D03*
X503325Y90650D03*
X508637Y90615D03*
X496023Y362913D03*
X497048Y369450D03*
X495750Y377531D03*
X506500Y379687D03*
X495203Y386890D03*
X503682Y448419D03*
X504729Y469905D03*
X496729Y461919D03*
X504729Y461419D03*
X501224Y492050D03*
X501649Y482165D03*
X500890Y500202D03*
X502493Y495917D03*
X506925Y546830D03*
X497448Y610548D03*
X504265Y633736D03*
X499258Y633716D03*
X506278Y628078D03*
X499278Y641817D03*
X499528Y657843D03*
X496176Y684973D03*
X504508Y783817D03*
X507241Y802149D03*
X495539Y795000D03*
X504641Y789139D03*
X507095Y814784D03*
X507741Y807973D03*
X509665Y824512D03*
X503383Y863025D03*
X498507Y865392D03*
X508248Y873319D03*
X509791Y881932D03*
X509017Y905295D03*
X498435Y1008766D03*
X498524Y997590D03*
X498585Y1016266D03*
X506562Y1238194D03*
X498562Y1226194D03*
Y1242194D03*
X494901Y1273083D03*
X500334Y1273157D03*
X506026Y1273542D03*
X521916Y92874D03*
X512958Y99961D03*
X523867Y169454D03*
X516367D03*
X522276Y223661D03*
X519638Y314346D03*
X512943Y443071D03*
X520823Y442603D03*
X518240Y459371D03*
X512210Y475825D03*
X513310Y462004D03*
X522756Y461818D03*
X513626Y528578D03*
X518416Y544895D03*
X520945Y590801D03*
X520770Y597130D03*
X524770Y605637D03*
X523596Y628242D03*
X515267Y627908D03*
X511278Y633473D03*
X514585Y681325D03*
X520277Y682624D03*
X516973Y713088D03*
X512239Y708434D03*
X511677Y712798D03*
X513504Y755804D03*
X513278Y783286D03*
X526171Y801205D03*
X519891Y795848D03*
X520741Y805149D03*
X524741Y845149D03*
X520870Y874694D03*
X516044Y880162D03*
X520685Y887763D03*
X511025Y911443D03*
X525159Y913818D03*
X516902Y910251D03*
X524475Y952290D03*
X522544Y992854D03*
X512232Y985172D03*
X521055Y1104335D03*
X514562Y1230194D03*
X511876Y1272083D03*
X535984Y79592D03*
X528484D03*
X540751Y97475D03*
X539748Y143740D03*
X537128Y148277D03*
X538170Y172190D03*
X537589Y177616D03*
X532026Y188727D03*
X529148Y208695D03*
X528783Y226141D03*
X532525Y265701D03*
X537612Y265896D03*
X534160Y281716D03*
X540101Y281982D03*
X540906Y290755D03*
X532659Y359557D03*
X526388Y351301D03*
X531612Y354272D03*
X531636Y349057D03*
X528812Y369164D03*
X533211Y364746D03*
X533115Y371856D03*
X530144Y376062D03*
X531953Y380749D03*
X542034Y392209D03*
X541706Y386223D03*
X533189Y390723D03*
X531953Y385749D03*
X535119Y483886D03*
X541572Y556742D03*
X535219Y566797D03*
X535819Y578405D03*
X541245Y578986D03*
X534820Y596782D03*
X540770Y596729D03*
X529601Y596089D03*
X536810Y691203D03*
X536087Y702364D03*
X528653Y708952D03*
X542275Y760782D03*
X539449Y782389D03*
X537578Y772428D03*
X539852Y788099D03*
X530741Y845149D03*
X531076Y913190D03*
X532812Y1273169D03*
X538572Y1289143D03*
X547732Y100625D03*
X552798Y143518D03*
X551898Y152373D03*
X555850Y178560D03*
X555913Y172665D03*
X555740Y183834D03*
X555260Y190185D03*
X549985Y192490D03*
X556030Y200864D03*
X556119Y212455D03*
X556053Y207037D03*
X542628Y266114D03*
X546987Y281307D03*
X551620Y390723D03*
X553563Y384987D03*
X543760Y565997D03*
X547861Y692583D03*
X557751Y750851D03*
X550901Y789509D03*
X544515Y793875D03*
X544741Y809649D03*
X544878Y816309D03*
X556741Y820149D03*
X544741Y823149D03*
X552711Y840120D03*
X557836Y851669D03*
X543001Y874859D03*
X546940Y871389D03*
X547843Y892969D03*
X548327Y905295D03*
X553335Y905405D03*
X552923Y988813D03*
X544719Y1007522D03*
X551485Y1006648D03*
X548852Y1018307D03*
X545094Y1013678D03*
X545566Y1023731D03*
X554696Y1018469D03*
X557681Y1035088D03*
X543621Y1292726D03*
X557584Y1543411D03*
X560573Y60513D03*
X569114Y86012D03*
X565207Y94279D03*
X570394Y110784D03*
X574973Y124663D03*
X564885Y124283D03*
X569951Y124879D03*
X574588Y201683D03*
X564659Y208864D03*
X560928Y228631D03*
X575035Y249108D03*
X573479Y374705D03*
X574625Y547918D03*
X563200Y739600D03*
X571493Y763090D03*
X564362Y757979D03*
X560263Y782207D03*
X567126Y779066D03*
X571984Y784507D03*
X560762Y791422D03*
X564388Y839899D03*
X561134Y869291D03*
X559214Y897425D03*
X567827Y884000D03*
X565003Y936807D03*
X570603Y957207D03*
X560923Y988813D03*
X568923D03*
X567484Y1024003D03*
X566058Y1109564D03*
X560211Y1134764D03*
Y1165091D03*
X566502Y1202103D03*
X575620Y1207737D03*
X569135Y1214372D03*
X564890Y1218169D03*
X570796Y1530309D03*
X563968Y1541445D03*
X568279Y1538438D03*
X572507Y1541375D03*
X576669Y102249D03*
X586037Y97667D03*
X575394Y110784D03*
X579954Y125107D03*
X582468Y148717D03*
X576317Y138838D03*
X577769Y195176D03*
X585016Y198733D03*
X586789Y230556D03*
X591044Y227824D03*
X582048Y228646D03*
X577655Y244571D03*
X584998Y256394D03*
X578193Y336391D03*
X584679Y336285D03*
X577638Y769772D03*
X578271Y763556D03*
X583102Y767137D03*
X587183Y785008D03*
X578204Y775137D03*
X585912Y778470D03*
X588659Y790336D03*
X588501Y811048D03*
X577501Y811548D03*
X582737Y819831D03*
X580327Y892000D03*
X586136Y908935D03*
X586103Y961807D03*
X584923Y988813D03*
X576923D03*
X581166Y1021954D03*
X577704Y1029427D03*
X587880Y1034834D03*
X587467Y1105091D03*
X582012Y1102091D03*
X587467Y1117691D03*
X582012Y1127291D03*
Y1114691D03*
X587467Y1130291D03*
Y1142891D03*
X582012Y1139891D03*
X587467Y1155491D03*
X582012Y1152491D03*
X587467Y1168091D03*
X582012Y1165091D03*
X587467Y1180691D03*
X582012Y1177691D03*
X583520Y1230407D03*
X581803Y1493687D03*
X578859Y1497758D03*
X588859Y1490895D03*
X590826Y1495688D03*
X588507Y1514141D03*
X582027Y1502800D03*
X581803Y1509687D03*
X577931Y1505687D03*
X575809Y1532912D03*
X587809Y1528389D03*
X583809Y1533025D03*
X579809Y1528163D03*
X587809Y1545854D03*
X583809Y1541607D03*
X577571Y1544013D03*
X594497Y103411D03*
X594891Y97667D03*
X605687Y90650D03*
X592034Y199248D03*
X595634Y230117D03*
X593351Y244297D03*
X603554Y250783D03*
X605147Y378600D03*
X602462Y458711D03*
X597517Y546805D03*
X605011Y615600D03*
X604715Y914640D03*
X591754Y956979D03*
X606142Y965665D03*
X597556Y965829D03*
X600923Y988813D03*
X592923D03*
X599113Y1012354D03*
X593658Y1009354D03*
X599113Y1024954D03*
X593658Y1021954D03*
X606434Y1041904D03*
X597026Y1224472D03*
X592991Y1215035D03*
X594183Y1220068D03*
X592885Y1229402D03*
X592634Y1234921D03*
X591487Y1501687D03*
X591481Y1509313D03*
X595809Y1532133D03*
Y1546214D03*
X591809Y1542407D03*
X610999Y90615D03*
X615320Y99961D03*
X618729Y169454D03*
X613401Y242913D03*
X618801Y546062D03*
X616923Y988813D03*
X608923D03*
X612923Y997860D03*
X607993Y1036920D03*
X610780Y1051037D03*
X613386Y1143390D03*
X622736Y1151870D03*
Y1159350D03*
X613738Y1546507D03*
X628153Y81611D03*
X635653D03*
X624278Y92874D03*
X639490Y148277D03*
X626229Y169454D03*
X639951Y177616D03*
X634388Y188727D03*
X631510Y208695D03*
X624638Y223661D03*
X631145Y226141D03*
X639974Y265896D03*
X634887Y265701D03*
X636522Y281716D03*
X632071Y1142487D03*
X624594Y1146271D03*
X626476Y1155610D03*
X626073Y1170092D03*
X624606Y1164960D03*
X639565Y1194917D03*
X650094Y100625D03*
X643113Y97475D03*
X655160Y143518D03*
X642110Y143740D03*
X654260Y152373D03*
X640532Y172190D03*
X652347Y192490D03*
X647547Y231021D03*
X644990Y266114D03*
X649349Y281307D03*
X642463Y281982D03*
X643268Y290755D03*
X642414Y545528D03*
X656026Y551040D03*
X650958Y668153D03*
X643271Y1135040D03*
X650787Y1217322D03*
X662935Y60513D03*
X671476Y86012D03*
X667569Y94279D03*
X658756Y103621D03*
X667247Y124283D03*
X672313Y124879D03*
X658275Y172665D03*
X658212Y178560D03*
X658102Y183834D03*
X657622Y190185D03*
X658392Y200864D03*
X667021Y208864D03*
X658481Y212455D03*
X658415Y207037D03*
X663290Y228631D03*
X661761Y382109D03*
X661760Y551683D03*
X660586Y606929D03*
X665086Y604567D03*
X665586Y595500D03*
X660827Y612592D03*
X666244Y610072D03*
X660546Y618400D03*
X666180Y616317D03*
X665643Y646055D03*
X658064Y650119D03*
X669488Y1209842D03*
X662008Y1217322D03*
X669488D03*
X679031Y102249D03*
X688399Y97667D03*
X677756Y110784D03*
X672756D03*
X682316Y125107D03*
X677335Y124663D03*
X684830Y148717D03*
X678679Y138838D03*
X680131Y195176D03*
X687378Y198733D03*
X676950Y201683D03*
X684410Y228646D03*
X677397Y249108D03*
X680017Y244571D03*
X682857Y339477D03*
X687055Y376456D03*
X685353Y404718D03*
Y412718D03*
X672586Y544000D03*
X680586Y568000D03*
X681256Y1055975D03*
X687408Y1050045D03*
X682088Y1062847D03*
X673228Y1213582D03*
X696859Y103411D03*
X697253Y97667D03*
X690930Y143762D03*
X694396Y199248D03*
X697996Y230117D03*
X689151Y230556D03*
X693406Y227824D03*
X695713Y244297D03*
X690504Y253198D03*
X689486Y339583D03*
X692356Y764614D03*
X691991Y759581D03*
X692155Y778974D03*
X692221Y773449D03*
X697684Y1053324D03*
X690085Y1058763D03*
X701899Y1633858D03*
X708049Y90650D03*
X713361Y90615D03*
X717682Y99961D03*
X721091Y169454D03*
X712692Y356779D03*
X717105Y410964D03*
X717420Y404334D03*
X709781Y442956D03*
X720996Y442856D03*
X715733Y447055D03*
X719051Y458455D03*
X719612Y451108D03*
X706211Y465874D03*
X711463Y546712D03*
X713425Y786029D03*
X707252Y1055787D03*
X707492Y1633514D03*
X713002Y1637887D03*
X729842Y81274D03*
X737342D03*
X726640Y92874D03*
X728591Y169454D03*
X736750Y188727D03*
X733872Y208695D03*
X733507Y226141D03*
X727000Y223661D03*
X737249Y265701D03*
X723404Y379657D03*
X721900Y384500D03*
X723440Y391496D03*
X734661Y393633D03*
X723440Y398583D03*
X728503Y891692D03*
X736452Y890548D03*
X728692Y886653D03*
X725194Y942073D03*
X733798Y950186D03*
X722820Y1064608D03*
X726823Y1263349D03*
X736067Y1611892D03*
X729600Y1625165D03*
X732268Y1618260D03*
X752456Y100625D03*
X745475Y97475D03*
X744472Y143740D03*
X741852Y148277D03*
X742894Y172190D03*
X742313Y177616D03*
X747352Y266114D03*
X742336Y265896D03*
X751711Y281307D03*
X744825Y281982D03*
X738884Y281716D03*
X745630Y290755D03*
X749444Y393858D03*
X745586Y388000D03*
X752785Y382047D03*
X753086Y403500D03*
X751086Y398583D03*
X739316Y458572D03*
X744069Y746617D03*
X742000Y768137D03*
X738707Y987952D03*
X745673Y1007009D03*
X743200Y1128100D03*
X748031Y1142519D03*
X744291Y1149999D03*
X753099Y1185514D03*
X753537Y1178467D03*
X749786Y1590517D03*
X738775Y1597866D03*
X749704Y1608631D03*
X765297Y60513D03*
X769931Y94279D03*
X769609Y124283D03*
X757522Y143518D03*
X756622Y152373D03*
X760637Y172665D03*
X760464Y183834D03*
X760574Y178560D03*
X754709Y192490D03*
X759984Y190185D03*
X760754Y200864D03*
X769383Y208864D03*
X760843Y212455D03*
X760777Y207037D03*
X769349Y324518D03*
X754805Y339559D03*
X759624Y353961D03*
X756086Y377912D03*
X755086Y391496D03*
X756086Y386500D03*
X756174Y397912D03*
X755086Y409000D03*
X767585Y433666D03*
X765105Y572830D03*
Y600537D03*
X757721Y617468D03*
X755512Y1112598D03*
X766732Y1142519D03*
X760398Y1440276D03*
X763542Y1590186D03*
X767310Y1599164D03*
X768361Y1610083D03*
X756358Y1616917D03*
X773838Y86012D03*
X781393Y102249D03*
X775118Y110784D03*
X780118D03*
X784678Y125107D03*
X779697Y124663D03*
X774675Y124879D03*
X781041Y138838D03*
X782493Y195176D03*
X779312Y201683D03*
X774432Y218085D03*
X782379Y244571D03*
X779759Y249108D03*
X772165Y314890D03*
X784118Y303962D03*
X772162Y332584D03*
X778502Y348015D03*
X772859Y347937D03*
X784902Y428653D03*
X780782Y433440D03*
X783620Y1460108D03*
X781110Y1595254D03*
X777059Y1608982D03*
X784046Y1600438D03*
X799221Y103411D03*
X799615Y97667D03*
X790761D03*
X793292Y143762D03*
X787192Y148717D03*
X796758Y199248D03*
X789740Y198733D03*
X800358Y230117D03*
X795768Y227824D03*
X791513Y230556D03*
X786772Y228646D03*
X798075Y244297D03*
X789722Y256394D03*
X786461Y293028D03*
X790280Y287421D03*
X795445Y356950D03*
X789581Y405011D03*
X793893Y409502D03*
X802136Y448334D03*
X794733Y915483D03*
X797178Y922746D03*
X800018Y934000D03*
X792575Y932815D03*
X793810Y1013122D03*
X801043Y1010773D03*
X796338Y1138130D03*
X797160Y1146609D03*
X792277Y1173065D03*
X799020Y1175975D03*
X792382Y1191664D03*
X788208Y1208014D03*
X796777Y1206299D03*
X790587Y1202200D03*
X790749Y1196138D03*
X791986Y1224512D03*
X788327Y1221062D03*
X802394Y1221197D03*
X794971Y1233951D03*
X800262Y1237535D03*
X788102Y1232283D03*
X793548Y1397690D03*
X799330Y1416760D03*
X789647Y1427518D03*
X798601Y1431673D03*
X793288Y1450918D03*
X787694Y1442749D03*
X800607Y1440760D03*
X793994Y1441499D03*
X797083Y1467883D03*
X794005Y1464178D03*
X786591Y1452803D03*
X810411Y90650D03*
X815723Y90615D03*
X817456Y305368D03*
Y313368D03*
X809490Y305368D03*
X809466Y310604D03*
X817100Y319600D03*
X809457Y330459D03*
X809490Y325368D03*
Y317368D03*
X810749Y443045D03*
X810453Y453330D03*
X810406Y448214D03*
X813678Y740979D03*
X817584Y764219D03*
X818000Y797000D03*
X817845Y817879D03*
X818500Y810135D03*
X815863Y830097D03*
X814299Y840877D03*
X813887Y835146D03*
X816037Y845578D03*
X817884Y915425D03*
X806168Y910166D03*
X803507Y926197D03*
X817229Y935344D03*
X818070Y972723D03*
X809632Y1142666D03*
X817964Y1157404D03*
X811507Y1157544D03*
X810018Y1167768D03*
X815037D03*
X814170Y1185205D03*
X805212Y1180175D03*
X805519Y1187215D03*
X816284Y1197626D03*
X804458Y1193112D03*
X817446Y1210089D03*
X812405Y1228760D03*
X806148Y1383715D03*
Y1375208D03*
X810204Y1401661D03*
X804654Y1404769D03*
X805569Y1441519D03*
X802684Y1465549D03*
X807576Y1469584D03*
X834559Y80265D03*
X829002Y92874D03*
X820044Y99961D03*
X823453Y169454D03*
X830953D03*
X829362Y223661D03*
X822160Y258880D03*
X822477Y309368D03*
X829485Y345101D03*
X822626Y348066D03*
X818840Y444091D03*
X824650Y455034D03*
Y450034D03*
X832284Y731216D03*
X821582Y727140D03*
X830484Y738750D03*
X830075Y769000D03*
X824500Y756000D03*
Y774000D03*
Y782500D03*
X830075Y787000D03*
X824342Y792315D03*
X824500Y800500D03*
X830075Y805000D03*
Y823000D03*
X829757Y842672D03*
X822916Y852576D03*
X823540Y857956D03*
X831654Y864494D03*
X822938Y863298D03*
X828835Y854920D03*
X833194Y873561D03*
X827992Y874107D03*
X830063Y898500D03*
X819918Y889365D03*
X824804Y898395D03*
X829848Y914211D03*
X825336Y916774D03*
X834751Y922368D03*
X833683Y936743D03*
X824414Y939655D03*
X822829Y960614D03*
X832432Y977982D03*
X829517Y1010303D03*
X823549Y1009583D03*
X825744Y1146937D03*
X818879Y1187310D03*
X823309Y1180235D03*
X823516Y1185238D03*
X819419Y1230265D03*
X826204Y1440689D03*
X826341Y1451236D03*
X826365Y1458974D03*
X842059Y80265D03*
X847837Y97475D03*
X844675Y177616D03*
X845256Y172190D03*
X839112Y188727D03*
X836234Y208695D03*
X835869Y226141D03*
X844698Y265896D03*
X839611Y265701D03*
X849714Y266114D03*
X841246Y281716D03*
X847187Y281982D03*
X847992Y290755D03*
X845435Y356172D03*
X849591Y411388D03*
X842515Y461382D03*
X850732Y469382D03*
X842779Y473076D03*
X842916Y467009D03*
X848444Y657756D03*
X837272Y663910D03*
X842352Y659243D03*
X845850Y710969D03*
X836078Y709619D03*
X848284Y731181D03*
X846484Y738750D03*
X836713Y738751D03*
X844520Y791925D03*
X835215Y847719D03*
X835346Y891346D03*
X843665Y907110D03*
X841689Y941243D03*
X842856Y949146D03*
X843734Y1008778D03*
X843650Y1449546D03*
X835474Y1457397D03*
X854818Y100625D03*
X862826Y183834D03*
X862999Y172665D03*
X862936Y178560D03*
X857071Y192490D03*
X862346Y190185D03*
X863116Y200864D03*
X863205Y212455D03*
X863139Y207037D03*
X852271Y231021D03*
X866015Y224536D03*
X854073Y281307D03*
X863430Y309368D03*
Y316970D03*
X863114Y324505D03*
X863040Y330140D03*
X860586Y383000D03*
X861235Y394000D03*
X854086Y392999D03*
X855017Y411969D03*
X867093Y570703D03*
Y582828D03*
X861663Y646653D03*
X855300Y646819D03*
X853982Y657506D03*
X859441Y678015D03*
X864029Y688970D03*
X858186Y713170D03*
X867455Y710611D03*
X858002Y707244D03*
X867227Y722060D03*
X859199Y744517D03*
X854484Y738633D03*
X859000Y756000D03*
X854758Y766075D03*
X852710Y755925D03*
X859000Y774000D03*
X853837Y784075D03*
X851584Y773925D03*
X859000Y792000D03*
X853837Y802075D03*
X859000Y810000D03*
X853851Y818000D03*
X852250Y809925D03*
X856992Y829054D03*
X863206Y864154D03*
X865218Y853311D03*
X867310Y873743D03*
X861771Y874368D03*
X863631Y883459D03*
X862868Y891471D03*
X858988Y898307D03*
X867096Y935963D03*
X858601Y934505D03*
X853030Y934690D03*
X851925Y951350D03*
X860887Y1023208D03*
X867659Y60513D03*
X876200Y86012D03*
X867787Y85731D03*
X872293Y94279D03*
X872816Y244389D03*
X883118Y262687D03*
X873262Y300030D03*
X869924Y305368D03*
Y313368D03*
Y321368D03*
Y328722D03*
X874005Y344917D03*
X870413Y342791D03*
X869924Y333722D03*
X877909Y391731D03*
X882925Y391099D03*
X872736Y391754D03*
X867586Y393000D03*
X868586Y398500D03*
X874253Y420080D03*
X869454Y479303D03*
X869954Y487303D03*
X882954Y486256D03*
X882195Y539204D03*
X872264Y558530D03*
X883525Y554619D03*
X878382Y554942D03*
X876949Y571419D03*
X872264Y566530D03*
Y562530D03*
X881476Y588202D03*
X881131Y577349D03*
X877400Y584126D03*
X875290Y578703D03*
X878881Y667156D03*
X880501Y710611D03*
X873021Y715729D03*
X879875Y753612D03*
X873728Y752692D03*
X874851Y769017D03*
X880054Y769358D03*
X870017Y757313D03*
X874807Y784757D03*
X870000Y780000D03*
X879887Y784719D03*
X880040Y792851D03*
X881753Y833087D03*
X869886Y846907D03*
X869609Y841429D03*
X880404Y839742D03*
X875820Y843856D03*
X875171Y850086D03*
X870108Y862191D03*
X876751Y865038D03*
X878246Y859995D03*
X873845Y855576D03*
X870300Y881119D03*
X871876Y869076D03*
X873432Y874571D03*
X879286Y895183D03*
X877080Y887376D03*
X868945Y887459D03*
X871600Y898584D03*
X883286Y901937D03*
X876481Y941126D03*
X872126Y934766D03*
X870209Y949384D03*
X869741Y1025895D03*
X869902Y1079077D03*
X875600Y1096200D03*
X875321Y1207654D03*
X883142Y1259935D03*
X878244Y1451605D03*
X879174Y1459551D03*
X894472Y143740D03*
X891852Y148277D03*
X895064Y250186D03*
X885884Y255118D03*
X897004Y257480D03*
X892484Y260860D03*
X886496Y268968D03*
X886059Y284644D03*
X885953Y321368D03*
Y333368D03*
X888812Y357372D03*
X890553Y392038D03*
X889219Y426952D03*
X891699Y420445D03*
X885556Y543664D03*
X890274Y565040D03*
X894274D03*
X895933Y609696D03*
X886836Y729778D03*
X886610Y769419D03*
X890722Y777118D03*
X884894Y784778D03*
X892040Y784511D03*
X898737Y792289D03*
X889516Y792851D03*
X886065Y828112D03*
X890254Y835978D03*
X891386Y899501D03*
X887286Y896235D03*
X897623Y902409D03*
X891367Y941126D03*
X885099Y1021685D03*
X887862Y1088067D03*
X894004Y1081231D03*
X889033Y1134078D03*
X889967Y1147844D03*
X888650Y1199622D03*
X894713Y1210419D03*
X898878Y1214182D03*
X899286Y1219469D03*
X892532Y1220112D03*
X897169Y1225259D03*
X889244Y1444859D03*
X907522Y143518D03*
X906622Y152373D03*
X915653Y307438D03*
X905483Y355262D03*
X905000Y362158D03*
X906161Y367191D03*
X910646Y376084D03*
X906344Y372524D03*
X910236Y465272D03*
X914296Y558143D03*
X913728Y550495D03*
X908846Y560124D03*
X910789Y598726D03*
X912462Y683770D03*
Y695770D03*
X913247Y714204D03*
X909038Y806465D03*
X914577Y827133D03*
X902630Y828027D03*
X915095Y838701D03*
X911286Y899612D03*
X911487Y894491D03*
X914199Y890063D03*
X906586Y900841D03*
X900983Y940895D03*
X906909Y951494D03*
X909811Y962400D03*
X902389Y1081764D03*
X908799Y1093659D03*
Y1088659D03*
X908278Y1083484D03*
X908799Y1100659D03*
X902353Y1104333D03*
X903959Y1207823D03*
X906784Y1216607D03*
X931393Y102249D03*
X930118Y110784D03*
X925118D03*
X924675Y124879D03*
X929697Y124663D03*
X919609Y124283D03*
X931041Y138838D03*
X929978Y186854D03*
X923732Y304585D03*
X923311Y349959D03*
X921343Y376888D03*
X916330Y377748D03*
X929947Y376821D03*
X927766Y456442D03*
X927596Y447453D03*
X921973Y469328D03*
X927401Y469059D03*
X916593Y469140D03*
X917811Y544325D03*
X921306Y567295D03*
X927288Y567117D03*
X923642Y561578D03*
X923599Y581578D03*
X920165Y594914D03*
X930450Y603319D03*
X929790Y828603D03*
X921127Y833588D03*
X927867Y823081D03*
X921916Y822095D03*
X919702Y826833D03*
X930884Y848974D03*
X925072Y842031D03*
X930626Y842386D03*
X931145Y865672D03*
X931826Y874531D03*
X922475Y894575D03*
X917770Y897618D03*
X923892Y889077D03*
X929181Y895029D03*
X931597Y900701D03*
X916628Y918042D03*
X928628D03*
X929741Y967006D03*
X924956Y994321D03*
X924864Y1023208D03*
X916749Y1092664D03*
X930754Y1310564D03*
X925909Y1413070D03*
X940761Y97667D03*
X934678Y125107D03*
X943292Y143762D03*
X937192Y148717D03*
X933159Y180347D03*
X947424Y184419D03*
X940406Y183904D03*
X946234Y213390D03*
X942179Y215727D03*
X937438Y213817D03*
X936962Y249807D03*
X944248Y239844D03*
X934128Y355168D03*
X944238Y360828D03*
X936175Y364823D03*
X933424Y458455D03*
X933161Y451442D03*
X933404Y463462D03*
X933412Y468942D03*
X948532Y541135D03*
X939992Y544726D03*
X948598Y546553D03*
X948621Y552726D03*
X935281Y677795D03*
X939314Y707847D03*
X933201Y798297D03*
X946970Y786366D03*
X938357Y808856D03*
X940100Y830700D03*
X933344Y821858D03*
X943382Y835395D03*
X933713Y860799D03*
X937333Y864332D03*
X942194Y891216D03*
X944628Y928101D03*
X933810Y972433D03*
X945671Y982191D03*
X943093Y1021769D03*
X948633Y1078908D03*
X933879Y1079077D03*
X939298Y1207654D03*
X947119Y1259935D03*
X944207Y1320739D03*
X947308Y1325035D03*
X944235Y1406262D03*
X947411Y1443901D03*
X934456Y1479446D03*
X937671Y1492139D03*
X949221Y103411D03*
X949615Y97667D03*
X960411Y90650D03*
X950177Y215730D03*
X948741Y229468D03*
X948785Y242464D03*
X950953Y317947D03*
X962769Y451419D03*
X955816Y464919D03*
X963816Y464419D03*
X958124Y492354D03*
X958736Y482165D03*
X959600Y496486D03*
X957977Y500202D03*
X948905Y534909D03*
X950479Y622285D03*
X954535Y610548D03*
X950667Y616905D03*
X963365Y628078D03*
X961352Y633736D03*
X950865Y633724D03*
X950748Y627713D03*
X956345Y633716D03*
X956365Y641817D03*
X956023Y706907D03*
X963869Y725057D03*
X955950Y734178D03*
X957763Y725336D03*
X957579Y744168D03*
X953837Y763025D03*
X950699Y779711D03*
X949609Y796051D03*
X957487Y798553D03*
X955343Y866850D03*
X964280Y927777D03*
X958567Y927654D03*
X951863Y936168D03*
X957235Y936398D03*
X962329Y936229D03*
X957671Y977921D03*
X949671D03*
X957671Y991564D03*
X953671Y982191D03*
X954937Y1021998D03*
X957981Y1081231D03*
X951839Y1088067D03*
X953010Y1134078D03*
X953944Y1147844D03*
X952627Y1199622D03*
X958690Y1210419D03*
X963263Y1219469D03*
X962855Y1214182D03*
X956509Y1220112D03*
X961146Y1225259D03*
X952395Y1395276D03*
X958585Y1389437D03*
X952035Y1401223D03*
X957947Y1484672D03*
X979002Y92874D03*
X965723Y90615D03*
X970044Y99961D03*
X980953Y169454D03*
X973453D03*
X979362Y223661D03*
X975631Y343112D03*
X972030Y446071D03*
X979910Y445603D03*
X972397Y465004D03*
X977327Y462371D03*
X975868Y527449D03*
X978303Y544895D03*
X978032Y590801D03*
X977857Y597130D03*
X980683Y628242D03*
X972354Y627908D03*
X968365Y633473D03*
X973450Y747280D03*
X974437Y849140D03*
X973510Y834991D03*
X967842Y864801D03*
X970299Y853773D03*
X978880Y869552D03*
X973130Y880162D03*
X977771Y887684D03*
X966813Y904556D03*
X973988Y910038D03*
X965671Y982191D03*
X966366Y1081764D03*
X972776Y1093659D03*
X972255Y1083484D03*
X972776Y1088659D03*
X966330Y1104333D03*
X972776Y1100659D03*
X967936Y1207823D03*
X970761Y1216607D03*
X974985Y1290950D03*
X979996Y1386100D03*
X974882Y1392080D03*
X973806Y1444392D03*
X993743Y78919D03*
X986243D03*
X996834Y143740D03*
X994214Y148277D03*
X995256Y172190D03*
X994675Y177616D03*
X989112Y188727D03*
X986234Y208695D03*
X985869Y226141D03*
X989611Y265701D03*
X994698Y265896D03*
X991246Y281716D03*
X997187Y281982D03*
X987517Y314092D03*
X993552Y318175D03*
X989630Y343862D03*
X983717Y341665D03*
X983956Y346652D03*
X993026Y353813D03*
X981719Y352217D03*
X997059Y348522D03*
X988631Y349496D03*
X989950Y360307D03*
X986373Y370467D03*
X981843Y464818D03*
X992206Y483886D03*
X985699Y480705D03*
X985334Y498151D03*
X982375Y529929D03*
X986268Y532949D03*
X992306Y566797D03*
X992906Y578405D03*
X991907Y596782D03*
X986688Y596089D03*
X986600Y717641D03*
X987461Y745796D03*
X985921Y805135D03*
X994094Y829000D03*
X987702Y829159D03*
X987703Y837159D03*
X992441Y870398D03*
X985554Y913434D03*
X986177Y1367678D03*
X983400Y1381496D03*
X984600Y1386800D03*
X985448Y1398271D03*
X994994Y1444240D03*
X982241Y1489637D03*
X1004818Y100625D03*
X997837Y97475D03*
X1013480Y103621D03*
X1005397Y141247D03*
X1009884Y143518D03*
X1008984Y152373D03*
X1012936Y178560D03*
X1012826Y183834D03*
X1012999Y172665D03*
X1012346Y190185D03*
X1007071Y192490D03*
X1013116Y200864D03*
X1013139Y207037D03*
X1013205Y212455D03*
X999714Y266114D03*
X1004061Y280808D03*
X997992Y290755D03*
X1002580Y309619D03*
X1003181Y323057D03*
X1001105Y318006D03*
X1000411Y555306D03*
X1001926Y565908D03*
X998332Y578986D03*
X997857Y596729D03*
X1013151Y756726D03*
X1013319Y785929D03*
X1006053Y787745D03*
X1012703Y837659D03*
X1001187Y850084D03*
X1002176Y875303D03*
X1005413Y892787D03*
Y905295D03*
X1006619Y933822D03*
X1012219Y954222D03*
X1009564Y988874D03*
X1001805Y1007522D03*
X1008571Y1006648D03*
X1002180Y1013678D03*
X1002652Y1023731D03*
X1005938Y1018307D03*
X998600Y1369200D03*
X999283Y1377400D03*
X998643Y1398271D03*
X998685Y1389915D03*
X1017659Y60513D03*
X1026200Y86012D03*
X1017787Y85731D03*
X1022293Y94279D03*
X1027480Y110784D03*
X1021971Y124283D03*
X1027037Y124879D03*
X1021826Y186778D03*
X1018014Y228631D03*
X1015281Y309620D03*
X1014406Y344620D03*
X1020406Y350772D03*
X1025905Y353890D03*
X1021885Y698974D03*
X1021221Y848712D03*
X1017800Y867065D03*
X1021408Y895008D03*
X1024913Y884000D03*
X1013897Y904950D03*
X1022346Y917669D03*
X1029570Y917718D03*
X1027719Y958822D03*
X1018009Y988813D03*
X1026009D03*
X1024570Y1024003D03*
X1014767Y1035088D03*
X1025143Y1030672D03*
X1023144Y1109564D03*
X1023139Y1184856D03*
X1022420Y1203204D03*
X1026221Y1214372D03*
X1021976Y1218169D03*
X1019391Y1377061D03*
X1020196Y1444492D03*
X1016769Y1489832D03*
X1033755Y102249D03*
X1043123Y97667D03*
X1032480Y110784D03*
X1037040Y125107D03*
X1032059Y124663D03*
X1045654Y143762D03*
X1039554Y148717D03*
X1033403Y138838D03*
X1034855Y195176D03*
X1042102Y198733D03*
X1031674Y201683D03*
X1043875Y230556D03*
X1039134Y228646D03*
X1034741Y244571D03*
X1032121Y249108D03*
X1042084Y256394D03*
X1045650Y300093D03*
X1041783Y321114D03*
X1031259Y350427D03*
X1031712Y547918D03*
X1043016Y782161D03*
X1043425Y830800D03*
X1043626Y836563D03*
X1037527Y836486D03*
X1031813Y850273D03*
X1046045Y841217D03*
X1040822Y841339D03*
X1044390Y861210D03*
X1038363Y875288D03*
X1038010Y902565D03*
X1042009Y988813D03*
X1034009D03*
X1038252Y1021954D03*
X1044553Y1105091D03*
X1039098Y1102091D03*
X1044553Y1117691D03*
X1039098Y1114691D03*
Y1127291D03*
X1044553Y1130291D03*
Y1142891D03*
X1039098Y1139891D03*
X1044553Y1155491D03*
X1039098Y1152491D03*
X1044553Y1168091D03*
X1039098Y1165091D03*
X1044553Y1180691D03*
X1039098Y1177691D03*
X1032831Y1207950D03*
X1040606Y1230407D03*
X1045218Y1444596D03*
X1051583Y103411D03*
X1051977Y97667D03*
X1049120Y199248D03*
X1052720Y230117D03*
X1048130Y227824D03*
X1061387Y343509D03*
X1060679Y356151D03*
X1059549Y458711D03*
X1054604Y546805D03*
X1062098Y615600D03*
X1048314Y833102D03*
X1053392Y832788D03*
X1051550Y823146D03*
X1050358Y837793D03*
X1052500Y841200D03*
X1049087Y856033D03*
X1053909Y855472D03*
X1050009Y988813D03*
X1058009D03*
X1056199Y1012354D03*
X1050744Y1009354D03*
X1056199Y1024954D03*
X1050744Y1021954D03*
X1057212Y1040356D03*
X1049930Y1221407D03*
X1050178Y1214934D03*
X1054295Y1224472D03*
X1049770Y1229402D03*
X1049720Y1234921D03*
X1050944Y1437997D03*
X1062773Y90650D03*
X1068085Y90615D03*
X1072406Y99961D03*
X1075815Y169454D03*
X1076571Y310574D03*
X1075888Y546062D03*
X1063642Y634190D03*
X1066931Y645389D03*
X1065823Y988773D03*
X1074009Y988813D03*
X1070009Y997860D03*
X1065079Y1036920D03*
X1076577Y1041332D03*
X1067866Y1051037D03*
X1070472Y1143390D03*
X1069642Y1445541D03*
X1068861Y1451311D03*
X1085912Y78918D03*
X1093412D03*
X1081364Y92874D03*
X1083315Y169454D03*
X1091474Y188727D03*
X1088596Y208695D03*
X1088231Y226141D03*
X1081724Y223661D03*
X1091973Y265701D03*
X1093608Y281716D03*
X1092554Y340318D03*
X1089145Y1142518D03*
X1081680Y1146271D03*
X1079822Y1151870D03*
X1083562Y1155610D03*
X1079822Y1159350D03*
X1083159Y1170092D03*
X1081692Y1164960D03*
X1084000Y1529600D03*
X1091529Y1528718D03*
X1091525Y1546300D03*
X1091569Y1561300D03*
X1092527Y1579422D03*
X1090469Y1588435D03*
X1083900Y1593206D03*
X1088021Y1606949D03*
X1093778Y1599574D03*
X1086904Y1599004D03*
X1090093Y1628297D03*
X1089474Y1638213D03*
X1100199Y97475D03*
X1107180Y100625D03*
X1107759Y141247D03*
X1099196Y143740D03*
X1096576Y148277D03*
X1097618Y172190D03*
X1109903Y171523D03*
X1097037Y177616D03*
X1109433Y192490D03*
X1102076Y266114D03*
X1097060Y265896D03*
X1106435Y281307D03*
X1099549Y281982D03*
X1100354Y290755D03*
X1105012Y353504D03*
X1099501Y545528D03*
X1104448Y653161D03*
X1108045Y668153D03*
X1100357Y1135040D03*
X1096651Y1194917D03*
X1107873Y1217322D03*
X1107200Y1438914D03*
X1096780Y1526700D03*
X1101402Y1518200D03*
Y1531702D03*
X1098617Y1546183D03*
X1096780Y1535400D03*
X1099371Y1561153D03*
X1100476Y1579318D03*
X1102904Y1566668D03*
X1100233Y1588000D03*
X1098904Y1602138D03*
X1101946Y1614709D03*
X1096941Y1627905D03*
X1105474Y1629450D03*
Y1638426D03*
X1097474Y1637753D03*
X1120021Y60513D03*
X1120149Y85731D03*
X1124655Y94279D03*
X1115842Y103621D03*
X1124333Y124283D03*
X1112246Y143518D03*
X1111346Y152373D03*
X1115188Y183834D03*
X1115298Y178560D03*
X1115361Y172665D03*
X1124075Y192665D03*
X1115478Y200864D03*
X1115501Y207037D03*
X1115567Y212455D03*
X1124107Y208864D03*
X1120376Y228631D03*
X1118848Y382109D03*
X1118847Y551683D03*
X1113113Y551040D03*
X1117673Y606929D03*
X1122673Y595500D03*
X1122173Y604567D03*
X1123331Y610072D03*
X1123267Y616317D03*
X1117633Y618400D03*
X1117914Y612592D03*
X1115151Y650119D03*
X1119094Y1217322D03*
X1126574D03*
Y1209842D03*
X1128562Y86012D03*
X1136117Y102249D03*
X1129842Y110784D03*
X1134842D03*
X1139402Y125107D03*
X1129399Y124879D03*
X1134421Y124663D03*
X1141916Y148717D03*
X1135765Y138838D03*
X1137217Y195176D03*
X1134036Y201683D03*
X1141496Y228646D03*
X1137103Y244571D03*
X1134483Y249108D03*
X1137830Y336230D03*
X1142440Y404718D03*
Y412718D03*
X1135548Y455804D03*
X1129673Y544000D03*
X1137673Y568000D03*
X1138342Y1055975D03*
X1139174Y1062847D03*
X1130314Y1213582D03*
X1153945Y103411D03*
X1145485Y97667D03*
X1154339D03*
X1148016Y143762D03*
X1151482Y199248D03*
X1144464Y198733D03*
X1146237Y230556D03*
X1155082Y230117D03*
X1150492Y227824D03*
X1147590Y253198D03*
X1145587Y339148D03*
X1157251Y636842D03*
X1152485Y764552D03*
X1147468Y766093D03*
X1146674Y778409D03*
X1153485Y813142D03*
X1154985Y802897D03*
X1153229Y848581D03*
X1144494Y1050045D03*
X1154770Y1053324D03*
X1147171Y1058763D03*
X1170447Y90615D03*
X1165135Y90650D03*
X1174768Y99961D03*
X1174284Y443585D03*
X1166868Y442956D03*
X1172172Y433003D03*
X1163298Y465874D03*
X1160756Y665140D03*
X1164732Y802269D03*
X1173122Y802759D03*
X1163579Y850774D03*
X1161535Y844167D03*
X1174461Y914515D03*
X1164338Y1055787D03*
X1189957Y80938D03*
X1183726Y92874D03*
X1178177Y169454D03*
X1185677D03*
X1190958Y208695D03*
X1190593Y226141D03*
X1184086Y223661D03*
X1191748Y392676D03*
X1179184Y403307D03*
X1176699Y451108D03*
X1176138Y458455D03*
X1177566Y778539D03*
X1185516Y844248D03*
X1190968Y848703D03*
X1184340Y851072D03*
X1183012Y856553D03*
X1190213Y856816D03*
X1182602Y879142D03*
X1184652Y886399D03*
X1190431Y888873D03*
X1181151Y919034D03*
X1187871Y916534D03*
X1188219Y951789D03*
X1181438Y978941D03*
X1187714Y984794D03*
X1179906Y1064608D03*
X1191643Y1163114D03*
X1197457Y80938D03*
X1202561Y97475D03*
X1201558Y143740D03*
X1198938Y148277D03*
X1199980Y172190D03*
X1199399Y177616D03*
X1193836Y188727D03*
X1199422Y265896D03*
X1204438Y266114D03*
X1194335Y265701D03*
X1201911Y281982D03*
X1195970Y281716D03*
X1202716Y290755D03*
X1195800Y324000D03*
X1206531Y393858D03*
X1202673Y388000D03*
X1208173Y398583D03*
X1192702Y440489D03*
X1192957Y435158D03*
X1196403Y458572D03*
X1197152Y882399D03*
X1196661Y922901D03*
X1192651Y918534D03*
X1203219Y962789D03*
X1193483Y983053D03*
X1205117Y1112598D03*
X1200313Y1128100D03*
X1205117Y1142519D03*
X1201377Y1149999D03*
X1222383Y60513D03*
X1222511Y85731D03*
X1218204Y103621D03*
X1209542Y100625D03*
X1210121Y141247D03*
X1214608Y143518D03*
X1213708Y152373D03*
X1217550Y183834D03*
X1212265Y171523D03*
X1217723Y172665D03*
X1217660Y178560D03*
X1211795Y192490D03*
X1217840Y200864D03*
X1217863Y207037D03*
X1217929Y212455D03*
X1222738Y228631D03*
X1208797Y281307D03*
X1211892Y339559D03*
X1213173Y377912D03*
Y386500D03*
X1209872Y382047D03*
X1212173Y391496D03*
X1213261Y397912D03*
X1210173Y403500D03*
X1212173Y409000D03*
X1212598Y1112598D03*
X1223818Y1142519D03*
X1210623Y1178467D03*
X1210185Y1185514D03*
X1230924Y86012D03*
X1238479Y102249D03*
X1227017Y94279D03*
X1232204Y110784D03*
X1237204D03*
X1236783Y124663D03*
X1226695Y124283D03*
X1231761Y124879D03*
X1238127Y138838D03*
X1239579Y195176D03*
X1236398Y201683D03*
X1226469Y208864D03*
X1239465Y244571D03*
X1236845Y249108D03*
X1229252Y314890D03*
X1226436Y324518D03*
X1235589Y348015D03*
X1229942Y347937D03*
X1227159Y432124D03*
X1232773Y456559D03*
X1256307Y103411D03*
X1247847Y97667D03*
X1256701D03*
X1241764Y125107D03*
X1250378Y143762D03*
X1244278Y148717D03*
X1253844Y199248D03*
X1246826Y198733D03*
X1248599Y230556D03*
X1252854Y227824D03*
X1243858Y228646D03*
X1246808Y256394D03*
X1241205Y303962D03*
X1252330Y456005D03*
X1254200Y1146600D03*
X1256218Y1175987D03*
X1249363Y1166065D03*
X1255628Y1188345D03*
X1246056Y1205107D03*
X1249072Y1224512D03*
X1245413Y1221062D03*
X1245188Y1232283D03*
X1252057Y1233951D03*
X1254275Y1531334D03*
X1249894Y1527805D03*
X1254275Y1539334D03*
X1250434Y1535334D03*
X1267497Y90650D03*
X1257444Y230117D03*
X1266616Y322456D03*
X1263500Y336000D03*
X1263484Y385644D03*
X1268659Y385123D03*
X1268067Y406060D03*
X1261231Y399918D03*
X1260818Y418996D03*
X1260563Y431730D03*
X1267540Y459330D03*
X1267493Y454214D03*
X1267836Y449045D03*
X1270586Y905324D03*
X1272661Y929858D03*
X1266718Y1142666D03*
X1268593Y1157544D03*
X1267104Y1167768D03*
X1272123D03*
X1271256Y1185205D03*
X1262605Y1187215D03*
X1262298Y1180175D03*
X1260800Y1191096D03*
X1262421Y1195059D03*
X1258237Y1203115D03*
X1273370Y1197626D03*
X1259480Y1221197D03*
X1257348Y1237535D03*
X1269491Y1228760D03*
X1267333Y1531334D03*
X1262891Y1527334D03*
X1267183Y1539334D03*
X1262891Y1535334D03*
X1286088Y92874D03*
X1277130Y99961D03*
X1280539Y169454D03*
X1288039D03*
X1286448Y223661D03*
X1289345Y330655D03*
X1287437Y370010D03*
Y379429D03*
X1273659Y385123D03*
X1280659D03*
X1284333Y391569D03*
X1282760Y409016D03*
X1281737Y461034D03*
Y456034D03*
X1284900Y678800D03*
X1278255Y722241D03*
X1282539Y746076D03*
Y756076D03*
X1279539Y776576D03*
X1281777Y823500D03*
X1285500Y843500D03*
X1281269Y835492D03*
X1285500Y851500D03*
X1279460Y854487D03*
Y859487D03*
Y864487D03*
Y874487D03*
Y879487D03*
X1274264Y898591D03*
X1279460Y884487D03*
X1279299Y898813D03*
X1279460Y889487D03*
X1288500Y904120D03*
X1274400Y914123D03*
X1283493Y929858D03*
X1279693Y919800D03*
X1274670Y919808D03*
X1289547Y941000D03*
X1275050Y1157404D03*
X1275965Y1187232D03*
X1280602Y1185238D03*
X1280395Y1180235D03*
X1275032Y1209589D03*
X1302139Y26325D03*
X1290973Y78245D03*
X1298473D03*
X1304923Y97475D03*
X1301761Y177616D03*
X1302342Y172190D03*
X1296198Y188727D03*
X1293320Y208695D03*
X1292955Y226141D03*
X1296697Y265701D03*
X1301784Y265896D03*
X1304273Y281982D03*
X1298332Y281716D03*
X1305078Y290755D03*
X1292500Y335000D03*
X1299959Y356954D03*
X1299410Y370976D03*
X1293048Y379088D03*
X1298346Y379028D03*
X1293100Y406739D03*
X1299867Y477318D03*
X1299466Y466409D03*
X1299807Y472020D03*
X1299304Y487382D03*
X1301194Y565518D03*
X1305836Y660009D03*
X1298963Y659609D03*
X1289811Y677612D03*
X1303520Y748403D03*
X1291604Y781576D03*
Y776576D03*
Y771435D03*
X1298720Y798975D03*
X1302140Y812625D03*
X1302501Y824747D03*
X1297667Y832150D03*
X1293500Y827500D03*
Y843500D03*
Y835500D03*
X1296687Y839500D03*
X1303628Y841054D03*
X1293500Y851500D03*
X1294000Y863500D03*
X1304050Y874900D03*
X1305250Y889250D03*
X1304000Y884000D03*
X1291129Y892267D03*
X1299895Y896545D03*
X1296466Y903469D03*
X1304949Y928546D03*
X1295453Y928047D03*
X1291059Y917000D03*
X1302000D03*
X1300882Y937144D03*
X1297558Y970216D03*
X1296787Y1291220D03*
X1301769Y1295154D03*
X1314887Y45448D03*
X1311904Y100625D03*
X1320566Y103621D03*
X1319912Y183834D03*
X1314627Y171523D03*
X1320085Y172665D03*
X1320022Y178560D03*
X1314157Y192490D03*
X1320202Y200864D03*
X1320225Y207037D03*
X1320291Y212455D03*
X1309357Y231021D03*
X1306800Y266114D03*
X1311159Y281307D03*
X1313103Y339606D03*
X1312240Y334681D03*
X1308012Y348109D03*
X1320925Y356636D03*
X1315807Y353785D03*
X1308410Y379591D03*
X1310546Y407104D03*
X1308066Y413611D03*
X1308006Y423944D03*
X1307819Y474382D03*
X1319474Y467560D03*
X1319974Y475560D03*
X1319323Y598454D03*
X1319000Y641000D03*
X1313979Y677726D03*
X1319000Y685500D03*
X1321000Y796000D03*
X1313000D03*
X1317000Y799000D03*
X1315000Y811620D03*
X1321000Y804000D03*
X1321972Y825042D03*
X1317276Y826776D03*
X1311277Y837557D03*
X1312359Y845788D03*
X1315104Y852201D03*
X1310678Y856981D03*
X1310125Y863849D03*
X1307500Y880000D03*
X1314641Y874641D03*
X1315603Y889517D03*
X1314500Y911500D03*
Y905000D03*
X1309103Y917000D03*
X1313152Y936605D03*
X1312575Y943974D03*
X1321256Y943815D03*
X1307000Y960500D03*
X1315441Y960000D03*
X1311000Y970124D03*
X1307707Y979870D03*
X1307561Y986951D03*
X1315756Y1039344D03*
X1306385Y1036646D03*
X1319237Y1225428D03*
X1306805Y1279545D03*
X1318287Y1291381D03*
X1324120Y22742D03*
X1328003Y32403D03*
X1328318Y27333D03*
X1336623Y30483D03*
X1328831Y208864D03*
X1325100Y228631D03*
X1322547Y323226D03*
X1332359Y322685D03*
X1331922Y359836D03*
X1335440Y452799D03*
X1329083Y448931D03*
X1332974Y474513D03*
X1326993Y556788D03*
X1327043Y573346D03*
X1327000Y562500D03*
X1326946Y567906D03*
X1338000Y562500D03*
X1335000Y590500D03*
X1327000Y578500D03*
Y583826D03*
Y605000D03*
Y594500D03*
X1333224Y615484D03*
X1327000Y613000D03*
X1335532Y622260D03*
X1338000Y609000D03*
X1335000Y633000D03*
X1327000Y629000D03*
X1327003Y623940D03*
X1338000Y653500D03*
X1327000Y641000D03*
Y657500D03*
Y685500D03*
Y695500D03*
Y700500D03*
X1338000D03*
X1327000Y711500D03*
Y716500D03*
Y732500D03*
X1330295Y746328D03*
X1336661Y753675D03*
Y745675D03*
Y737675D03*
X1330295Y751328D03*
X1330086Y763758D03*
X1324217Y780595D03*
X1336746Y781675D03*
X1329000Y796000D03*
X1325000Y799000D03*
X1337000Y796000D03*
X1333000Y799000D03*
X1330850Y830350D03*
X1331877Y825377D03*
X1337463Y824038D03*
X1326288Y864602D03*
X1332203Y864566D03*
X1323549Y897045D03*
X1336096Y905042D03*
X1338500Y913000D03*
X1326500Y925500D03*
X1333132Y933781D03*
X1336000Y943500D03*
X1323000Y934075D03*
X1326500Y943500D03*
X1325550Y960445D03*
X1334161Y1098518D03*
X1337514Y1104335D03*
X1331237Y1229428D03*
X1335237Y1237428D03*
X1323237D03*
X1332907Y1278568D03*
X1336936Y1278376D03*
X1328903Y1278838D03*
X1351559Y143740D03*
X1348939Y148277D03*
X1344007Y279054D03*
X1347990Y322539D03*
X1341169Y325926D03*
X1349636Y340862D03*
X1346510Y355658D03*
X1349763Y371908D03*
X1346443Y431112D03*
X1352008Y435101D03*
X1352271Y442114D03*
X1346613Y440101D03*
X1352251Y447121D03*
X1346248Y452718D03*
X1340820Y452987D03*
X1352259Y452601D03*
X1346738Y564492D03*
X1339289Y568461D03*
X1342053Y579339D03*
X1346533Y576780D03*
X1340522Y586133D03*
X1343000Y590458D03*
X1346533Y581898D03*
X1344129Y606914D03*
X1344433Y601201D03*
X1339289Y614961D03*
X1344680Y619085D03*
X1346738Y611192D03*
X1346533Y628398D03*
X1342053Y625839D03*
X1340522Y632633D03*
X1343000Y636958D03*
X1346738Y655492D03*
X1339289Y659461D03*
X1346533Y667780D03*
X1342053Y670339D03*
X1346533Y672898D03*
X1340522Y677133D03*
X1343000Y681458D03*
X1350929Y687043D03*
X1340299Y686243D03*
X1346738Y702492D03*
X1346533Y719898D03*
X1339289Y706461D03*
X1342053Y717339D03*
X1346533Y714780D03*
X1340522Y724133D03*
X1343000Y728458D03*
X1344768Y769675D03*
X1345226Y777675D03*
X1341000Y799000D03*
X1345000Y796000D03*
X1348917D03*
X1352817D03*
X1348000Y832000D03*
X1344000Y825500D03*
X1353000Y824000D03*
X1341500Y831000D03*
X1348275Y849171D03*
X1348170Y880104D03*
X1348134Y896278D03*
X1343500Y911000D03*
X1348500Y913500D03*
X1353948Y943603D03*
X1345948D03*
X1349848Y936755D03*
X1343237Y1241428D03*
X1351876Y1260160D03*
X1341226Y1278592D03*
X1346362Y1278700D03*
X1351673D03*
X1360122Y141247D03*
X1364609Y143518D03*
X1363709Y152373D03*
X1355255Y561032D03*
Y652032D03*
X1367000Y811620D03*
X1365000Y804000D03*
X1355000Y811620D03*
X1360000Y824500D03*
X1369000D03*
X1361500Y831500D03*
X1355000Y829500D03*
X1356141Y910359D03*
X1362510Y912490D03*
X1368155Y912270D03*
X1361000Y904000D03*
X1365948Y939475D03*
X1357948Y938842D03*
X1361948Y943603D03*
X1369948D03*
X1365049Y1028416D03*
X1369765Y1015825D03*
X1365314Y1021793D03*
X1366265Y1039880D03*
X1366289Y1098518D03*
X1369642Y1104335D03*
X1360876Y1260160D03*
X1362308Y1278862D03*
X1367828D03*
X1356856D03*
X1382205Y110784D03*
X1387205D03*
X1386784Y124663D03*
X1376696Y124283D03*
X1381762Y124879D03*
X1386399Y201683D03*
X1381519Y218085D03*
X1386846Y249108D03*
X1383634Y342766D03*
X1384265Y334371D03*
Y352371D03*
X1383963Y366675D03*
X1375108Y420838D03*
X1383343Y508228D03*
X1383907Y516591D03*
X1383556Y554388D03*
X1378415Y558795D03*
Y563984D03*
Y569776D03*
X1378957Y584457D03*
X1382997Y581317D03*
X1383425Y593575D03*
X1378415Y605295D03*
Y610484D03*
Y616276D03*
X1384657Y631620D03*
X1378957Y627988D03*
X1378415Y649795D03*
Y654984D03*
Y660776D03*
X1386289Y672488D03*
X1378957Y675457D03*
X1378415Y696795D03*
Y701984D03*
X1378957Y719488D03*
X1378415Y707776D03*
X1385290Y722400D03*
X1381000Y804000D03*
X1385360Y811757D03*
X1375480Y824745D03*
X1381481Y825415D03*
X1386287Y836500D03*
X1384147Y855177D03*
X1378490Y864853D03*
X1385361Y875675D03*
X1385933Y886594D03*
X1386747Y896548D03*
X1377500Y904000D03*
X1382500Y907500D03*
X1380000Y912500D03*
X1372600Y906458D03*
X1374500Y912000D03*
X1378500Y925500D03*
X1382775Y930281D03*
X1373948Y940103D03*
X1373534Y996755D03*
X1381519Y996280D03*
X1373534Y1012325D03*
X1378938Y1000586D03*
X1374059Y1018860D03*
X1379065Y1019069D03*
X1378559Y1038534D03*
X1384784Y1033783D03*
X1385929Y1038665D03*
X1373874Y1032266D03*
X1385152Y1046591D03*
X1384667Y1223783D03*
X1382078Y1238778D03*
X1380855Y1230148D03*
X1380936Y1270898D03*
X1386122Y1270954D03*
X1373032Y1278566D03*
X1388480Y102249D03*
X1397848Y97667D03*
X1391765Y125107D03*
X1400379Y143762D03*
X1394279Y148717D03*
X1388128Y138838D03*
X1389580Y195176D03*
X1396827Y198733D03*
X1402855Y227824D03*
X1398600Y230556D03*
X1393859Y228646D03*
X1389466Y244571D03*
X1396809Y256394D03*
X1395726Y320529D03*
X1395568Y325529D03*
X1395726Y330529D03*
X1395736Y335529D03*
X1395726Y340529D03*
Y345529D03*
Y360529D03*
Y350529D03*
Y355529D03*
X1391896Y365529D03*
X1399884Y367165D03*
X1389557Y424678D03*
X1390271Y417578D03*
X1403085Y460565D03*
X1397079Y531726D03*
Y544726D03*
X1390741Y561000D03*
Y569000D03*
X1397000Y652000D03*
Y660000D03*
Y699000D03*
Y707000D03*
X1391040Y812027D03*
X1398530Y811717D03*
X1402417Y811692D03*
X1400069Y827515D03*
X1401300Y820485D03*
X1402000Y840000D03*
Y848000D03*
X1389404Y847052D03*
X1402000Y864000D03*
Y876000D03*
Y884000D03*
Y892000D03*
X1391764Y887128D03*
X1402000Y900000D03*
X1387520Y905307D03*
X1387753Y912629D03*
X1394891Y914783D03*
X1402187Y908270D03*
X1396869Y958707D03*
X1402064Y965913D03*
X1389192Y992568D03*
X1394885Y999941D03*
X1392031Y1004375D03*
X1390459Y1017180D03*
X1388128Y1027202D03*
X1402809Y1024184D03*
X1389762Y1043055D03*
X1393909Y1032551D03*
X1399807Y1036155D03*
X1392086Y1092743D03*
X1399748Y1098518D03*
X1403101Y1104335D03*
X1396296Y1270918D03*
X1401428D03*
X1391272Y1270920D03*
X1389052Y1303139D03*
X1406308Y103411D03*
X1406702Y97667D03*
X1417498Y90650D03*
X1403845Y199248D03*
X1407445Y230117D03*
X1408854Y381207D03*
X1408254Y398041D03*
X1407844Y411033D03*
X1415674Y421278D03*
X1417856Y448419D03*
X1410903Y470419D03*
Y461919D03*
X1418903Y461419D03*
X1415623Y492268D03*
X1415823Y482165D03*
X1415064Y500202D03*
X1416413Y495649D03*
X1405992Y534909D03*
X1405619Y541135D03*
X1405685Y546553D03*
X1405708Y552726D03*
X1411622Y610548D03*
X1407566Y622285D03*
X1407754Y616905D03*
X1418439Y633736D03*
X1407952Y633724D03*
X1413432Y633716D03*
X1407835Y627713D03*
X1413452Y641817D03*
X1418000Y696000D03*
Y701000D03*
Y717000D03*
X1410000D03*
X1418000Y724000D03*
Y729000D03*
X1404249Y735858D03*
X1418000Y740000D03*
Y745000D03*
X1407482Y750853D03*
X1418000Y761000D03*
X1406867Y783273D03*
X1409115Y773520D03*
X1414597Y792375D03*
X1406483Y811717D03*
X1413449Y823934D03*
X1405402Y819917D03*
X1405500Y844000D03*
Y836000D03*
Y860000D03*
Y880000D03*
Y868000D03*
X1413500Y876000D03*
X1417797Y879501D03*
X1405500Y888000D03*
Y896000D03*
X1417081D03*
X1413500Y892000D03*
Y884000D03*
X1405500Y904000D03*
X1404760Y915186D03*
X1419337Y942285D03*
X1419446Y977192D03*
X1405090Y981903D03*
X1412698Y997590D03*
X1412609Y1008766D03*
X1412759Y1016266D03*
X1416736Y1242194D03*
X1417711Y1301729D03*
X1409900Y1442356D03*
X1422810Y90615D03*
X1427131Y99961D03*
X1430540Y169454D03*
X1434166Y325361D03*
X1434164Y339232D03*
X1434038Y334114D03*
X1435818Y352361D03*
X1434997Y442603D03*
X1427117Y443071D03*
X1432414Y459371D03*
X1427484Y462004D03*
X1427800Y528578D03*
X1421099Y546830D03*
X1435390Y544895D03*
X1435119Y590801D03*
X1434944Y597130D03*
X1420452Y628078D03*
X1430175Y627852D03*
X1425452Y633473D03*
X1433529Y660564D03*
X1426615Y674112D03*
X1429000Y685000D03*
X1425909Y691120D03*
X1433464Y692658D03*
X1433053Y701839D03*
X1431522Y708633D03*
X1434000Y712958D03*
X1430289Y734961D03*
X1429000Y729000D03*
X1434000Y751958D03*
X1433153Y745839D03*
X1435000Y765500D03*
X1434000Y756958D03*
X1435000Y770500D03*
Y802500D03*
Y814500D03*
Y809500D03*
X1434975Y830500D03*
X1435000Y825500D03*
Y846500D03*
X1427000D03*
X1435043Y874694D03*
X1435082Y869475D03*
X1430217Y880162D03*
X1434858Y887763D03*
X1423190Y905295D03*
X1429907Y936998D03*
X1424897Y936777D03*
X1435516Y936000D03*
X1430839Y965546D03*
X1435229Y1104335D03*
X1420736Y1226194D03*
X1424736Y1238194D03*
X1432736Y1230194D03*
X1421964Y1502813D03*
X1442656Y76899D03*
X1450156D03*
X1436089Y92874D03*
X1451301Y148277D03*
X1438040Y169454D03*
X1451762Y177616D03*
X1446199Y188727D03*
X1443321Y208695D03*
X1442956Y226141D03*
X1436449Y223661D03*
X1451785Y265896D03*
X1446698Y265701D03*
X1448333Y281716D03*
X1449060Y329861D03*
Y320861D03*
X1438829Y329861D03*
X1437064Y320861D03*
X1448500Y340575D03*
X1439712Y336673D03*
X1440420Y346833D03*
X1441180Y354909D03*
X1448572Y349441D03*
X1443041Y363648D03*
X1442633Y371502D03*
X1440523Y382747D03*
X1436930Y461818D03*
X1439462Y529929D03*
X1449393Y566797D03*
X1449993Y578405D03*
X1443775Y596089D03*
X1448994Y596782D03*
X1437770Y628242D03*
X1437738Y686992D03*
X1451976Y693844D03*
X1437533Y704398D03*
Y699280D03*
X1438930Y716363D03*
X1446860Y730735D03*
X1437738Y730992D03*
X1437533Y743280D03*
Y748398D03*
X1447289Y776461D03*
X1446000Y770500D03*
X1451000Y793458D03*
Y798458D03*
X1450253Y787339D03*
X1447000Y810500D03*
Y818500D03*
X1448000Y834500D03*
X1449000Y844500D03*
X1448581Y924436D03*
X1448743Y935588D03*
X1441088Y976409D03*
X1440700Y981763D03*
X1440869Y1010256D03*
X1447361Y1273222D03*
X1457347Y31518D03*
X1457829Y26425D03*
X1461905Y100625D03*
X1454924Y97475D03*
X1462484Y141247D03*
X1466971Y143518D03*
X1453921Y143740D03*
X1466071Y152373D03*
X1452343Y172190D03*
X1464158Y192490D03*
X1456801Y266114D03*
X1461160Y281307D03*
X1454274Y281982D03*
X1455079Y290755D03*
X1463145Y391579D03*
X1456958Y556317D03*
X1459146Y565573D03*
X1455419Y578986D03*
X1454944Y596729D03*
X1461474Y655807D03*
X1468372Y673812D03*
X1454504Y777575D03*
X1454533Y784780D03*
X1454738Y772492D03*
X1454533Y789898D03*
X1453102Y821102D03*
X1454541Y831339D03*
X1453102Y826500D03*
X1452619Y836457D03*
X1457174Y874859D03*
X1461113Y871389D03*
X1462391Y892822D03*
X1462500Y905295D03*
X1467508Y905405D03*
X1458202Y960288D03*
X1457937Y966712D03*
X1467096Y988813D03*
X1458892Y1007522D03*
X1465658Y1006648D03*
X1463025Y1018307D03*
X1459267Y1013678D03*
X1456280Y1023405D03*
X1459683Y1028377D03*
X1452784Y1289102D03*
X1457794Y1292726D03*
X1474746Y60513D03*
X1474874Y85731D03*
X1483287Y86012D03*
X1479380Y94279D03*
X1470567Y103621D03*
X1484567Y110784D03*
X1479058Y124283D03*
X1484124Y124879D03*
X1469913Y183834D03*
X1470023Y178560D03*
X1470086Y172665D03*
X1469433Y190185D03*
X1478800Y196665D03*
X1470203Y200864D03*
X1470292Y212455D03*
X1470226Y207037D03*
X1475101Y228631D03*
X1475264Y680933D03*
X1476716Y704398D03*
X1479500Y689630D03*
Y697630D03*
X1479759Y720885D03*
X1469957Y706957D03*
X1479794Y709388D03*
X1472000Y727500D03*
X1480000Y731500D03*
X1476716Y748398D03*
X1480000Y739500D03*
X1471006Y744818D03*
X1470801Y739280D03*
X1479665Y754555D03*
X1474883Y868206D03*
X1473387Y897425D03*
X1482195Y885807D03*
X1472000Y929500D03*
X1472500Y935324D03*
X1480144Y946880D03*
X1480414Y952214D03*
X1479196Y970000D03*
X1480414Y975064D03*
X1475096Y988813D03*
X1483096D03*
X1482535Y1024254D03*
X1471854Y1035088D03*
X1474384Y1165091D03*
X1480675Y1202103D03*
X1483308Y1214372D03*
X1479063Y1218169D03*
X1489556Y17645D03*
X1489829Y29424D03*
X1490563Y23043D03*
X1490842Y102249D03*
X1500210Y97667D03*
X1489567Y110784D03*
X1494127Y125107D03*
X1489146Y124663D03*
X1496641Y148717D03*
X1490490Y138838D03*
X1491942Y195176D03*
X1499189Y198733D03*
X1488761Y201683D03*
X1496221Y228646D03*
X1491828Y244571D03*
X1489208Y249108D03*
X1499171Y256394D03*
X1486860Y327200D03*
X1500659Y330024D03*
X1495605Y322700D03*
X1487318Y318200D03*
X1500386Y344642D03*
X1486913Y340327D03*
X1495689Y332534D03*
X1495521Y340700D03*
Y349681D03*
X1495925Y358700D03*
X1499839Y354001D03*
X1486890Y368576D03*
X1488799Y547918D03*
X1488731Y739500D03*
X1496629Y765000D03*
X1493301Y776911D03*
X1496814Y773000D03*
X1497000Y781000D03*
X1499633Y787794D03*
X1493716Y789898D03*
X1495170Y796670D03*
X1487050Y809413D03*
X1496845Y809000D03*
X1496806Y817000D03*
X1486386Y825296D03*
X1493038Y833898D03*
X1495240Y825000D03*
X1500563Y881339D03*
X1500063Y870339D03*
X1494954Y895264D03*
X1500417Y915191D03*
X1484824Y927324D03*
X1490000Y928655D03*
X1485500Y932500D03*
X1498983Y944443D03*
X1495500Y972500D03*
X1489500D03*
X1491096Y988813D03*
X1499096D03*
X1490235Y1004816D03*
X1487266Y1002046D03*
X1495339Y1021954D03*
X1486030Y1016827D03*
X1491877D03*
X1496185Y1102091D03*
Y1114691D03*
Y1127291D03*
Y1139891D03*
Y1152491D03*
Y1165091D03*
Y1177691D03*
X1489793Y1207737D03*
X1497693Y1230407D03*
X1508670Y103411D03*
X1509064Y97667D03*
X1502741Y143762D03*
X1506207Y199248D03*
X1509807Y230117D03*
X1500962Y230556D03*
X1505217Y227824D03*
X1501000Y317500D03*
X1501684Y336561D03*
X1516838Y347422D03*
X1515909Y354601D03*
X1516636Y458711D03*
X1511691Y546805D03*
X1502158Y899479D03*
X1504208Y909740D03*
X1506151Y915726D03*
X1509274Y921226D03*
X1516139Y918399D03*
X1511256Y916334D03*
X1509500Y937000D03*
Y944138D03*
X1516500Y947500D03*
X1504085Y943714D03*
X1501812Y938397D03*
X1509500Y950500D03*
X1507096Y988813D03*
X1515096D03*
X1513286Y1012354D03*
X1507831Y1009354D03*
X1513286Y1024954D03*
X1507831Y1021954D03*
X1501640Y1105091D03*
Y1117691D03*
Y1130291D03*
Y1142891D03*
Y1155491D03*
Y1168091D03*
Y1180691D03*
X1507232Y1214967D03*
X1508356Y1220068D03*
X1511550Y1224260D03*
X1506807Y1234921D03*
X1507058Y1229402D03*
X1525172Y90615D03*
X1519860Y90650D03*
X1529493Y99961D03*
X1532902Y169454D03*
X1519321Y378600D03*
X1532975Y546062D03*
X1519185Y615600D03*
X1520729Y634190D03*
X1529000Y884006D03*
X1525022Y909558D03*
X1526206Y918341D03*
X1521500Y947500D03*
X1528500Y947612D03*
X1529097Y967090D03*
X1517470Y967471D03*
X1531096Y988813D03*
X1523096D03*
X1527096Y997860D03*
X1526810Y1025090D03*
X1522904Y1021256D03*
X1521939Y1040818D03*
X1522099Y1035521D03*
X1531993Y1056453D03*
X1531961Y1050849D03*
X1524953Y1051037D03*
X1527559Y1143390D03*
X1545018Y76899D03*
X1538451Y92874D03*
X1540402Y169454D03*
X1548561Y188727D03*
X1545683Y208695D03*
X1538811Y223661D03*
X1545318Y226141D03*
X1549060Y265701D03*
X1545583Y316363D03*
X1539140Y320863D03*
X1545636Y325363D03*
X1542797Y329863D03*
X1545846Y334363D03*
X1544951Y343363D03*
X1545434Y352363D03*
X1548080Y910757D03*
X1547644Y903060D03*
X1546224Y1142520D03*
X1536909Y1151870D03*
X1538767Y1146271D03*
X1536909Y1159350D03*
X1540649Y1155610D03*
X1538845Y1168638D03*
X1540487Y1163381D03*
X1552518Y76899D03*
X1564267Y100625D03*
X1557286Y97475D03*
X1564846Y141247D03*
X1556283Y143740D03*
X1553663Y148277D03*
X1554705Y172190D03*
X1554124Y177616D03*
X1559163Y266114D03*
X1554147Y265896D03*
X1563522Y281307D03*
X1556636Y281982D03*
X1550695Y281716D03*
X1557441Y290755D03*
X1550931Y305158D03*
X1553534Y327337D03*
X1553597Y336601D03*
X1551175Y347283D03*
X1556588Y545528D03*
X1564670Y650122D03*
X1565132Y668153D03*
Y677843D03*
X1557444Y1135040D03*
X1553738Y1194917D03*
X1564960Y1217322D03*
X1577108Y60513D03*
X1577236Y85731D03*
X1581742Y94279D03*
X1572929Y103621D03*
X1581420Y124283D03*
X1569333Y143518D03*
X1568433Y152373D03*
X1572275Y183834D03*
X1572385Y178560D03*
X1572448Y172665D03*
X1571795Y190185D03*
X1566520Y192490D03*
X1572565Y200864D03*
X1572654Y212455D03*
X1572588Y207037D03*
X1581194Y208864D03*
X1577463Y228631D03*
X1578420Y338309D03*
X1574775Y344127D03*
X1575935Y382109D03*
X1577862Y554121D03*
X1570200Y551040D03*
X1579760Y595500D03*
X1574760Y606929D03*
X1579260Y604567D03*
X1574720Y618400D03*
X1575001Y612592D03*
X1580418Y610072D03*
X1580354Y616317D03*
X1577077Y631712D03*
X1571888Y649380D03*
X1576181Y1217322D03*
X1585649Y86012D03*
X1593204Y102249D03*
X1586929Y110784D03*
X1591929D03*
X1596489Y125107D03*
X1586486Y124879D03*
X1591508Y124663D03*
X1592852Y138838D03*
X1594304Y195176D03*
X1591123Y201683D03*
X1594190Y244571D03*
X1591570Y249108D03*
X1595069Y337361D03*
X1595109Y342663D03*
X1594466Y350984D03*
X1586760Y544000D03*
X1594760Y568000D03*
X1595429Y1055975D03*
X1596261Y1062847D03*
X1583661Y1217322D03*
Y1209842D03*
X1587401Y1213582D03*
X1596790Y1442557D03*
X1596038Y1492000D03*
X1590748Y1523377D03*
X1602572Y97667D03*
X1611032Y103411D03*
X1611426Y97667D03*
X1605103Y143762D03*
X1599003Y148717D03*
X1608569Y199248D03*
X1601551Y198733D03*
X1603324Y230556D03*
X1607579Y227824D03*
X1612169Y230117D03*
X1598583Y228646D03*
X1604677Y253198D03*
X1599527Y404718D03*
Y412718D03*
X1600262Y479577D03*
X1614338Y636842D03*
X1606190Y803774D03*
X1606709Y819165D03*
X1604258Y1058763D03*
X1601581Y1050045D03*
X1611857Y1053324D03*
X1600008Y1488492D03*
X1601500Y1514500D03*
X1608500Y1506000D03*
X1613790Y1531334D03*
X1609348Y1527334D03*
X1613790Y1523334D03*
X1604000Y1519000D03*
X1600732Y1539334D03*
X1609348Y1535334D03*
X1622222Y90650D03*
X1627534Y90615D03*
X1617595Y399648D03*
X1630650Y443035D03*
X1623955Y442956D03*
X1629259Y433003D03*
X1620385Y465874D03*
X1618538Y618288D03*
X1617843Y665140D03*
X1621425Y1055787D03*
X1646707Y76900D03*
X1640813Y92874D03*
X1631855Y99961D03*
X1635264Y169454D03*
X1642764D03*
X1641173Y223661D03*
X1636271Y403307D03*
X1632439Y452265D03*
X1633225Y458455D03*
X1635185Y446595D03*
X1644552Y871353D03*
X1635176Y886761D03*
X1644718Y909263D03*
X1635000Y919263D03*
X1644325Y942120D03*
X1637771Y952120D03*
X1636993Y1064608D03*
X1640581Y1551907D03*
X1654207Y76900D03*
X1659648Y97475D03*
X1658645Y143740D03*
X1656025Y148277D03*
X1656486Y177616D03*
X1657067Y172190D03*
X1650923Y188727D03*
X1648045Y208695D03*
X1647680Y226141D03*
X1656509Y265896D03*
X1661525Y266114D03*
X1651422Y265701D03*
X1653057Y281716D03*
X1658998Y281982D03*
X1659803Y290755D03*
X1649061Y336546D03*
X1659760Y388000D03*
X1650044Y435158D03*
X1649789Y440489D03*
X1653490Y458572D03*
X1647402Y881460D03*
X1647565Y981432D03*
X1662204Y1112598D03*
X1657400Y1128100D03*
X1662204Y1142519D03*
X1658464Y1149999D03*
X1648730Y1163114D03*
X1679470Y60513D03*
X1679598Y85731D03*
X1675291Y103621D03*
X1666629Y100625D03*
X1667208Y141247D03*
X1671695Y143518D03*
X1670795Y152373D03*
X1674637Y183834D03*
X1674810Y172665D03*
X1674747Y178560D03*
X1674157Y190185D03*
X1668882Y192490D03*
X1674927Y200864D03*
X1674950Y207037D03*
X1675016Y212455D03*
X1664082Y231021D03*
X1665884Y281307D03*
X1668979Y339559D03*
X1670260Y377912D03*
X1669260Y391496D03*
X1663618Y393858D03*
X1666959Y382047D03*
X1670260Y386500D03*
X1669260Y409000D03*
X1665260Y398583D03*
X1670348Y397912D03*
X1667260Y403500D03*
X1667815Y1064640D03*
X1667272Y1185514D03*
X1667710Y1178467D03*
X1688011Y86012D03*
X1695566Y102249D03*
X1684104Y94279D03*
X1694291Y110784D03*
X1689291D03*
X1683782Y124283D03*
X1693870Y124663D03*
X1688848Y124879D03*
X1695214Y138838D03*
X1693485Y201683D03*
X1683556Y208864D03*
X1679825Y228631D03*
X1693932Y249108D03*
X1686339Y314890D03*
X1683523Y324518D03*
X1687424Y347937D03*
X1692676Y348015D03*
X1691182Y357016D03*
X1680905Y1142519D03*
X1704934Y97667D03*
X1698851Y125107D03*
X1707465Y143762D03*
X1701365Y148717D03*
X1696666Y195176D03*
X1710931Y199248D03*
X1703913Y198733D03*
X1705686Y230556D03*
X1709941Y228747D03*
X1700945Y228646D03*
X1696552Y244571D03*
X1703895Y256394D03*
X1699205Y368854D03*
X1699391Y433834D03*
X1704945Y442080D03*
X1698716Y550065D03*
X1711333Y1146609D03*
X1706450Y1173065D03*
X1704760Y1202200D03*
X1706159Y1224512D03*
X1702500Y1221062D03*
X1702275Y1232283D03*
X1709144Y1233951D03*
X1713394Y103411D03*
X1713788Y97667D03*
X1724584Y90650D03*
X1714531Y230117D03*
X1720571Y385644D03*
X1725746Y385123D03*
X1718318Y399918D03*
X1725154Y406060D03*
X1717905Y418996D03*
X1717650Y431730D03*
X1724627Y459330D03*
X1724580Y454214D03*
X1724923Y449045D03*
X1723805Y1142666D03*
X1725680Y1157544D03*
X1724191Y1167768D03*
X1713239Y1176038D03*
X1728343Y1185205D03*
X1719692Y1187215D03*
X1719385Y1180175D03*
X1712715Y1188500D03*
X1717406Y1195603D03*
X1715324Y1203115D03*
X1716567Y1221197D03*
X1714435Y1237535D03*
X1726578Y1228760D03*
X1712966Y1229841D03*
X1743175Y92874D03*
X1729896Y90615D03*
X1734217Y99961D03*
X1737626Y169454D03*
X1743535Y223661D03*
X1744524Y379429D03*
X1730746Y385123D03*
X1737746D03*
X1741420Y391569D03*
X1739847Y409016D03*
X1738824Y456034D03*
Y461034D03*
X1739917Y1146937D03*
X1732137Y1157404D03*
X1729210Y1167768D03*
X1733052Y1187310D03*
X1737689Y1185238D03*
X1737482Y1180235D03*
X1730457Y1197626D03*
X1731619Y1210089D03*
X1750752Y82285D03*
X1758252D03*
X1745126Y169454D03*
X1758848Y177616D03*
X1759429Y172190D03*
X1753285Y188727D03*
X1750407Y208695D03*
X1750042Y226141D03*
X1753784Y265701D03*
X1758871Y265896D03*
X1755419Y281716D03*
X1752497Y371076D03*
X1750135Y379088D03*
X1755433Y379028D03*
X1750187Y406739D03*
X1756894Y472020D03*
X1756553Y466409D03*
X1756954Y477318D03*
X1756391Y487382D03*
X1745824Y987058D03*
X1759569Y1021944D03*
X1759947Y1599029D03*
X1750685Y1618504D03*
X1762010Y97475D03*
X1768991Y100625D03*
X1776999Y183834D03*
X1771244Y192490D03*
X1776519Y190185D03*
X1763887Y266114D03*
X1768246Y281307D03*
X1761360Y281982D03*
X1762165Y290755D03*
X1765497Y379591D03*
X1767633Y407104D03*
X1765093Y423944D03*
X1765153Y413611D03*
X1764906Y474382D03*
X1776561Y467560D03*
X1777061Y475560D03*
X1768844Y1023694D03*
X1772188Y1428369D03*
X1766313Y1580198D03*
X1761072Y1590719D03*
X1765040Y1599511D03*
X1764422Y1640303D03*
X1762041Y1631511D03*
X1768422Y1632245D03*
X1773820Y1631238D03*
X1781832Y60513D03*
X1781960Y85731D03*
X1790712Y81713D03*
X1786466Y94279D03*
X1777172Y172665D03*
X1777109Y178560D03*
X1777289Y200864D03*
X1777378Y212455D03*
X1777312Y207037D03*
X1785918Y208864D03*
X1781559Y219379D03*
X1782187Y228631D03*
X1786170Y448931D03*
X1792527Y452799D03*
X1790061Y474513D03*
X1779404Y826570D03*
X1781263Y964660D03*
X1786863Y985060D03*
X1779033Y1023432D03*
X1792613Y1079394D03*
X1781559Y1082075D03*
X1783278Y1208140D03*
X1791099Y1260421D03*
X1787745Y1437765D03*
X1777131Y1604357D03*
X1809095Y435101D03*
X1803700Y440101D03*
X1803530Y431112D03*
X1809358Y442114D03*
X1803335Y452718D03*
X1809346Y452601D03*
X1797907Y452987D03*
X1809338Y447121D03*
X1802363Y989660D03*
X1801961Y1081717D03*
X1795819Y1088553D03*
X1796990Y1134564D03*
X1797924Y1148330D03*
X1796607Y1200108D03*
X1806835Y1214668D03*
X1800489Y1220598D03*
X1807243Y1219955D03*
X1802670Y1210905D03*
X1805126Y1225745D03*
X1795374Y1444543D03*
X1802813Y1464015D03*
X1817439Y447101D03*
X1816756Y1089145D03*
Y1094145D03*
X1816235Y1083970D03*
X1810346Y1082250D03*
X1816756Y1101145D03*
X1810310Y1104819D03*
X1812130Y1205349D03*
X1814741Y1217093D03*
X1812202Y1432624D03*
G54D31*
X51043Y60709D03*
Y150197D03*
X153405Y60709D03*
Y150197D03*
X190325Y455492D03*
Y503760D03*
Y583957D03*
Y636752D03*
X255767Y60709D03*
Y150197D03*
X279360Y368760D03*
Y421555D03*
Y501752D03*
Y550020D03*
X358129Y60709D03*
Y150197D03*
X508130Y60709D03*
Y150197D03*
X610492Y60709D03*
Y150197D03*
X647411Y455492D03*
Y503760D03*
Y583957D03*
Y636752D03*
X712854Y60709D03*
Y150197D03*
X736446Y368760D03*
Y421555D03*
Y501752D03*
Y550020D03*
X815216Y60709D03*
Y150197D03*
X965216Y60709D03*
Y150197D03*
X1067578Y60709D03*
Y150197D03*
X1104498Y455492D03*
Y503760D03*
Y583957D03*
Y636752D03*
X1169940Y60709D03*
Y150197D03*
X1193533Y368760D03*
Y421555D03*
Y501752D03*
Y550020D03*
X1272302Y60709D03*
Y150197D03*
X1422303Y60709D03*
Y150197D03*
X1524665Y60709D03*
Y150197D03*
X1561585Y455492D03*
Y503760D03*
Y583957D03*
Y636752D03*
X1627027Y60709D03*
Y150197D03*
X1650620Y368760D03*
Y421555D03*
Y501752D03*
Y550020D03*
X1729389Y60709D03*
Y150197D03*
G54D116*
G01X146947Y1170570D02*
X145802D01*
X145452Y1170220D01*
Y1169352D01*
X144000Y1167900D01*
X139225D01*
X138900Y1167575D01*
X138813D01*
G01X143207Y1170570D02*
X144352D01*
X144652Y1170270D01*
Y1169684D01*
X143668Y1168700D01*
X139225D01*
X138900Y1169025D01*
X138813D01*
G01X146947Y1178051D02*
X145802D01*
X145452Y1178401D01*
Y1179874D01*
X144626Y1180700D01*
X139525D01*
X139200Y1181025D01*
X139113D01*
G01X143207Y1178051D02*
X144352D01*
X144652Y1178351D01*
Y1179542D01*
X144294Y1179900D01*
X139525D01*
X139200Y1179575D01*
X139113D01*
G01Y1184775D02*
X139200D01*
X139525Y1185100D01*
X156968D01*
X157769Y1184299D01*
Y1176530D01*
X157419Y1176180D01*
X156299D01*
G01X139113Y1186225D02*
X139200D01*
X139525Y1185900D01*
X157300D01*
X158569Y1184631D01*
Y1176530D01*
X158919Y1176180D01*
X160039D01*
G01X1527559D02*
X1528679D01*
X1529029Y1176530D01*
Y1184397D01*
X1528340Y1185086D01*
X1512608D01*
X1512283Y1184761D01*
X1512196D01*
G01X1531299Y1176180D02*
X1530179D01*
X1529829Y1176530D01*
Y1184729D01*
X1528672Y1185886D01*
X1512558D01*
X1512283Y1186161D01*
X1512240D01*
Y1186167D01*
X1512284Y1186211D01*
X1512196D01*
G01X604034Y1178051D02*
X602914D01*
X602564Y1178401D01*
Y1179228D01*
X601413Y1180379D01*
X595842D01*
X595517Y1180704D01*
X595430D01*
G01X600294Y1178051D02*
X601414D01*
X601764Y1178401D01*
Y1178896D01*
X601081Y1179579D01*
X595842D01*
X595517Y1179254D01*
X595430D01*
G01X600294Y1170570D02*
X601439D01*
X601789Y1170220D01*
Y1169510D01*
X600079Y1167800D01*
X598425D01*
X598100Y1168125D01*
X598013D01*
G01X604034Y1170570D02*
X602889D01*
X602589Y1170270D01*
Y1169178D01*
X600411Y1167000D01*
X598425D01*
X598100Y1166675D01*
X598013D01*
G01X887669Y842143D02*
Y841784D01*
X883458Y837573D01*
G01X881645Y878945D02*
X882959Y877631D01*
Y876140D01*
X883872Y875227D01*
X886080D01*
X887669Y873638D01*
G01X877573Y846882D02*
X886109D01*
X887669Y848442D01*
G01X882175Y842006D02*
X883872Y843703D01*
X885172D01*
X886762Y845293D01*
X887669D01*
G01X884519D02*
X882975Y844653D01*
X882055Y843733D01*
X875943D01*
G01X877573Y850032D02*
X889258D01*
X890818Y851592D01*
G01X876269Y853152D02*
X892406D01*
X893967Y851591D01*
G01X884519Y870488D02*
X882959Y868928D01*
X880012D01*
X879864Y869076D01*
G01X884519Y876787D02*
X883854Y878392D01*
X882930Y879316D01*
Y888000D01*
G01X893968Y842143D02*
Y841201D01*
X892408Y839641D01*
Y834455D01*
G01X893968Y845293D02*
X892408Y843733D01*
Y841353D01*
G01X897118Y845293D02*
X895558Y843733D01*
Y839952D01*
G01X889243Y841397D02*
Y843070D01*
X890359Y844186D01*
X890818Y845293D01*
G01X884325Y839742D02*
X886079Y841496D01*
Y842760D01*
X887052Y843733D01*
X888316D01*
X889229Y844646D01*
Y845911D01*
X890171Y846853D01*
X892379D01*
X893968Y848442D01*
G01X890818Y873638D02*
X889258Y875198D01*
Y880584D01*
X889293Y880619D01*
Y882200D01*
G01X895543D02*
Y878362D01*
X893968Y876787D01*
G01X900267Y845293D02*
X898678Y843704D01*
Y840448D01*
X897636Y839406D01*
G01X922313Y867338D02*
X920723Y868928D01*
X918516D01*
X917603Y869841D01*
Y871106D01*
X916631Y872078D01*
X915367D01*
X914424Y873021D01*
Y874285D01*
X913505Y875204D01*
X912240D01*
X911275Y876169D01*
Y877433D01*
X910350Y878358D01*
X905229D01*
G01X916014Y842143D02*
X917055Y841102D01*
Y837659D01*
G01X919163Y845293D02*
X920753Y843703D01*
Y840483D01*
G01X919163Y873638D02*
X920723Y875198D01*
Y887700D01*
G01X919163Y870488D02*
Y871431D01*
X917603Y872991D01*
Y884700D01*
G01X923892Y887200D02*
Y872067D01*
X922313Y870488D01*
G01X912864Y876787D02*
X914428Y878351D01*
Y881600D01*
G01X925462Y864189D02*
X927062Y865789D01*
Y888027D01*
G01X1510513Y1179240D02*
X1510600D01*
X1510925Y1179565D01*
X1515154D01*
X1515962Y1178757D01*
Y1178401D01*
X1515612Y1178051D01*
X1514467D01*
G01X1053289Y1181102D02*
X1053376D01*
X1053701Y1180777D01*
X1058101D01*
X1059650Y1179228D01*
Y1178401D01*
X1060000Y1178051D01*
X1061120D01*
G01X1053289Y1179652D02*
X1053376D01*
X1053701Y1179977D01*
X1057769D01*
X1058850Y1178896D01*
Y1178401D01*
X1058500Y1178051D01*
X1057380D01*
G01X1510513Y1180690D02*
X1510600D01*
X1510925Y1180365D01*
X1515486D01*
X1516762Y1179089D01*
Y1178351D01*
X1517062Y1178051D01*
X1518207D01*
G01X1061120Y1170570D02*
X1060000D01*
X1059650Y1170920D01*
Y1171747D01*
X1058583Y1172814D01*
X1053375D01*
X1052876Y1172315D01*
X1052416D01*
X1052355Y1172254D01*
G01X1057380Y1170570D02*
X1058500D01*
X1058850Y1170920D01*
Y1171415D01*
X1058251Y1172014D01*
X1053707D01*
X1053442Y1171749D01*
Y1171289D01*
X1053381Y1171228D01*
G01X1518207Y1170570D02*
X1517062D01*
X1516762Y1170270D01*
Y1169393D01*
X1515669Y1168300D01*
X1511025D01*
X1510700Y1167975D01*
X1510613D01*
G01X1514467Y1170570D02*
X1515612D01*
X1515962Y1170220D01*
Y1169725D01*
X1515337Y1169100D01*
X1511025D01*
X1510700Y1169425D01*
X1510613D01*
G01X1321644Y894551D02*
Y891071D01*
X1320285Y889712D01*
X1320055D01*
G01X1318390Y872390D02*
X1321629D01*
X1323204Y873965D01*
G01X1351550Y889712D02*
X1349967Y888129D01*
X1341357D01*
X1340524Y888962D01*
Y894087D01*
G01X1313310Y878690D02*
X1321632D01*
X1323205Y880263D01*
G01X1317000Y875540D02*
X1321631D01*
X1323205Y877114D01*
G01X1313000Y881839D02*
X1321631D01*
X1323205Y883413D01*
G01X1335803Y839320D02*
X1334229Y837746D01*
Y833729D01*
G01X1334800Y828300D02*
X1336800D01*
X1337378Y828878D01*
Y837745D01*
X1338952Y839319D01*
G01X1327930Y831000D02*
Y837746D01*
X1329504Y839320D01*
G01X1323204Y889713D02*
Y889899D01*
X1324778Y891473D01*
Y895816D01*
G01X1338953Y886562D02*
X1337384Y888131D01*
Y897337D01*
G01X1338953Y842470D02*
X1340535Y840888D01*
Y835200D01*
G01X1345252Y889712D02*
X1343674Y891290D01*
Y895474D01*
G01X1356274Y895400D02*
Y891287D01*
X1354699Y889712D01*
G01X1364148Y842470D02*
X1365730Y840888D01*
Y827770D01*
G01X1360999Y842470D02*
X1359426Y840897D01*
Y833574D01*
G01X1353137Y834400D02*
Y837758D01*
X1354699Y839320D01*
G01X1364148Y889712D02*
X1362566Y891294D01*
Y897934D01*
G01X1373598Y839319D02*
X1372028Y837749D01*
Y829700D01*
X1372914Y828814D01*
G01X1375172Y894600D02*
Y891287D01*
X1373598Y889713D01*
G01X1376747Y889712D02*
X1378317Y891282D01*
Y894670D01*
G01X1370447Y889712D02*
X1372022Y891287D01*
Y894500D01*
G54D23*
X23622Y1604724D03*
X62205Y765197D03*
X74016Y333464D03*
X102224Y70866D03*
X409488Y1604724D03*
X433130Y70866D03*
X463387Y286221D03*
X463386Y765197D03*
X661674Y23622D03*
X785039Y1547638D03*
X890217Y23622D03*
X920473Y765196D03*
X1055905Y1547637D03*
X1118760Y23622D03*
X1347303Y70866D03*
X1377559Y286220D03*
Y765197D03*
X1431457Y1604724D03*
X1575846Y23622D03*
X1766929Y333464D03*
X1778740Y765197D03*
X1795010Y23622D03*
X1817323Y1604724D03*
G54D107*
X1803917Y823898D03*
G54D50*
X195570Y1156430D03*
X191830D03*
X188090Y1144389D03*
Y1146489D03*
Y1151870D03*
Y1153970D03*
X195570Y1158530D03*
X188090Y1159050D03*
Y1156950D03*
X191830Y1158530D03*
X188090Y1172210D03*
Y1161850D03*
Y1163950D03*
X195570Y1171390D03*
X188090Y1168930D03*
Y1166830D03*
X191830Y1171390D03*
X188090Y1174310D03*
X195570Y1173490D03*
X191830D03*
X188100Y1185300D03*
Y1183200D03*
Y1178250D03*
Y1180350D03*
X197500Y1188451D03*
Y1186351D03*
X212401Y1133989D03*
Y1136089D03*
X204921Y1133989D03*
Y1136089D03*
X201181Y1133989D03*
Y1136089D03*
X203051Y1126508D03*
Y1128608D03*
X206791Y1126508D03*
Y1128608D03*
X214271Y1126508D03*
Y1128608D03*
X210531Y1126508D03*
Y1128608D03*
X208661Y1133989D03*
Y1136089D03*
X199311Y1126508D03*
Y1128608D03*
X208661Y1141469D03*
Y1143569D03*
X201181Y1141469D03*
Y1143569D03*
X204921Y1141469D03*
Y1143569D03*
X212401Y1141469D03*
Y1143569D03*
X199311Y1156430D03*
X208661Y1148949D03*
Y1151049D03*
X204921Y1148949D03*
Y1151049D03*
X201181Y1148949D03*
Y1151049D03*
X212401Y1148949D03*
Y1151049D03*
X210531Y1156430D03*
X214271D03*
X203051D03*
X206791D03*
X199311Y1158530D03*
X210531D03*
X214271D03*
X203051D03*
X206791D03*
X203051Y1171390D03*
X199311D03*
X206791D03*
X210531D03*
X214271D03*
X203051Y1173490D03*
X199311D03*
X206791D03*
X210531D03*
X214271D03*
X212401Y1188451D03*
Y1186351D03*
Y1180971D03*
Y1178871D03*
X208661Y1188451D03*
Y1186351D03*
Y1180971D03*
Y1178871D03*
X204921Y1180971D03*
Y1178871D03*
Y1188451D03*
Y1186351D03*
X201181Y1188451D03*
Y1186351D03*
Y1180971D03*
Y1178871D03*
X210315Y1203412D03*
Y1201312D03*
X202835Y1203412D03*
Y1201312D03*
X206575Y1203412D03*
Y1201312D03*
X214055Y1203412D03*
Y1201312D03*
X212401Y1195931D03*
Y1193831D03*
X208661Y1195931D03*
Y1193831D03*
X201181Y1195931D03*
Y1193831D03*
X204921Y1195931D03*
Y1193831D03*
X199095Y1203412D03*
Y1201312D03*
X231102Y1133989D03*
Y1136089D03*
X219881Y1133989D03*
Y1136089D03*
X229044Y1126508D03*
Y1128608D03*
X221751Y1126508D03*
Y1128608D03*
X225492Y1126508D03*
Y1128608D03*
X227362Y1133989D03*
Y1136089D03*
X223622Y1133989D03*
Y1136089D03*
X216141Y1133989D03*
Y1136089D03*
X218011Y1126508D03*
Y1128608D03*
X231102Y1141469D03*
Y1143569D03*
X227362Y1141469D03*
Y1143569D03*
X219881Y1141469D03*
Y1143569D03*
X223622Y1141469D03*
Y1143569D03*
X231102Y1148949D03*
Y1151049D03*
X219881Y1148949D03*
Y1151049D03*
X227362Y1148949D03*
Y1151049D03*
X223622Y1148949D03*
Y1151049D03*
X221752Y1156430D03*
X229232D03*
X225492D03*
X218011D03*
X216141Y1141469D03*
Y1143569D03*
Y1148949D03*
Y1151049D03*
X221752Y1158530D03*
X229232D03*
X225492D03*
X218011D03*
X229292Y1171390D03*
X225492D03*
X221752D03*
X218011D03*
X229292Y1173490D03*
X225492D03*
X221752D03*
X218011D03*
X223622Y1180971D03*
Y1178871D03*
X219881Y1188451D03*
Y1186351D03*
X223622Y1188451D03*
Y1186351D03*
X231102Y1180971D03*
Y1178871D03*
Y1188451D03*
Y1186351D03*
X227362Y1180971D03*
Y1178871D03*
Y1188451D03*
Y1186351D03*
X219881Y1180971D03*
Y1178871D03*
X216141Y1180971D03*
Y1178871D03*
Y1188451D03*
Y1186351D03*
X229016Y1203412D03*
Y1201312D03*
X231102Y1195931D03*
Y1193831D03*
X223622Y1195931D03*
Y1193831D03*
X227362Y1195931D03*
Y1193831D03*
X219881Y1195931D03*
Y1193831D03*
X225276Y1203412D03*
Y1201312D03*
X221535Y1203412D03*
Y1201312D03*
X217795Y1203412D03*
Y1201312D03*
X216141Y1195931D03*
Y1193831D03*
X238582Y1133989D03*
Y1136089D03*
X246062Y1133989D03*
Y1136089D03*
X244192Y1126508D03*
Y1128608D03*
X240452Y1126508D03*
Y1128608D03*
X236844Y1126508D03*
Y1128608D03*
X234842Y1133989D03*
Y1136089D03*
X242322Y1133989D03*
Y1136089D03*
Y1148949D03*
Y1151049D03*
X244192Y1156430D03*
X236712D03*
X240452D03*
X246062Y1148949D03*
Y1151049D03*
X234842Y1148949D03*
Y1151049D03*
X238582Y1148949D03*
Y1151049D03*
X246062Y1141469D03*
Y1143569D03*
X238582Y1141469D03*
Y1143569D03*
X234842Y1141469D03*
Y1143569D03*
X242322Y1141469D03*
Y1143569D03*
X244192Y1158530D03*
X236712D03*
X240452D03*
Y1171390D03*
X244192D03*
X236712D03*
X240452Y1173490D03*
X244192D03*
X236712D03*
X242322Y1180971D03*
Y1178871D03*
Y1188451D03*
Y1186351D03*
X246062Y1188451D03*
Y1186351D03*
X238582Y1180971D03*
Y1178871D03*
X234842Y1188451D03*
Y1186351D03*
X246062Y1180971D03*
Y1178871D03*
X238582Y1188451D03*
Y1186351D03*
X234842Y1180971D03*
Y1178871D03*
X246062Y1195931D03*
Y1193831D03*
X234842Y1195931D03*
Y1193831D03*
X240556Y1203412D03*
Y1201312D03*
X236816Y1203412D03*
Y1201312D03*
X244296Y1203412D03*
Y1201312D03*
X238582Y1195931D03*
Y1193831D03*
X242322Y1195931D03*
Y1193831D03*
X251673Y1126508D03*
Y1128608D03*
X255413Y1126508D03*
Y1128608D03*
X262893Y1126508D03*
Y1128608D03*
X261023Y1133989D03*
Y1136089D03*
X249803Y1133989D03*
Y1136089D03*
X257283Y1133989D03*
Y1136089D03*
X253543Y1133989D03*
Y1136089D03*
X259153Y1126508D03*
Y1128608D03*
X247933Y1126508D03*
Y1128608D03*
X259153Y1156430D03*
X261023Y1148949D03*
Y1151049D03*
X257283Y1148949D03*
Y1151049D03*
X262900Y1156430D03*
X249803Y1148949D03*
Y1151049D03*
X247932Y1156430D03*
X261023Y1141469D03*
Y1143569D03*
X257283Y1141469D03*
Y1143569D03*
X249803Y1141469D03*
Y1143569D03*
X253543Y1141469D03*
Y1143569D03*
Y1148949D03*
Y1151049D03*
X255413Y1156430D03*
X251673D03*
X259153Y1158530D03*
X262900D03*
X251673Y1171390D03*
X262893D03*
X259153D03*
X247933D03*
X255413D03*
X247932Y1158530D03*
X255413D03*
X251673D03*
Y1173490D03*
X262893D03*
X259153D03*
X247933D03*
X255413D03*
X249803Y1180971D03*
Y1178871D03*
Y1188451D03*
Y1186351D03*
X253543Y1180971D03*
Y1178871D03*
Y1188451D03*
Y1186351D03*
X261023Y1188451D03*
Y1186351D03*
X257283Y1188451D03*
Y1186351D03*
X261023Y1180971D03*
Y1178871D03*
X257283Y1180971D03*
Y1178871D03*
X262997Y1203412D03*
Y1201312D03*
X253543Y1195931D03*
Y1193831D03*
X259257Y1203412D03*
Y1201312D03*
X255517Y1203412D03*
Y1201312D03*
X251777Y1203412D03*
Y1201312D03*
X249803Y1195931D03*
Y1193831D03*
X261023Y1195931D03*
Y1193831D03*
X257283Y1195931D03*
Y1193831D03*
X248037Y1203412D03*
Y1201312D03*
X266633Y1126508D03*
Y1128608D03*
X264763Y1133989D03*
Y1136089D03*
Y1148949D03*
Y1151049D03*
Y1141469D03*
Y1143569D03*
Y1188451D03*
Y1186351D03*
Y1180971D03*
Y1178871D03*
Y1195931D03*
Y1193831D03*
X274114Y1196751D03*
Y1198851D03*
X266737Y1203412D03*
Y1201312D03*
X274114Y1204232D03*
Y1202132D03*
X395951Y1213350D03*
Y1215450D03*
X399246Y1213268D03*
Y1215368D03*
X406296Y1214005D03*
Y1216105D03*
X402595Y1213240D03*
Y1215340D03*
X506275Y1214181D03*
Y1216281D03*
X519673Y1214181D03*
Y1216281D03*
X531235Y1214210D03*
Y1216310D03*
X528129Y1214181D03*
Y1216281D03*
X645177Y1145209D03*
Y1147309D03*
Y1152350D03*
Y1154450D03*
X652657Y1156430D03*
X648917D03*
X652657Y1158530D03*
X645177Y1159350D03*
Y1157250D03*
X648917Y1158530D03*
X645177Y1172210D03*
Y1162150D03*
Y1164250D03*
X652657Y1171390D03*
X645177Y1169350D03*
Y1167250D03*
X648917Y1171390D03*
X645177Y1174310D03*
X652657Y1173490D03*
X648917D03*
X645177Y1185531D03*
Y1183431D03*
Y1178051D03*
Y1180151D03*
X658268Y1133989D03*
Y1136089D03*
X667618Y1126508D03*
Y1128608D03*
X663878Y1126508D03*
Y1128608D03*
X660138Y1126508D03*
Y1128608D03*
X665748Y1133989D03*
Y1136089D03*
X662008Y1133989D03*
Y1136089D03*
X669488Y1133989D03*
Y1136089D03*
X656398Y1126508D03*
Y1128608D03*
X665748Y1141469D03*
Y1143569D03*
X658268Y1141469D03*
Y1143569D03*
X662008Y1141469D03*
Y1143569D03*
X669488Y1141469D03*
Y1143569D03*
X656398Y1156430D03*
X663878D03*
X658268Y1148949D03*
Y1151049D03*
X665748Y1148949D03*
Y1151049D03*
X662008Y1148949D03*
Y1151049D03*
X669488Y1148949D03*
Y1151049D03*
X667618Y1156430D03*
X660138D03*
X656398Y1158530D03*
X663878D03*
X667618D03*
X660138D03*
Y1171390D03*
X663878D03*
X656398D03*
X667618D03*
X660138Y1173490D03*
X663878D03*
X656398D03*
X667618D03*
X658268Y1188451D03*
Y1186351D03*
X665748Y1180971D03*
Y1178871D03*
X662008Y1180971D03*
Y1178871D03*
Y1188451D03*
Y1186351D03*
X658268Y1180971D03*
Y1178871D03*
X669488Y1188451D03*
Y1186351D03*
Y1180971D03*
Y1178871D03*
X665748Y1188451D03*
Y1186351D03*
X654587Y1188451D03*
Y1186351D03*
X663878Y1203412D03*
Y1201312D03*
X667618Y1203412D03*
Y1201312D03*
X669488Y1195931D03*
Y1193831D03*
X665748Y1195931D03*
Y1193831D03*
X658268Y1195931D03*
Y1193831D03*
X662008Y1195931D03*
Y1193831D03*
X660138Y1203412D03*
Y1201312D03*
X656398Y1203412D03*
Y1201312D03*
X673228Y1133989D03*
Y1136089D03*
X684449Y1133989D03*
Y1136089D03*
X678838Y1126508D03*
Y1128608D03*
X675098Y1126508D03*
Y1128608D03*
X682579Y1126508D03*
Y1128608D03*
X680709Y1133989D03*
Y1136089D03*
X676968Y1133989D03*
Y1136089D03*
X671358Y1126508D03*
Y1128608D03*
X680709Y1141469D03*
Y1143569D03*
X684449Y1141469D03*
Y1143569D03*
X673228Y1141469D03*
Y1143569D03*
X676968Y1141469D03*
Y1143569D03*
X673228Y1148949D03*
Y1151049D03*
X682579Y1156430D03*
X671358D03*
X675098D03*
X678838D03*
X684449Y1148949D03*
Y1151049D03*
X680709Y1148949D03*
Y1151049D03*
X676968Y1148949D03*
Y1151049D03*
X682579Y1158530D03*
X671358D03*
X675098D03*
X678838D03*
X675098Y1171390D03*
X671358D03*
X682579D03*
X678838D03*
X675098Y1173490D03*
X671358D03*
X682579D03*
X678838D03*
X676968Y1188451D03*
Y1186351D03*
X673228Y1180971D03*
Y1178871D03*
X680709Y1188451D03*
Y1186351D03*
X673228Y1188451D03*
Y1186351D03*
X684449Y1180971D03*
Y1178871D03*
Y1188451D03*
Y1186351D03*
X676968Y1180971D03*
Y1178871D03*
X680709Y1180971D03*
Y1178871D03*
X675098Y1203412D03*
Y1201312D03*
X684449Y1195931D03*
Y1193831D03*
X680709Y1195931D03*
Y1193831D03*
X676968Y1195931D03*
Y1193831D03*
X673228Y1195931D03*
Y1193831D03*
X682579Y1203412D03*
Y1201312D03*
X678838Y1203412D03*
Y1201312D03*
X671358Y1203412D03*
Y1201312D03*
X701279Y1126508D03*
Y1128608D03*
X686131Y1126508D03*
Y1128608D03*
X695669Y1133989D03*
Y1136089D03*
X699409Y1133989D03*
Y1136089D03*
X691929Y1133989D03*
Y1136089D03*
X688189Y1133989D03*
Y1136089D03*
X697539Y1126508D03*
Y1128608D03*
X693931Y1126508D03*
Y1128608D03*
X699409Y1148949D03*
Y1151049D03*
X693799Y1156430D03*
X701279D03*
X697539D03*
X686319D03*
X688189Y1148949D03*
Y1151049D03*
X691929Y1148949D03*
Y1151049D03*
X695669Y1148949D03*
Y1151049D03*
X688189Y1141469D03*
Y1143569D03*
X695669Y1141469D03*
Y1143569D03*
X691929Y1141469D03*
Y1143569D03*
X699409Y1141469D03*
Y1143569D03*
X693799Y1158530D03*
X701279D03*
X697539D03*
X686319D03*
X697539Y1171390D03*
X701279D03*
X693799D03*
X686319D03*
X697539Y1173490D03*
X701279D03*
X693799D03*
X686319D03*
X699409Y1180971D03*
Y1178871D03*
X691929Y1180971D03*
Y1178871D03*
Y1188451D03*
Y1186351D03*
X695669Y1188451D03*
Y1186351D03*
X688189Y1180971D03*
Y1178871D03*
Y1188451D03*
Y1186351D03*
X699409Y1188451D03*
Y1186351D03*
X695669Y1180971D03*
Y1178871D03*
X688189Y1195931D03*
Y1193831D03*
X695669Y1195931D03*
Y1193831D03*
X691929Y1195931D03*
Y1193831D03*
X699409Y1195931D03*
Y1193831D03*
X693903Y1203412D03*
Y1201312D03*
X697539Y1203412D03*
Y1201312D03*
X701279Y1203412D03*
Y1201312D03*
X686103Y1203412D03*
Y1201312D03*
X703149Y1133989D03*
Y1136089D03*
X705020Y1126508D03*
Y1128608D03*
X712500Y1126508D03*
Y1128608D03*
X708760Y1126508D03*
Y1128608D03*
X718110Y1133989D03*
Y1136089D03*
X716240Y1126508D03*
Y1128608D03*
X710630Y1133989D03*
Y1136089D03*
X714370Y1133989D03*
Y1136089D03*
X706890Y1133989D03*
Y1136089D03*
X703149Y1141469D03*
Y1143569D03*
X705020Y1156430D03*
X703149Y1148949D03*
Y1151049D03*
X706890Y1141469D03*
Y1143569D03*
X710630Y1141469D03*
Y1143569D03*
X718110Y1141469D03*
Y1143569D03*
X714370Y1141469D03*
Y1143569D03*
X716240Y1156430D03*
X708760D03*
X712500D03*
X718110Y1148949D03*
Y1151049D03*
X710630Y1148949D03*
Y1151049D03*
X706890Y1148949D03*
Y1151049D03*
X714370Y1148949D03*
Y1151049D03*
X712500Y1171390D03*
X705020Y1158530D03*
X716240D03*
X708760D03*
X712500D03*
X716240Y1171390D03*
X708760D03*
X705020D03*
X712500Y1173490D03*
X706890Y1188451D03*
Y1186351D03*
X718110Y1180971D03*
Y1178871D03*
Y1188451D03*
Y1186351D03*
X714370Y1180971D03*
Y1178871D03*
Y1188451D03*
Y1186351D03*
X710630Y1180971D03*
Y1178871D03*
X706890Y1180971D03*
Y1178871D03*
X710630Y1188451D03*
Y1186351D03*
X703149Y1180971D03*
Y1178871D03*
Y1188451D03*
Y1186351D03*
X716240Y1173490D03*
X708760D03*
X705020D03*
X706890Y1195931D03*
Y1193831D03*
X708760Y1203412D03*
Y1201312D03*
X712500Y1203412D03*
Y1201312D03*
X710630Y1195931D03*
Y1193831D03*
X705020Y1203412D03*
Y1201312D03*
X714370Y1195931D03*
Y1193831D03*
X716240Y1203412D03*
Y1201312D03*
X718110Y1195931D03*
Y1193831D03*
X703149Y1195931D03*
Y1193831D03*
X723720Y1126508D03*
Y1128608D03*
X721850Y1133989D03*
Y1136089D03*
X719980Y1126508D03*
Y1128608D03*
X721850Y1141469D03*
Y1143569D03*
Y1148949D03*
Y1151049D03*
X719980Y1156430D03*
Y1171390D03*
Y1158530D03*
Y1173490D03*
X721850Y1180971D03*
Y1178871D03*
Y1188451D03*
Y1186351D03*
Y1195931D03*
Y1193831D03*
X719980Y1203412D03*
Y1201312D03*
X723720Y1203412D03*
Y1201312D03*
X731201Y1196751D03*
Y1198851D03*
Y1204232D03*
Y1202132D03*
X873257Y1103056D03*
Y1100956D03*
X876877Y1103058D03*
Y1100958D03*
X870004Y1103014D03*
Y1100914D03*
X951421Y1098057D03*
Y1095957D03*
X1106003Y1156430D03*
X1102263Y1151870D03*
Y1153970D03*
Y1144389D03*
Y1146489D03*
X1106003Y1171390D03*
X1102263Y1172210D03*
Y1168930D03*
Y1166830D03*
Y1161850D03*
Y1163950D03*
Y1159050D03*
Y1156950D03*
X1106003Y1158530D03*
X1102273Y1185300D03*
Y1183200D03*
Y1178250D03*
Y1180350D03*
X1106003Y1173490D03*
X1102263Y1174310D03*
X1122834Y1133989D03*
Y1136089D03*
X1119094Y1133989D03*
Y1136089D03*
X1115354Y1133989D03*
Y1136089D03*
X1120964Y1126508D03*
Y1128608D03*
X1117224Y1126508D03*
Y1128608D03*
X1113484Y1126508D03*
Y1128608D03*
X1120964Y1156430D03*
X1117224D03*
X1113484D03*
X1109743D03*
X1122834Y1148949D03*
Y1151049D03*
X1119094Y1148949D03*
Y1151049D03*
X1115354Y1148949D03*
Y1151049D03*
X1122834Y1141469D03*
Y1143569D03*
X1115354Y1141469D03*
Y1143569D03*
X1119094Y1141469D03*
Y1143569D03*
X1120964Y1171390D03*
X1117224D03*
X1113484D03*
X1109743D03*
X1120964Y1158530D03*
X1117224D03*
X1113484D03*
X1109743D03*
X1122834Y1188451D03*
Y1186351D03*
X1119094Y1188451D03*
Y1186351D03*
X1115354Y1188451D03*
Y1186351D03*
X1111673Y1188451D03*
Y1186351D03*
X1122834Y1180971D03*
Y1178871D03*
X1119094Y1180971D03*
Y1178871D03*
X1115354Y1180971D03*
Y1178871D03*
X1120964Y1173490D03*
X1117224D03*
X1113484D03*
X1109743D03*
X1124488Y1203412D03*
Y1201312D03*
X1120748Y1203412D03*
Y1201312D03*
X1117008Y1203412D03*
Y1201312D03*
X1113268Y1203412D03*
Y1201312D03*
X1122834Y1195931D03*
Y1193831D03*
X1119094Y1195931D03*
Y1193831D03*
X1115354Y1195931D03*
Y1193831D03*
X1137795Y1133989D03*
Y1136089D03*
X1134054Y1133989D03*
Y1136089D03*
X1130314Y1133989D03*
Y1136089D03*
X1126574Y1133989D03*
Y1136089D03*
X1139665Y1126508D03*
Y1128608D03*
X1135924Y1126508D03*
Y1128608D03*
X1132184Y1126508D03*
Y1128608D03*
X1128444Y1126508D03*
Y1128608D03*
X1124704Y1126508D03*
Y1128608D03*
X1139665Y1156430D03*
X1135925D03*
X1132184D03*
X1128444D03*
X1124704D03*
X1137795Y1148949D03*
Y1151049D03*
X1134054Y1148949D03*
Y1151049D03*
X1130314Y1148949D03*
Y1151049D03*
X1126574Y1148949D03*
Y1151049D03*
X1137795Y1141469D03*
Y1143569D03*
X1134054Y1141469D03*
Y1143569D03*
X1130314Y1141469D03*
Y1143569D03*
X1126574Y1141469D03*
Y1143569D03*
X1139665Y1171390D03*
X1135925D03*
X1132184D03*
X1128444D03*
X1124704D03*
X1139665Y1158530D03*
X1135925D03*
X1132184D03*
X1128444D03*
X1124704D03*
X1137795Y1188451D03*
Y1186351D03*
X1134054Y1188451D03*
Y1186351D03*
X1130314Y1188451D03*
Y1186351D03*
X1126574Y1188451D03*
Y1186351D03*
X1137795Y1180971D03*
Y1178871D03*
X1134054Y1180971D03*
Y1178871D03*
X1130314Y1180971D03*
Y1178871D03*
X1126574Y1180971D03*
Y1178871D03*
X1139665Y1173490D03*
X1135925D03*
X1132184D03*
X1128444D03*
X1124704D03*
X1139449Y1203412D03*
Y1201312D03*
X1135708Y1203412D03*
Y1201312D03*
X1131968Y1203412D03*
Y1201312D03*
X1128228Y1203412D03*
Y1201312D03*
X1137795Y1195931D03*
Y1193831D03*
X1134054Y1195931D03*
Y1193831D03*
X1130314Y1195931D03*
Y1193831D03*
X1126574Y1195931D03*
Y1193831D03*
X1156495Y1133989D03*
Y1136089D03*
X1152755Y1133989D03*
Y1136089D03*
X1149015Y1133989D03*
Y1136089D03*
X1145275Y1133989D03*
Y1136089D03*
X1141535Y1133989D03*
Y1136089D03*
X1154625Y1126508D03*
Y1128608D03*
X1150885Y1126508D03*
Y1128608D03*
X1143405Y1126508D03*
Y1128608D03*
X1154625Y1156430D03*
X1150885D03*
X1143405D03*
X1156495Y1148949D03*
Y1151049D03*
X1152755Y1148949D03*
Y1151049D03*
X1149015Y1148949D03*
Y1151049D03*
X1145275Y1148949D03*
Y1151049D03*
X1141535Y1148949D03*
Y1151049D03*
X1152755Y1141469D03*
Y1143569D03*
X1156495Y1141469D03*
Y1143569D03*
X1149015Y1141469D03*
Y1143569D03*
X1145275Y1141469D03*
Y1143569D03*
X1141535Y1141469D03*
Y1143569D03*
X1154625Y1171390D03*
X1150885D03*
X1143465D03*
X1154625Y1158530D03*
X1150885D03*
X1143405D03*
X1156495Y1188451D03*
Y1186351D03*
X1152755Y1188451D03*
Y1186351D03*
X1149015Y1188451D03*
Y1186351D03*
X1145275Y1188451D03*
Y1186351D03*
X1141535Y1188451D03*
Y1186351D03*
X1156495Y1180971D03*
Y1178871D03*
X1152755Y1180971D03*
Y1178871D03*
X1149015Y1180971D03*
Y1178871D03*
X1145275Y1180971D03*
Y1178871D03*
X1141535Y1180971D03*
Y1178871D03*
X1154625Y1173490D03*
X1150885D03*
X1143465D03*
X1154729Y1203412D03*
Y1201312D03*
X1150989Y1203412D03*
Y1201312D03*
X1143189Y1203412D03*
Y1201312D03*
X1156495Y1195931D03*
Y1193831D03*
X1152755Y1195931D03*
Y1193831D03*
X1149015Y1195931D03*
Y1193831D03*
X1145275Y1195931D03*
Y1193831D03*
X1141535Y1195931D03*
Y1193831D03*
X1171456Y1133989D03*
Y1136089D03*
X1167716Y1133989D03*
Y1136089D03*
X1163976Y1133989D03*
Y1136089D03*
X1160235Y1133989D03*
Y1136089D03*
X1169586Y1126508D03*
Y1128608D03*
X1165846Y1126508D03*
Y1128608D03*
X1162106Y1126508D03*
Y1128608D03*
X1158365Y1126508D03*
Y1128608D03*
X1169586Y1156430D03*
X1165846D03*
X1162105D03*
X1158365D03*
X1171456Y1148949D03*
Y1151049D03*
X1167716Y1148949D03*
Y1151049D03*
X1163976Y1148949D03*
Y1151049D03*
X1160235Y1148949D03*
Y1151049D03*
X1171456Y1141469D03*
Y1143569D03*
X1167716Y1141469D03*
Y1143569D03*
X1160235Y1141469D03*
Y1143569D03*
X1163976Y1141469D03*
Y1143569D03*
X1169586Y1171390D03*
X1165846D03*
X1162106D03*
X1158365D03*
X1169586Y1158530D03*
X1165846D03*
X1162105D03*
X1158365D03*
X1171456Y1188451D03*
Y1186351D03*
X1167716Y1188451D03*
Y1186351D03*
X1163976Y1188451D03*
Y1186351D03*
X1160235Y1188451D03*
Y1186351D03*
X1171456Y1180971D03*
Y1178871D03*
X1167716Y1180971D03*
Y1178871D03*
X1163976Y1180971D03*
Y1178871D03*
X1160235Y1180971D03*
Y1178871D03*
X1169586Y1173490D03*
X1165846D03*
X1162106D03*
X1158365D03*
X1169690Y1203412D03*
Y1201312D03*
X1165950Y1203412D03*
Y1201312D03*
X1162210Y1203412D03*
Y1201312D03*
X1158469Y1203412D03*
Y1201312D03*
X1171456Y1195931D03*
Y1193831D03*
X1167716Y1195931D03*
Y1193831D03*
X1163976Y1195931D03*
Y1193831D03*
X1160235Y1195931D03*
Y1193831D03*
X1178936Y1133989D03*
Y1136089D03*
X1175196Y1133989D03*
Y1136089D03*
X1180806Y1126508D03*
Y1128608D03*
X1177066Y1126508D03*
Y1128608D03*
X1173326Y1126508D03*
Y1128608D03*
X1177073Y1156430D03*
X1173326D03*
X1178936Y1148949D03*
Y1151049D03*
X1175196Y1148949D03*
Y1151049D03*
X1178936Y1141469D03*
Y1143569D03*
X1175196Y1141469D03*
Y1143569D03*
X1177066Y1171390D03*
X1173326D03*
X1177073Y1158530D03*
X1173326D03*
X1178936Y1188451D03*
Y1186351D03*
X1175196Y1188451D03*
Y1186351D03*
X1178936Y1180971D03*
Y1178871D03*
X1175196Y1180971D03*
Y1178871D03*
X1177066Y1173490D03*
X1173326D03*
X1188287Y1204232D03*
Y1202132D03*
Y1196751D03*
Y1198851D03*
X1180910Y1203412D03*
Y1201312D03*
X1177170Y1203412D03*
Y1201312D03*
X1173430Y1203412D03*
Y1201312D03*
X1178936Y1195931D03*
Y1193831D03*
X1175196Y1195931D03*
Y1193831D03*
X1312962Y1213613D03*
Y1215713D03*
X1310791Y1275725D03*
Y1273625D03*
X1333734Y1214501D03*
Y1216601D03*
X1340056Y1214492D03*
Y1216592D03*
X1336913Y1214487D03*
Y1216587D03*
X1420941Y1214217D03*
Y1216317D03*
X1445901Y1214246D03*
Y1216346D03*
X1442795Y1214217D03*
Y1216317D03*
X1434339Y1214217D03*
Y1216317D03*
X1559350Y1151870D03*
Y1153970D03*
Y1144389D03*
Y1146489D03*
X1563090Y1156430D03*
X1559350Y1172210D03*
Y1168930D03*
Y1166830D03*
Y1161850D03*
Y1163950D03*
Y1159050D03*
Y1156950D03*
X1563090Y1171390D03*
Y1158530D03*
X1559360Y1185300D03*
Y1183200D03*
Y1178250D03*
Y1180350D03*
X1559350Y1174310D03*
X1563090Y1173490D03*
X1570571Y1126508D03*
Y1128608D03*
X1572441Y1133989D03*
Y1136089D03*
X1574311Y1126508D03*
Y1128608D03*
X1578051Y1126508D03*
Y1128608D03*
X1576181Y1133989D03*
Y1136089D03*
X1572441Y1141469D03*
Y1143569D03*
Y1148949D03*
Y1151049D03*
X1566830Y1156430D03*
X1570571D03*
X1576181Y1141469D03*
Y1143569D03*
Y1148949D03*
Y1151049D03*
X1574311Y1156430D03*
X1578051D03*
X1566830Y1171390D03*
X1570571D03*
X1574311D03*
X1578051D03*
X1566830Y1158530D03*
X1570571D03*
X1574311D03*
X1578051D03*
X1572441Y1180971D03*
Y1178871D03*
X1568760Y1188451D03*
Y1186351D03*
X1572441Y1188451D03*
Y1186351D03*
X1576181Y1180971D03*
Y1178871D03*
Y1188451D03*
Y1186351D03*
X1566830Y1173490D03*
X1570571D03*
X1574311D03*
X1578051D03*
X1572441Y1195931D03*
Y1193831D03*
X1570355Y1203412D03*
Y1201312D03*
X1576181Y1195931D03*
Y1193831D03*
X1574095Y1203412D03*
Y1201312D03*
X1577835Y1203412D03*
Y1201312D03*
X1581791Y1126508D03*
Y1128608D03*
X1585531Y1126508D03*
Y1128608D03*
X1589271Y1126508D03*
Y1128608D03*
X1579921Y1133989D03*
Y1136089D03*
X1583661Y1133989D03*
Y1136089D03*
X1587401Y1133989D03*
Y1136089D03*
X1593011Y1126508D03*
Y1128608D03*
X1591141Y1133989D03*
Y1136089D03*
X1594882Y1133989D03*
Y1136089D03*
X1579921Y1141469D03*
Y1143569D03*
X1583661Y1141469D03*
Y1143569D03*
X1587401Y1141469D03*
Y1143569D03*
X1579921Y1148949D03*
Y1151049D03*
X1583661Y1148949D03*
Y1151049D03*
X1587401Y1148949D03*
Y1151049D03*
X1581791Y1156430D03*
X1585531D03*
X1589271D03*
X1591141Y1141469D03*
Y1143569D03*
X1594882Y1141469D03*
Y1143569D03*
X1591141Y1148949D03*
Y1151049D03*
X1594882Y1148949D03*
Y1151049D03*
X1593012Y1156430D03*
X1581791Y1171390D03*
X1585531D03*
X1589271D03*
X1593012D03*
X1581791Y1158530D03*
X1585531D03*
X1589271D03*
X1593012D03*
X1579921Y1180971D03*
Y1178871D03*
X1583661Y1180971D03*
Y1178871D03*
X1587401Y1180971D03*
Y1178871D03*
X1579921Y1188451D03*
Y1186351D03*
X1583661Y1188451D03*
Y1186351D03*
X1587401Y1188451D03*
Y1186351D03*
X1591141Y1180971D03*
Y1178871D03*
X1594882Y1180971D03*
Y1178871D03*
X1591141Y1188451D03*
Y1186351D03*
X1594882Y1188451D03*
Y1186351D03*
X1581791Y1173490D03*
X1585531D03*
X1589271D03*
X1593012D03*
X1579921Y1195931D03*
Y1193831D03*
X1583661Y1195931D03*
Y1193831D03*
X1587401Y1195931D03*
Y1193831D03*
X1581575Y1203412D03*
Y1201312D03*
X1585315Y1203412D03*
Y1201312D03*
X1589055Y1203412D03*
Y1201312D03*
X1591141Y1195931D03*
Y1193831D03*
X1594882Y1195931D03*
Y1193831D03*
X1592795Y1203412D03*
Y1201312D03*
X1596752Y1126508D03*
Y1128608D03*
X1600492Y1126508D03*
Y1128608D03*
X1598622Y1133989D03*
Y1136089D03*
X1602362Y1133989D03*
Y1136089D03*
X1606102Y1133989D03*
Y1136089D03*
X1607972Y1126508D03*
Y1128608D03*
X1611712Y1126508D03*
Y1128608D03*
X1609842Y1133989D03*
Y1136089D03*
X1598622Y1141469D03*
Y1143569D03*
X1602362Y1141469D03*
Y1143569D03*
X1606102Y1141469D03*
Y1143569D03*
X1598622Y1148949D03*
Y1151049D03*
X1602362Y1148949D03*
Y1151049D03*
X1606102Y1148949D03*
Y1151049D03*
X1596752Y1156430D03*
X1600492D03*
X1609842Y1141469D03*
Y1143569D03*
Y1148949D03*
Y1151049D03*
X1607972Y1156430D03*
X1611712D03*
X1596752Y1171390D03*
X1600552D03*
X1607972D03*
X1611712D03*
X1596752Y1158530D03*
X1600492D03*
X1607972D03*
X1611712D03*
X1598622Y1180971D03*
Y1178871D03*
X1602362Y1180971D03*
Y1178871D03*
X1606102Y1180971D03*
Y1178871D03*
X1598622Y1188451D03*
Y1186351D03*
X1602362Y1188451D03*
Y1186351D03*
X1606102Y1188451D03*
Y1186351D03*
X1609842Y1180971D03*
Y1178871D03*
Y1188451D03*
Y1186351D03*
X1596752Y1173490D03*
X1600552D03*
X1607972D03*
X1611712D03*
X1598622Y1195931D03*
Y1193831D03*
X1602362Y1195931D03*
Y1193831D03*
X1606102Y1195931D03*
Y1193831D03*
X1596536Y1203412D03*
Y1201312D03*
X1600276Y1203412D03*
Y1201312D03*
X1609842Y1195931D03*
Y1193831D03*
X1608076Y1203412D03*
Y1201312D03*
X1611816Y1203412D03*
Y1201312D03*
X1615452Y1126508D03*
Y1128608D03*
X1619193Y1126508D03*
Y1128608D03*
X1613582Y1133989D03*
Y1136089D03*
X1617322Y1133989D03*
Y1136089D03*
X1621063Y1133989D03*
Y1136089D03*
X1622933Y1126508D03*
Y1128608D03*
X1626673Y1126508D03*
Y1128608D03*
X1624803Y1133989D03*
Y1136089D03*
X1613582Y1141469D03*
Y1143569D03*
X1617322Y1141469D03*
Y1143569D03*
X1621063Y1141469D03*
Y1143569D03*
X1613582Y1148949D03*
Y1151049D03*
X1617322Y1148949D03*
Y1151049D03*
X1621063Y1148949D03*
Y1151049D03*
X1615452Y1156430D03*
X1619192D03*
X1624803Y1141469D03*
Y1143569D03*
Y1148949D03*
Y1151049D03*
X1622933Y1156430D03*
X1626673D03*
X1615452Y1171390D03*
X1619193D03*
X1622933D03*
X1626673D03*
X1615452Y1158530D03*
X1619192D03*
X1622933D03*
X1626673D03*
X1613582Y1180971D03*
Y1178871D03*
X1617322Y1180971D03*
Y1178871D03*
X1621063Y1180971D03*
Y1178871D03*
X1613582Y1188451D03*
Y1186351D03*
X1617322Y1188451D03*
Y1186351D03*
X1621063Y1188451D03*
Y1186351D03*
X1624803Y1180971D03*
Y1178871D03*
Y1188451D03*
Y1186351D03*
X1615452Y1173490D03*
X1619193D03*
X1622933D03*
X1626673D03*
X1613582Y1195931D03*
Y1193831D03*
X1617322Y1195931D03*
Y1193831D03*
X1621063Y1195931D03*
Y1193831D03*
X1615556Y1203412D03*
Y1201312D03*
X1619297Y1203412D03*
Y1201312D03*
X1624803Y1195931D03*
Y1193831D03*
X1623037Y1203412D03*
Y1201312D03*
X1626777Y1203412D03*
Y1201312D03*
X1630413Y1126508D03*
Y1128608D03*
X1634153Y1126508D03*
Y1128608D03*
X1637893Y1126508D03*
Y1128608D03*
X1628543Y1133989D03*
Y1136089D03*
X1632283Y1133989D03*
Y1136089D03*
X1636023Y1133989D03*
Y1136089D03*
X1628543Y1141469D03*
Y1143569D03*
X1632283Y1141469D03*
Y1143569D03*
X1636023Y1141469D03*
Y1143569D03*
X1628543Y1148949D03*
Y1151049D03*
X1632283Y1148949D03*
Y1151049D03*
X1636023Y1148949D03*
Y1151049D03*
X1630413Y1156430D03*
X1634160D03*
X1630413Y1171390D03*
X1634153D03*
X1630413Y1158530D03*
X1634160D03*
X1628543Y1180971D03*
Y1178871D03*
X1632283Y1180971D03*
Y1178871D03*
X1636023Y1180971D03*
Y1178871D03*
X1628543Y1188451D03*
Y1186351D03*
X1632283Y1188451D03*
Y1186351D03*
X1636023Y1188451D03*
Y1186351D03*
X1630413Y1173490D03*
X1634153D03*
X1628543Y1195931D03*
Y1193831D03*
X1632283Y1195931D03*
Y1193831D03*
X1636023Y1195931D03*
Y1193831D03*
X1630517Y1203412D03*
Y1201312D03*
X1634257Y1203412D03*
Y1201312D03*
X1637997Y1203412D03*
Y1201312D03*
X1645374Y1196751D03*
Y1198851D03*
Y1204232D03*
Y1202132D03*
G54D14*
X15916Y1041679D03*
X28318D03*
X50051Y1041371D03*
X37649D03*
X438119Y1234726D03*
X450521D03*
X476828D03*
X489230D03*
X862606Y1050682D03*
X875008D03*
X896741Y1050374D03*
X884339D03*
X926583Y1050682D03*
X938985D03*
X960718Y1050374D03*
X948316D03*
X1352293Y1234726D03*
X1364695D03*
X1391002D03*
X1403404D03*
X1770563Y1051168D03*
X1782965D03*
X1804698Y1050860D03*
X1792296D03*
G54D32*
X51043Y144095D03*
X57933Y66811D03*
X160295D03*
X153405Y144095D03*
X183435Y630650D03*
X190325Y374862D03*
X262657Y66811D03*
X255767Y144095D03*
X279360Y630650D03*
X286250Y374862D03*
X358129Y144095D03*
X365019Y66811D03*
X508130Y144095D03*
X515020Y66811D03*
X617382D03*
X610492Y144095D03*
X647411Y374862D03*
X640521Y630650D03*
X719744Y66811D03*
X712854Y144095D03*
X736446Y630650D03*
X743336Y374862D03*
X815216Y144095D03*
X822106Y66811D03*
X972106D03*
X965216Y144095D03*
X1074468Y66811D03*
X1067578Y144095D03*
X1104498Y374862D03*
X1097608Y630650D03*
X1169940Y144095D03*
X1176830Y66811D03*
X1200423Y374862D03*
X1193533Y630650D03*
X1272302Y144095D03*
X1279192Y66811D03*
X1429193D03*
X1422303Y144095D03*
X1531555Y66811D03*
X1524665Y144095D03*
X1561585Y374862D03*
X1554695Y630650D03*
X1627027Y144095D03*
X1633917Y66811D03*
X1657510Y374862D03*
X1650620Y630650D03*
X1736279Y66811D03*
X1729389Y144095D03*
G54D41*
X116731Y1052235D03*
X106619Y1056423D03*
X102431Y1066535D03*
X106619Y1076647D03*
X116731Y1080835D03*
Y1249086D03*
X106619Y1253274D03*
X102431Y1263386D03*
X106619Y1273498D03*
X116731Y1277686D03*
X126843Y1056423D03*
Y1076647D03*
X131031Y1066535D03*
X126843Y1253274D03*
X131031Y1263386D03*
X126843Y1273498D03*
X342840Y1056423D03*
X338652Y1066535D03*
X342840Y1076647D03*
Y1253274D03*
X338652Y1263386D03*
X342840Y1273498D03*
X352952Y1052235D03*
Y1080835D03*
Y1249086D03*
Y1277686D03*
X363064Y1056423D03*
Y1076647D03*
X367252Y1066535D03*
X363064Y1253274D03*
X367252Y1263386D03*
X363064Y1273498D03*
X563706Y1056423D03*
X559518Y1066535D03*
X563706Y1076647D03*
Y1253274D03*
X559518Y1263386D03*
X563706Y1273498D03*
X583930Y1056423D03*
X573818Y1052235D03*
X583930Y1076647D03*
X588118Y1066535D03*
X573818Y1080835D03*
X583930Y1253274D03*
X573818Y1249086D03*
X588118Y1263386D03*
X573818Y1277686D03*
X583930Y1273498D03*
X760433Y1480906D03*
X756274Y1490945D03*
X760433Y1500984D03*
X780511Y1480906D03*
X770472Y1476747D03*
Y1505143D03*
X780511Y1500984D03*
X799926Y1056423D03*
X795738Y1066535D03*
X799926Y1076647D03*
Y1253274D03*
X795738Y1263386D03*
X799926Y1273498D03*
X784670Y1490945D03*
X810040Y378544D03*
X805881Y388583D03*
X810040Y398622D03*
X810038Y1052235D03*
Y1080835D03*
Y1249086D03*
Y1277686D03*
X820079Y374385D03*
X830118Y378544D03*
X820079Y402781D03*
X830118Y398622D03*
X820150Y1056423D03*
Y1076647D03*
X824338Y1066535D03*
X820150Y1253274D03*
X824338Y1263386D03*
X820150Y1273498D03*
X834277Y388583D03*
X970071Y1365652D03*
Y1409152D03*
X1010827Y378544D03*
X1006668Y388583D03*
X1010827Y398622D03*
X1020866Y374385D03*
Y402781D03*
X1020793Y1056423D03*
X1016605Y1066535D03*
X1020793Y1076647D03*
Y1253274D03*
X1016605Y1263386D03*
X1020793Y1273498D03*
X1030905Y378544D03*
X1035064Y388583D03*
X1030905Y398622D03*
X1041017Y1056423D03*
X1030905Y1052235D03*
X1041017Y1076647D03*
X1030905Y1080835D03*
X1041017Y1253274D03*
X1030905Y1249086D03*
Y1277686D03*
X1041017Y1273498D03*
X1045205Y1066535D03*
Y1263386D03*
X1060433Y1480906D03*
X1056274Y1490945D03*
X1060433Y1500984D03*
X1070472Y1476747D03*
Y1505143D03*
X1080511Y1480906D03*
X1084670Y1490945D03*
X1080511Y1500984D03*
X1252825Y1066535D03*
Y1263386D03*
X1267125Y1052235D03*
X1257013Y1056423D03*
Y1076647D03*
X1267125Y1080835D03*
Y1249086D03*
X1257013Y1253274D03*
Y1273498D03*
X1267125Y1277686D03*
X1277237Y1056423D03*
Y1076647D03*
X1281425Y1066535D03*
X1277237Y1253274D03*
X1281425Y1263386D03*
X1277237Y1273498D03*
X1477879Y1056423D03*
X1473691Y1066535D03*
X1477879Y1076647D03*
Y1253274D03*
X1473691Y1263386D03*
X1477879Y1273498D03*
X1498103Y1056423D03*
X1487991Y1052235D03*
X1498103Y1076647D03*
X1487991Y1080835D03*
X1498103Y1253274D03*
X1487991Y1249086D03*
Y1277686D03*
X1498103Y1273498D03*
X1502291Y1066535D03*
Y1263386D03*
X1709912Y1066535D03*
Y1263386D03*
X1724212Y1052235D03*
X1714100Y1056423D03*
Y1076647D03*
X1724212Y1080835D03*
Y1249086D03*
X1714100Y1253274D03*
Y1273498D03*
X1724212Y1277686D03*
X1734324Y1056423D03*
Y1076647D03*
X1738512Y1066535D03*
X1734324Y1253274D03*
X1738512Y1263386D03*
X1734324Y1273498D03*
G54D117*
G01X86289Y822088D02*
X86119Y821918D01*
X74349D01*
G01X931124Y837531D02*
X930272Y838383D01*
X928177D01*
X927325Y837531D01*
X925755D01*
G01D02*
Y841348D01*
X925072Y842031D01*
G01D02*
X924419Y842684D01*
Y843187D01*
X922313Y845293D01*
G01X935124Y837531D02*
X931124D01*
G54D42*
X116731Y1066535D03*
Y1263386D03*
X352952Y1066535D03*
Y1263386D03*
X573818Y1066535D03*
Y1263386D03*
X810038Y1066535D03*
Y1263386D03*
X1030905Y1066535D03*
Y1263386D03*
X1267125Y1066535D03*
Y1263386D03*
X1487991Y1066535D03*
Y1263386D03*
X1724212Y1066535D03*
Y1263386D03*
G54D24*
X28819Y81575D03*
X73307Y61614D03*
X131181Y81575D03*
X175669Y61614D03*
X233543Y81575D03*
X278032Y61614D03*
X335906Y81575D03*
X380394Y61614D03*
X485886Y81595D03*
X530394Y61614D03*
X588248Y81594D03*
X632756Y61614D03*
X690611Y81595D03*
X735118Y61614D03*
X792973Y81595D03*
X837480Y61614D03*
X942973Y81595D03*
X987480Y61614D03*
X1045335Y81595D03*
X1089843Y61614D03*
X1147697Y81595D03*
X1192205Y61614D03*
X1250060Y81595D03*
X1294567Y61614D03*
X1400060Y81595D03*
X1444567Y61614D03*
X1502441Y81575D03*
X1546929Y61614D03*
X1604784Y81595D03*
X1649291Y61614D03*
X1707146Y81595D03*
X1751654Y61614D03*
G54D108*
X1817323Y1567323D03*
G54D51*
X197247Y1544069D03*
G54D15*
X17874Y1041679D03*
X26360D03*
X48093D03*
X39607D03*
X440077Y1234726D03*
X448563D03*
X478786D03*
X487272D03*
X864564Y1050682D03*
X873050D03*
X894783D03*
X886297D03*
X928541D03*
X937027D03*
X958760D03*
X950274D03*
X1362737Y1234726D03*
X1354251D03*
X1392960D03*
X1401446D03*
X1772521Y1051168D03*
X1781007D03*
X1802740D03*
X1794254D03*
G54D33*
X51750Y617861D03*
X48207D03*
X44664D03*
X51750Y620661D03*
X48207D03*
X44664D03*
X55294Y617861D03*
Y620661D03*
X73872Y1348187D03*
X81752D03*
X73872Y1360099D03*
X81752D03*
X73872Y1384297D03*
Y1372385D03*
X81752Y1384297D03*
Y1372385D03*
X86112Y1348187D03*
X98352D03*
X93992D03*
X86112Y1360099D03*
X98352D03*
X93992D03*
X86112Y1384297D03*
Y1372385D03*
X98352Y1384297D03*
Y1372385D03*
X93992D03*
Y1384297D03*
X86112Y1396583D03*
X93992D03*
X98352D03*
X86112Y1408495D03*
X93992D03*
X98352D03*
X110592Y1348187D03*
X106232D03*
X110592Y1360099D03*
X106232D03*
X110592Y1384297D03*
X106232D03*
Y1372385D03*
X110592D03*
Y1396583D03*
X106232D03*
X110592Y1408495D03*
X106232D03*
X118472Y1348187D03*
X122832D03*
X130712D03*
X118472Y1360099D03*
X122832D03*
X130712D03*
X118472Y1384297D03*
Y1372385D03*
X122832Y1384297D03*
Y1372385D03*
X130712Y1384297D03*
Y1372385D03*
X118472Y1396583D03*
X122832D03*
X130712D03*
X118472Y1408495D03*
X122832D03*
X130712D03*
X143208Y1084547D03*
Y1092027D03*
X146948Y1077066D03*
Y1080806D03*
Y1084547D03*
Y1092027D03*
Y1088287D03*
X143208D03*
Y1095767D03*
X146948D03*
Y1103247D03*
X143208D03*
X146948Y1099507D03*
X143208D03*
X146948Y1106988D03*
X143208D03*
Y1110728D03*
Y1118208D03*
X146948Y1110728D03*
Y1118208D03*
Y1114468D03*
Y1121948D03*
X143208Y1114468D03*
Y1121948D03*
X146948Y1133169D03*
Y1140649D03*
X139468Y1136909D03*
X143208Y1125688D03*
Y1133169D03*
Y1140649D03*
X146948Y1125688D03*
Y1129429D03*
X143208D03*
Y1144389D03*
Y1151870D03*
X146948Y1144389D03*
Y1151870D03*
Y1148129D03*
X143208D03*
X140707Y1170569D03*
X143208Y1159350D03*
X146949Y1166830D03*
X146948Y1159350D03*
X146947Y1170570D03*
X143207D03*
X148818Y1183661D03*
X140707Y1178050D03*
X145078Y1187401D03*
Y1183661D03*
X148818Y1187401D03*
X146947Y1174310D03*
Y1178051D03*
X143207D03*
X141337Y1191142D03*
X145078Y1194881D03*
Y1202362D03*
X148818Y1194881D03*
Y1202362D03*
X141337Y1198622D03*
Y1206103D03*
X145078Y1209842D03*
Y1217322D03*
X148818Y1209842D03*
Y1217322D03*
X141337Y1213583D03*
Y1221063D03*
X148818Y1224803D03*
X145078Y1232283D03*
Y1236023D03*
X148818Y1232283D03*
Y1236023D03*
X145078Y1224803D03*
X141337Y1228542D03*
X148818Y1254724D03*
X145078Y1250984D03*
X148818Y1243503D03*
Y1250984D03*
X141336Y1247242D03*
Y1239762D03*
X145078Y1243503D03*
X135072Y1348187D03*
X142952D03*
X147312D03*
X135072Y1360099D03*
X147312D03*
X142952D03*
X135072Y1384297D03*
Y1372385D03*
X147312Y1384297D03*
Y1372385D03*
X142952Y1384297D03*
Y1372385D03*
X135072Y1396583D03*
X147312D03*
X142952D03*
X135072Y1408495D03*
X147312D03*
X142952D03*
X154429Y1073326D03*
X161909D03*
X165649D03*
X158169D03*
X150689D03*
X154429Y1092027D03*
X161909Y1077066D03*
X165649Y1080807D03*
Y1088287D03*
X161909D03*
Y1092027D03*
X150688Y1077066D03*
X154429D03*
X158169Y1080807D03*
X150689D03*
X158169Y1084547D03*
X150689D03*
X158169Y1088287D03*
X154429D03*
X150689D03*
X165649Y1084547D03*
Y1092027D03*
X158169D03*
X150689D03*
X165649Y1077066D03*
X161909Y1084547D03*
X158169Y1077066D03*
X154429Y1084547D03*
X161909Y1080807D03*
X154429D03*
X158169Y1099507D03*
X150689D03*
X158169Y1103247D03*
X150689D03*
X158169Y1106988D03*
X161909Y1095767D03*
X165649Y1099507D03*
Y1103247D03*
Y1106988D03*
X161909D03*
X154429D03*
X150689D03*
X154429Y1095767D03*
X165649D03*
X161909Y1103247D03*
X158169Y1095767D03*
X154429Y1103247D03*
X150689Y1095767D03*
X161909Y1099507D03*
X154429D03*
X158169Y1110728D03*
Y1114468D03*
X154429D03*
X150689D03*
X158169Y1118208D03*
Y1121948D03*
X154429D03*
X150689D03*
X165649Y1114468D03*
X161909D03*
Y1118208D03*
Y1121948D03*
X165649Y1110728D03*
X161909D03*
X154429D03*
Y1118208D03*
X150689Y1110728D03*
Y1118208D03*
X158169Y1133169D03*
X161909Y1140649D03*
X158169Y1125688D03*
Y1129429D03*
X154429D03*
X150689D03*
Y1136909D03*
X154429Y1140649D03*
X150689D03*
X165649D03*
X161909Y1125688D03*
X165649Y1129429D03*
X161909D03*
X165649Y1136909D03*
X158169Y1140649D03*
X154429Y1125688D03*
X150689D03*
Y1151870D03*
X158169Y1155610D03*
X154429D03*
X150689D03*
X161909Y1144389D03*
Y1148129D03*
Y1151870D03*
Y1155610D03*
X150689Y1144389D03*
X158169Y1151869D03*
X154429D03*
X150689Y1148129D03*
X165649D03*
Y1144389D03*
Y1155610D03*
X150689Y1159350D03*
X158169Y1166830D03*
X154429D03*
X150688D03*
X154429Y1170570D03*
X150688D03*
X161909Y1159350D03*
X165649Y1166830D03*
Y1170570D03*
X160039Y1187401D03*
X156299Y1183661D03*
X152559D03*
X161909Y1174310D03*
Y1178051D03*
X165649Y1181791D03*
X161909D03*
X165649Y1178050D03*
Y1174310D03*
X158169D03*
X154429D03*
X150688Y1178051D03*
Y1174310D03*
X156299Y1179921D03*
X160039Y1183661D03*
X163779D03*
X160039Y1176180D03*
X156299D03*
X160039Y1194881D03*
Y1202362D03*
X156299Y1198621D03*
X152559D03*
X163779D03*
X160039D03*
X152559Y1191141D03*
X156299D03*
X160039D03*
X163779D03*
X160039Y1206102D03*
X156299D03*
X152559D03*
X163779D03*
X160039Y1209842D03*
Y1217322D03*
X156299Y1213582D03*
X152559D03*
X160039Y1221062D03*
X156299D03*
X152559D03*
X163779Y1213582D03*
Y1221062D03*
X160039Y1213582D03*
Y1228543D03*
X152559D03*
X160039Y1224803D03*
X152559D03*
X156299Y1232283D03*
Y1236023D03*
X163779D03*
Y1232283D03*
X160039Y1239763D03*
X152559D03*
Y1243503D03*
X156299Y1250984D03*
X160039Y1247243D03*
Y1243503D03*
X152559Y1247243D03*
X156299Y1239763D03*
X163779Y1250984D03*
X156299Y1254724D03*
X163779D03*
Y1239763D03*
X152559Y1258465D03*
X160039D03*
X159552Y1348187D03*
X155192D03*
X159552Y1360099D03*
X155192D03*
X159552Y1372385D03*
Y1384297D03*
X155192D03*
Y1372385D03*
X159552Y1396583D03*
X155192D03*
X159552Y1408495D03*
X155192D03*
X174998Y1071455D03*
X182479D03*
X178740Y1075196D03*
X171259D03*
X178740Y1090157D03*
Y1078936D03*
X174999Y1086417D03*
Y1082677D03*
X171259Y1078936D03*
X174999Y1090157D03*
X171259D03*
X182480Y1086417D03*
Y1082677D03*
Y1090157D03*
X169389Y1084547D03*
Y1080807D03*
X178740Y1093897D03*
Y1097637D03*
X174999Y1101377D03*
X169389Y1106988D03*
X171259Y1093897D03*
Y1097637D03*
X174999Y1105117D03*
X182480Y1101377D03*
Y1105117D03*
X169389Y1103247D03*
X174999Y1108858D03*
X178740D03*
X169389Y1121948D03*
X176870Y1114468D03*
Y1118208D03*
Y1121948D03*
X178740Y1112598D03*
X173129Y1110728D03*
X169389D03*
X180610Y1114468D03*
Y1118208D03*
Y1121948D03*
X182480Y1112598D03*
Y1108858D03*
X180610Y1136909D03*
X173129Y1133169D03*
X169389D03*
X176870Y1140649D03*
Y1125688D03*
Y1129429D03*
Y1133169D03*
Y1136909D03*
X173129Y1140649D03*
X169389D03*
X173129Y1129428D03*
X169389D03*
X180610Y1140649D03*
Y1125688D03*
Y1129429D03*
Y1133169D03*
Y1148129D03*
X173129Y1144389D03*
X169389D03*
X173129Y1148129D03*
Y1155610D03*
Y1151870D03*
X180610Y1155610D03*
Y1151870D03*
Y1144389D03*
X176870Y1151870D03*
Y1148129D03*
Y1144389D03*
X169389Y1151870D03*
Y1148129D03*
X176870Y1170570D03*
X173129Y1159350D03*
Y1166830D03*
Y1170570D03*
X180610Y1166830D03*
Y1159350D03*
Y1170570D03*
X176870Y1166830D03*
Y1159350D03*
X169389D03*
X180610Y1174310D03*
Y1181791D03*
X173129Y1174310D03*
Y1178051D03*
Y1181791D03*
X171259Y1187401D03*
X174999D03*
X180610Y1178051D03*
X167519Y1183661D03*
X178740Y1187401D03*
X182480D03*
X176870Y1185531D03*
X173129D03*
X176870Y1174310D03*
Y1178051D03*
Y1181791D03*
X171259Y1202362D03*
X167519Y1198621D03*
X171259Y1194881D03*
X174999Y1202362D03*
Y1194881D03*
X167519Y1191141D03*
X178740D03*
Y1194881D03*
Y1198621D03*
Y1202362D03*
X182480Y1191141D03*
Y1198621D03*
Y1202362D03*
X171259Y1209842D03*
X174999Y1217322D03*
X171259Y1221062D03*
X174999D03*
X171259Y1217322D03*
X174999Y1209842D03*
X167519Y1213582D03*
Y1206102D03*
Y1221062D03*
X178740Y1206102D03*
Y1209842D03*
Y1213582D03*
Y1221062D03*
X182480D03*
X178740Y1217322D03*
X182480Y1206102D03*
Y1209842D03*
Y1213582D03*
Y1217322D03*
X178740Y1232283D03*
Y1236023D03*
X174999Y1228543D03*
X171259Y1232283D03*
X174999Y1224803D03*
X171259Y1236023D03*
X182480Y1228543D03*
Y1224803D03*
X167519Y1228543D03*
Y1224803D03*
X182480Y1239763D03*
Y1243503D03*
Y1247243D03*
X171259Y1250984D03*
X178740D03*
Y1239763D03*
X174999Y1243503D03*
Y1247243D03*
X178740Y1254724D03*
X171259D03*
X174999Y1239763D03*
X171259D03*
X167519D03*
Y1243503D03*
Y1247243D03*
X175000Y1258465D03*
X182480D03*
X167519D03*
X167432Y1348187D03*
X171792D03*
X179672D03*
X167432Y1360099D03*
X171792D03*
X179672D03*
X167432Y1384297D03*
Y1372385D03*
X171792Y1384297D03*
Y1372385D03*
X179672Y1384297D03*
Y1372385D03*
X171792Y1396583D03*
X179672D03*
X167432D03*
Y1408495D03*
X171792D03*
X179672D03*
X197439Y1071455D03*
X189959D03*
X186220Y1075196D03*
X193700D03*
Y1090157D03*
X189960Y1086417D03*
Y1082677D03*
X193700Y1078936D03*
X186220D03*
X189960Y1090157D03*
X186220D03*
X197440Y1086417D03*
Y1082677D03*
Y1090157D03*
X193700Y1093897D03*
X189960Y1101377D03*
X186220Y1097637D03*
X189960Y1105117D03*
X186220Y1093897D03*
X193700Y1097637D03*
X197440Y1101377D03*
Y1105117D03*
X195570Y1121948D03*
X191830Y1118208D03*
X188090D03*
X184350D03*
X191830Y1121948D03*
X188090D03*
X184350D03*
X195570Y1118208D03*
X186220Y1108858D03*
X189960D03*
X193700D03*
X197440D03*
X188090Y1114468D03*
X184350D03*
X191830D03*
X195570D03*
X191830Y1125688D03*
X188090D03*
X184350D03*
X188090Y1129429D03*
X184350D03*
X188090Y1133169D03*
X184350D03*
X188090Y1136909D03*
Y1140649D03*
X184350D03*
X195570Y1133169D03*
Y1129429D03*
Y1125688D03*
Y1136909D03*
X191830Y1140649D03*
Y1136909D03*
X195570Y1140649D03*
X184350Y1136909D03*
X191830Y1133169D03*
Y1129429D03*
X188090Y1144389D03*
Y1151870D03*
X191830Y1155610D03*
Y1148129D03*
X195570Y1151869D03*
Y1144389D03*
X191830D03*
Y1151869D03*
X195570Y1148129D03*
Y1155610D03*
X184350Y1144389D03*
X188090Y1155610D03*
X184350Y1151870D03*
X188090Y1148129D03*
Y1159350D03*
Y1170570D03*
X191830Y1166830D03*
X195570Y1159350D03*
Y1170570D03*
X191830Y1159350D03*
Y1170570D03*
X195570Y1166830D03*
X184350Y1159350D03*
Y1170570D03*
X188090Y1166830D03*
Y1185531D03*
Y1178051D03*
X195570Y1189271D03*
X191830Y1181791D03*
Y1174310D03*
X195570Y1185531D03*
Y1178051D03*
X191830Y1185531D03*
Y1178051D03*
X195570Y1181791D03*
Y1174310D03*
X184350Y1185531D03*
X188090Y1181791D03*
Y1174310D03*
X184350Y1178051D03*
X188090Y1193011D03*
Y1196751D03*
Y1200491D03*
Y1204232D03*
X191830D03*
Y1196751D03*
Y1200491D03*
X184350Y1193011D03*
Y1196751D03*
X195570Y1200491D03*
Y1196751D03*
Y1193011D03*
Y1204232D03*
X186220Y1198621D03*
X191830Y1193011D03*
X193700Y1209842D03*
X191830Y1207972D03*
X189960Y1209842D03*
X195570Y1207972D03*
X193700Y1213582D03*
X191830Y1219192D03*
X186220Y1221062D03*
X189960D03*
X193700D03*
X197440D03*
X186220Y1206102D03*
Y1209842D03*
Y1213582D03*
X197440Y1209842D03*
X195570Y1215452D03*
X197440Y1217322D03*
X186220D03*
X189960D03*
Y1213582D03*
X197440Y1224803D03*
X193700Y1232283D03*
X189960Y1228543D03*
X186220Y1232283D03*
X189960Y1224803D03*
X193700Y1236023D03*
X186220D03*
X197440Y1228543D03*
Y1239763D03*
Y1247243D03*
Y1243503D03*
X193700Y1254724D03*
X186220D03*
X193700Y1239763D03*
X186220D03*
X189960D03*
X186220Y1250984D03*
X189960Y1247243D03*
X193700Y1250984D03*
X189960Y1243503D03*
Y1258465D03*
X197441D03*
X184032Y1348187D03*
X191912D03*
X196272D03*
X184032Y1360099D03*
X196272D03*
X191912D03*
X184032Y1384297D03*
Y1372385D03*
X196272Y1384297D03*
Y1372385D03*
X191912Y1384297D03*
Y1372385D03*
X184032Y1396583D03*
X191912D03*
X196272D03*
X184032Y1408495D03*
X191912D03*
X196272D03*
X201181Y1075196D03*
X208661D03*
X204920Y1071455D03*
X212400D03*
X208661Y1078936D03*
X204921Y1090157D03*
X212401Y1086417D03*
Y1082677D03*
Y1090157D03*
X208661D03*
X201181D03*
X204921Y1086417D03*
Y1082677D03*
X201181Y1078936D03*
X204921Y1101377D03*
X208661Y1097637D03*
X201181D03*
X204921Y1105117D03*
X212401Y1101377D03*
Y1105117D03*
X201181Y1093897D03*
X208661D03*
X199311Y1118208D03*
Y1121948D03*
X206791Y1118208D03*
X203051D03*
Y1121948D03*
X206791D03*
X210531Y1118208D03*
X214271Y1110728D03*
Y1114468D03*
X210531Y1121948D03*
X214271Y1118208D03*
Y1121948D03*
X201181Y1108858D03*
X204921D03*
X208661D03*
X212401D03*
X203051Y1114468D03*
X199311D03*
X206791D03*
X210531D03*
X199311Y1140649D03*
X203051D03*
X206791D03*
X199311Y1125688D03*
X203051D03*
X206791D03*
Y1133169D03*
X203051D03*
X199311D03*
X210531D03*
Y1140649D03*
X214271D03*
Y1125688D03*
X210531D03*
X214271Y1133169D03*
X206791Y1136909D03*
X203051D03*
X199311D03*
X214271D03*
X210531D03*
X199311Y1129429D03*
X206791D03*
X214271D03*
X210531D03*
X203051D03*
Y1148129D03*
X199311D03*
X206791D03*
X214271D03*
X210531D03*
X199311Y1155610D03*
X206791D03*
X214271D03*
X210531D03*
X203051D03*
X206791Y1144389D03*
X203051D03*
X199311D03*
X214271D03*
X210531D03*
X214271Y1151870D03*
X210531D03*
X206791D03*
X203051D03*
X199311D03*
X206791Y1166830D03*
X203051Y1159350D03*
X199311Y1166830D03*
X203051Y1170570D03*
X214271Y1166830D03*
X210531Y1159350D03*
Y1170570D03*
X214271D03*
X210531Y1166830D03*
X214271Y1159350D03*
X206791Y1170570D03*
X203051Y1166830D03*
X199311Y1170570D03*
X206791Y1159350D03*
X199311D03*
X206791Y1181791D03*
X203051D03*
X199311D03*
X206791Y1189271D03*
X203051D03*
X199311D03*
X214271Y1181791D03*
X210531D03*
X214271Y1189271D03*
X210531D03*
X199311Y1174310D03*
X206791D03*
X214271D03*
X203051D03*
X210531D03*
X203051Y1185531D03*
X199311D03*
X206791D03*
X214271D03*
X210531D03*
X206791Y1178051D03*
X203051D03*
X199311D03*
X214271D03*
X210531D03*
X206791Y1196751D03*
X203051D03*
X199311D03*
Y1204232D03*
X203051D03*
X206791D03*
X214271Y1196751D03*
X210531D03*
Y1204232D03*
X214271D03*
Y1193011D03*
X210531D03*
X199311D03*
X203051D03*
X206791D03*
X214271Y1200491D03*
X210531D03*
X199311D03*
X206791D03*
X203051D03*
X206791Y1207972D03*
X203051D03*
X199311D03*
X210531D03*
Y1211712D03*
X214271Y1207972D03*
X212401Y1221062D03*
X208661D03*
X204921D03*
X201181D03*
Y1213582D03*
X214271Y1211712D03*
X208661Y1213582D03*
X203051Y1215452D03*
X214271D03*
X201181Y1217322D03*
X208661D03*
X210531Y1215452D03*
X204921Y1213582D03*
X212401Y1228543D03*
Y1224803D03*
X208661Y1232283D03*
X204921Y1228543D03*
X201181Y1232283D03*
X204921Y1224803D03*
X201181Y1236023D03*
X208661D03*
Y1250984D03*
X201181Y1239763D03*
X212401D03*
Y1247243D03*
Y1243503D03*
X201181Y1254724D03*
X208661Y1239763D03*
X204921D03*
Y1243503D03*
X201181Y1250984D03*
X204921Y1247243D03*
X208661Y1254724D03*
X212401Y1258465D03*
X204921D03*
X204152Y1348187D03*
Y1360099D03*
Y1384297D03*
Y1372385D03*
Y1396583D03*
Y1408495D03*
X213969Y1445013D03*
Y1453293D03*
Y1456013D03*
Y1464293D03*
X219880Y1071455D03*
X227361D03*
X223622Y1075196D03*
X231102D03*
X216141D03*
X227362Y1086417D03*
Y1082677D03*
Y1090157D03*
X223622D03*
X219881Y1086417D03*
Y1082677D03*
Y1090157D03*
X223622Y1078936D03*
X231102Y1090157D03*
Y1078936D03*
X216141Y1090157D03*
Y1078936D03*
X223622Y1093897D03*
X231102D03*
Y1097637D03*
X227362Y1101377D03*
Y1105117D03*
X219881Y1101377D03*
Y1105117D03*
X223622Y1097637D03*
X216141D03*
Y1093897D03*
X225492Y1118208D03*
Y1121948D03*
X218011Y1118208D03*
X221751D03*
X218011Y1121948D03*
X221751D03*
X229232D03*
Y1118208D03*
Y1114468D03*
X216141Y1108858D03*
X219881D03*
X223622D03*
X227362D03*
X231102D03*
X225492Y1114468D03*
X221752D03*
X218011D03*
X225492Y1133169D03*
Y1140649D03*
Y1125688D03*
X218011Y1140649D03*
X221751D03*
X218011Y1125688D03*
X221751D03*
Y1133169D03*
X218011D03*
X229330Y1132677D03*
X229232Y1140649D03*
Y1125688D03*
X225492Y1136909D03*
X221751D03*
X218011D03*
X229232D03*
Y1129429D03*
X218011D03*
X221751D03*
X225492D03*
Y1148129D03*
X221751D03*
X218011D03*
X229232D03*
X221751Y1155610D03*
X229232D03*
X218011D03*
X225492D03*
Y1144389D03*
X221751D03*
X218011D03*
X229232D03*
Y1151870D03*
X221752D03*
X218011D03*
X225492D03*
Y1170570D03*
Y1159350D03*
X218011Y1170570D03*
X221752Y1166830D03*
X218011Y1159350D03*
X229232Y1166830D03*
X225492D03*
X221751Y1170570D03*
X218011Y1166830D03*
X221751Y1159350D03*
X229232Y1170570D03*
Y1159350D03*
X225492Y1181791D03*
Y1189271D03*
X221751Y1181791D03*
X218011D03*
X221751Y1189271D03*
X218011D03*
X229232Y1181791D03*
Y1189271D03*
X221751Y1174310D03*
X229232D03*
X225492D03*
X218011D03*
X225492Y1185531D03*
X218011D03*
X221751D03*
X229232D03*
X225492Y1178051D03*
X221751D03*
X218011D03*
X229232D03*
X218011Y1204232D03*
X229232Y1196751D03*
Y1204232D03*
X225492Y1196751D03*
Y1204232D03*
X221751D03*
Y1196751D03*
X218011D03*
Y1193011D03*
X221751D03*
X225492D03*
X229232D03*
X218011Y1200491D03*
X221751D03*
X225492D03*
X229232D03*
X225492Y1207972D03*
X218011Y1211712D03*
X221751Y1207972D03*
X218011D03*
X229232D03*
X231102Y1221062D03*
X227362D03*
X219881Y1217322D03*
X223622Y1221062D03*
X219881D03*
X216141D03*
X218011Y1215452D03*
X229232Y1211712D03*
Y1215452D03*
X225492Y1211712D03*
X221752D03*
Y1215452D03*
X227362Y1228543D03*
Y1224803D03*
X223622Y1232283D03*
X219881Y1228543D03*
Y1224803D03*
X223622Y1236023D03*
X231102Y1232283D03*
Y1236023D03*
X216141Y1232283D03*
Y1236023D03*
X223622Y1254724D03*
X231102D03*
X223622Y1239763D03*
X231102D03*
X227362Y1243503D03*
Y1247243D03*
X219881Y1239763D03*
X223622Y1250984D03*
X219881Y1247243D03*
Y1243503D03*
X231102Y1250984D03*
X227362Y1239763D03*
X216141Y1250984D03*
Y1254724D03*
Y1239763D03*
X219882Y1258465D03*
X227363D03*
X227249Y1445013D03*
Y1464293D03*
Y1456013D03*
Y1453293D03*
X246062Y1075196D03*
X234841Y1071454D03*
X242321Y1071455D03*
X238582Y1075196D03*
X234842Y1090157D03*
X246062D03*
Y1078936D03*
X238582D03*
Y1090157D03*
X242322Y1082677D03*
Y1086417D03*
X234842Y1082677D03*
Y1086417D03*
X242322Y1090157D03*
X246062Y1097637D03*
Y1093897D03*
X242322Y1105117D03*
X234842Y1101377D03*
X238582Y1097637D03*
Y1093897D03*
X242322Y1101377D03*
X234842Y1105117D03*
X236712Y1121948D03*
X240452D03*
X244192D03*
X234842Y1108858D03*
X238582D03*
X242322D03*
X246062D03*
X240452Y1114468D03*
X244192D03*
X236712Y1118208D03*
X244192D03*
X236712Y1114468D03*
X240452Y1118208D03*
X236712Y1133464D03*
X240452Y1133169D03*
X236712Y1140649D03*
X240452D03*
X236712Y1125688D03*
X240452D03*
X244192Y1133169D03*
Y1140649D03*
Y1125688D03*
X240452Y1136909D03*
X236712D03*
X244192D03*
Y1129429D03*
X240452D03*
X236712D03*
Y1148129D03*
X240452D03*
X244192D03*
X240452Y1155610D03*
X236712D03*
X244192D03*
X240452Y1151869D03*
X236712D03*
X244192D03*
X240452Y1144389D03*
X236712D03*
X244192D03*
X240452Y1166830D03*
X236712Y1170570D03*
Y1159350D03*
X244192Y1170570D03*
Y1159350D03*
X236712Y1166830D03*
X240452Y1170570D03*
Y1159350D03*
X244192Y1166830D03*
X240452Y1181791D03*
X236712D03*
Y1189271D03*
X240452D03*
X244192Y1181791D03*
Y1189271D03*
X240452Y1174310D03*
X236712D03*
X244192D03*
X240452Y1185531D03*
X236712D03*
X244192D03*
X240452Y1178051D03*
X236712D03*
X244192D03*
X240452Y1204232D03*
X236712D03*
Y1196751D03*
X240452D03*
X244192Y1204232D03*
Y1196751D03*
X240452Y1193011D03*
X236712D03*
X244192D03*
X236712Y1200491D03*
X244192D03*
X240452D03*
X246062Y1221062D03*
X240452Y1207972D03*
Y1211712D03*
X242322Y1221062D03*
X244192Y1211712D03*
Y1207972D03*
X236712D03*
X234842Y1221062D03*
X238582D03*
X244192Y1215452D03*
X240452D03*
X242322Y1217322D03*
X236712Y1211712D03*
Y1215452D03*
X238582Y1217322D03*
X246062Y1232283D03*
Y1236023D03*
X238582Y1232283D03*
X234842Y1228543D03*
Y1224803D03*
X238582Y1236023D03*
X242322Y1228543D03*
Y1224803D03*
X246062Y1254724D03*
Y1239763D03*
X238582Y1254724D03*
Y1239763D03*
X234842D03*
X238582Y1250984D03*
X234842Y1243503D03*
Y1247243D03*
X242322Y1243503D03*
Y1239763D03*
Y1247243D03*
X246062Y1250984D03*
X234842Y1258465D03*
X242322D03*
X239383Y1348187D03*
X247263D03*
Y1360099D03*
X239383D03*
X247263Y1384297D03*
Y1372385D03*
X239383Y1384297D03*
Y1372385D03*
X253543Y1075196D03*
X261023D03*
X249802Y1071455D03*
X257282D03*
X253543Y1090157D03*
X249803Y1082677D03*
Y1090157D03*
Y1086417D03*
X253543Y1078936D03*
X257283Y1090157D03*
Y1082677D03*
Y1086417D03*
X261023Y1090157D03*
Y1078936D03*
X249803Y1105117D03*
Y1101377D03*
X253543Y1093897D03*
X257283Y1101377D03*
X253543Y1097637D03*
X257283Y1105117D03*
X261023Y1093897D03*
Y1097637D03*
X255413Y1121948D03*
X251673D03*
X247933D03*
X262893D03*
X259153D03*
X249803Y1108858D03*
X253543D03*
X257283D03*
X261023D03*
X262893Y1118208D03*
X259153Y1114468D03*
X262893D03*
X255413Y1118208D03*
Y1114468D03*
X247933D03*
X259153Y1118208D03*
X251673Y1114468D03*
X247933Y1118208D03*
X251673D03*
X247933Y1133169D03*
X251673D03*
X255413D03*
X247933Y1140649D03*
X251673D03*
X255413D03*
X247933Y1125688D03*
X251673D03*
X255413D03*
X259153Y1133169D03*
X262893D03*
Y1140649D03*
X259153Y1125688D03*
X262893D03*
X259153Y1140649D03*
X255413Y1136909D03*
X251673D03*
X247933D03*
X259153D03*
X262893D03*
X247933Y1129429D03*
X259153D03*
X262893D03*
X255413D03*
X251673D03*
X259153Y1148129D03*
X262893D03*
Y1155610D03*
X247933Y1148129D03*
X251673D03*
X255413D03*
X247933Y1155610D03*
X255413D03*
X251673D03*
X259153D03*
X251673Y1144389D03*
X247933D03*
X255413D03*
X259153Y1151869D03*
X262893D03*
X247933D03*
X255413D03*
X251673D03*
X262893Y1144389D03*
X259153D03*
X262893Y1166830D03*
X251673Y1170570D03*
X255413Y1166830D03*
X247933D03*
X251673Y1159350D03*
X259153D03*
Y1170570D03*
X251673Y1166830D03*
X255413Y1170570D03*
X247933D03*
X255413Y1159350D03*
X247933D03*
X259153Y1166830D03*
X262893Y1170570D03*
Y1159350D03*
X247933Y1181791D03*
X251673D03*
X255413D03*
X247933Y1189271D03*
X251673D03*
X255413D03*
X262893D03*
Y1174310D03*
X259153Y1181791D03*
X262893D03*
X259153Y1189271D03*
X255413Y1174310D03*
X247933D03*
X251673D03*
X259153D03*
X247933Y1185531D03*
X255413D03*
X251673D03*
X259153D03*
X262893D03*
X251673Y1178051D03*
X247933D03*
X255413D03*
X259153D03*
X262893D03*
X247933Y1204232D03*
X255413D03*
X251673D03*
X247933Y1196751D03*
X251673D03*
X255413D03*
X259153Y1204232D03*
X262893D03*
X259153Y1196751D03*
X262893D03*
X251673Y1193011D03*
X255413D03*
X247933D03*
X262893D03*
X259153D03*
Y1200491D03*
X262893D03*
X251673D03*
X247933D03*
X255413D03*
X247933Y1207972D03*
X251673D03*
X255413Y1211712D03*
Y1207972D03*
X249803Y1221062D03*
X253543D03*
X262893Y1207972D03*
X259153D03*
X262893Y1211712D03*
X259153D03*
X261023Y1221062D03*
X257283D03*
X255413Y1215452D03*
X262893D03*
X247932Y1215451D03*
X259153Y1215452D03*
X251673D03*
X247932Y1211711D03*
X251673D03*
X249803Y1228543D03*
X257283D03*
X249803Y1224803D03*
X253543Y1236023D03*
X257283Y1224803D03*
X261023Y1236023D03*
X253543Y1232283D03*
X261023D03*
X249803Y1243503D03*
X253543Y1250984D03*
Y1254724D03*
X249803Y1247243D03*
X253543Y1239763D03*
X249803D03*
X257283Y1243503D03*
Y1247243D03*
X261023Y1250984D03*
Y1239763D03*
Y1254724D03*
X257283Y1239763D03*
X249803Y1258465D03*
X257283D03*
X263863Y1348187D03*
X259503D03*
X251623D03*
X263863Y1360099D03*
X259503D03*
X251623D03*
X263863Y1384297D03*
Y1372385D03*
X259503Y1384297D03*
Y1372385D03*
X251623D03*
Y1384297D03*
X263863Y1396583D03*
X259503D03*
X251623D03*
X263863Y1408495D03*
X259503D03*
X251623D03*
X279723Y1071455D03*
X264762D03*
X272243D03*
X268503Y1075196D03*
X275984D03*
X279724Y1082677D03*
Y1086417D03*
Y1090157D03*
X275984Y1078936D03*
X272244Y1082677D03*
X275984Y1090157D03*
X272244Y1086417D03*
X264763Y1082677D03*
X268503Y1078936D03*
Y1090157D03*
X264763Y1086417D03*
X272244Y1090157D03*
X264763D03*
X268503Y1093897D03*
Y1097637D03*
X272244Y1101377D03*
Y1105117D03*
X279724Y1101377D03*
X275984Y1097637D03*
X279724Y1105117D03*
X275984Y1093897D03*
X264763Y1101377D03*
Y1105117D03*
X274114Y1118208D03*
Y1121948D03*
X270373Y1118208D03*
X266633Y1121948D03*
X270373D03*
X277854Y1118208D03*
Y1121948D03*
X264763Y1108858D03*
X268503D03*
X272244D03*
X275984D03*
X279724D03*
X270373Y1114468D03*
X274114D03*
X277854D03*
Y1129429D03*
X274114Y1125688D03*
X270373Y1136909D03*
X266633Y1133169D03*
X270373D03*
X266633Y1140649D03*
X270373Y1125688D03*
Y1129429D03*
X266633Y1125688D03*
X270373Y1140649D03*
X277854Y1136909D03*
Y1133169D03*
Y1140649D03*
Y1125688D03*
X266633Y1136909D03*
Y1129429D03*
X274114D03*
Y1140649D03*
Y1136909D03*
Y1155610D03*
Y1151869D03*
Y1148129D03*
X266633D03*
X270373Y1144389D03*
Y1148129D03*
Y1151869D03*
X277854Y1144389D03*
Y1148129D03*
Y1151870D03*
X270373Y1155610D03*
X266633D03*
X277854D03*
X266633Y1151869D03*
Y1144389D03*
X274114D03*
Y1166830D03*
Y1159350D03*
Y1170570D03*
X277854Y1159350D03*
Y1166830D03*
Y1170570D03*
X266633D03*
X270373D03*
X266633Y1159350D03*
X270373D03*
Y1166830D03*
X266633D03*
Y1181791D03*
X270373Y1189271D03*
X277854Y1178051D03*
Y1189271D03*
Y1185531D03*
X270373Y1174310D03*
X277854Y1181791D03*
X274114D03*
Y1174310D03*
X266633Y1189271D03*
X270373Y1178051D03*
Y1185531D03*
X266633Y1174310D03*
X277854D03*
X266633Y1185531D03*
Y1178051D03*
X270373Y1181791D03*
X274114Y1185531D03*
Y1189271D03*
Y1178051D03*
Y1204232D03*
Y1196751D03*
X270393Y1196732D03*
X270373Y1204232D03*
X266633D03*
X270373Y1200491D03*
X266633Y1196751D03*
X270373Y1193011D03*
X277854D03*
X266633D03*
Y1200491D03*
X274114D03*
Y1193011D03*
X277854Y1204232D03*
Y1196751D03*
Y1200491D03*
X274114Y1207972D03*
X270373Y1211712D03*
X266633Y1207972D03*
Y1211712D03*
X264763Y1221062D03*
X270373Y1207972D03*
X277854Y1211712D03*
X279724Y1221062D03*
X275984D03*
X272244D03*
X268503D03*
X274114Y1215452D03*
X277854D03*
X266633D03*
X274114Y1211712D03*
X277854Y1207972D03*
X279724Y1224803D03*
X272244D03*
X268503Y1236023D03*
Y1232283D03*
X272244Y1228543D03*
X264763Y1224803D03*
X275984Y1232283D03*
Y1236023D03*
X264763Y1228543D03*
X279724D03*
Y1239763D03*
Y1247243D03*
X268503Y1239763D03*
X275984D03*
X272244Y1243503D03*
Y1247243D03*
X264763Y1239763D03*
Y1247243D03*
X268503Y1250984D03*
X264763Y1243503D03*
X272244Y1239763D03*
X275984Y1250984D03*
X279724Y1243503D03*
X268503Y1254724D03*
X275984D03*
X279724Y1258465D03*
X264763D03*
X272244D03*
X276103Y1348187D03*
X271743D03*
X276103Y1360099D03*
X271743D03*
X276103Y1384297D03*
Y1372385D03*
X271743Y1384297D03*
Y1372385D03*
X276103Y1396583D03*
X271743D03*
Y1408495D03*
X276103D03*
X294684Y1071455D03*
X290944Y1075196D03*
X287203Y1071455D03*
X283464Y1075196D03*
X294684Y1082677D03*
Y1090157D03*
X294685Y1086417D03*
X287204Y1090157D03*
X290944Y1078936D03*
X287204Y1082677D03*
Y1086417D03*
X283464Y1078936D03*
Y1090157D03*
X290943D03*
X290944Y1093897D03*
X283464D03*
X287204Y1101377D03*
X283464Y1097637D03*
X287204Y1105117D03*
X290944Y1097637D03*
X294684Y1101377D03*
X294685Y1105117D03*
X294684Y1120078D03*
Y1112598D03*
X283464Y1108858D03*
X287204D03*
X290944D03*
X294685D03*
X290944Y1112598D03*
Y1116338D03*
Y1120078D03*
Y1123818D03*
X285334Y1118208D03*
X281594D03*
X285334Y1114468D03*
X281594D03*
X294685Y1127558D03*
Y1135039D03*
X281594Y1140649D03*
Y1136909D03*
X290944Y1127558D03*
Y1131299D03*
Y1135039D03*
Y1138779D03*
X289074Y1140649D03*
X285334D03*
Y1136909D03*
X292815Y1140649D03*
X281594Y1148129D03*
Y1155610D03*
Y1151869D03*
X285334D03*
X289074D03*
Y1155610D03*
Y1144389D03*
X292814Y1151869D03*
Y1144389D03*
X285334Y1155610D03*
X281594Y1144389D03*
X285334Y1148129D03*
Y1144389D03*
X289074Y1148129D03*
X292815D03*
Y1155610D03*
X281594Y1159350D03*
X289074Y1166830D03*
Y1170570D03*
Y1159350D03*
X281594Y1170570D03*
Y1166830D03*
X292814Y1159350D03*
Y1166830D03*
X285334Y1170570D03*
Y1166830D03*
Y1159350D03*
X292815Y1170570D03*
X292814Y1181791D03*
X285334Y1185531D03*
X289074Y1174310D03*
Y1178051D03*
Y1185531D03*
X281594Y1189271D03*
Y1185531D03*
X285334Y1181791D03*
X281594Y1178051D03*
Y1174310D03*
X292814D03*
Y1189271D03*
X285334Y1174310D03*
X289074Y1189271D03*
X285334D03*
X281594Y1181791D03*
X285334Y1178051D03*
X289074Y1181791D03*
X294685Y1194881D03*
Y1202362D03*
X281594Y1196751D03*
Y1204232D03*
X290944Y1191141D03*
X281594Y1193011D03*
X285334D03*
X290944Y1194881D03*
Y1198621D03*
Y1202362D03*
X285334Y1196751D03*
Y1204232D03*
X281594Y1200491D03*
X285334D03*
X294685Y1209842D03*
Y1221062D03*
Y1217322D03*
X290944Y1221062D03*
X287204D03*
X283464D03*
X290944Y1206102D03*
Y1209842D03*
Y1213582D03*
Y1217322D03*
X285334Y1207972D03*
Y1215452D03*
Y1211712D03*
X281594Y1215452D03*
Y1207972D03*
X294685Y1228543D03*
Y1224803D03*
X290944Y1232283D03*
Y1236023D03*
X283464Y1232283D03*
X287204Y1228543D03*
X283464Y1236023D03*
X287204Y1224803D03*
X294685Y1247243D03*
Y1243503D03*
X283464Y1250984D03*
X287204Y1247243D03*
Y1243503D03*
Y1239763D03*
X294685D03*
X290944Y1250984D03*
X283464Y1254724D03*
X290944D03*
X283464Y1239763D03*
X290944D03*
X294685Y1258465D03*
X287204D03*
X288343Y1348187D03*
X296223D03*
X283983D03*
X288343Y1360099D03*
X296223D03*
X283983D03*
X288343Y1384297D03*
Y1372385D03*
X296223Y1384297D03*
Y1372385D03*
X283983D03*
Y1384297D03*
X288343Y1396583D03*
X296223D03*
X283983D03*
X288343Y1408495D03*
X296223D03*
X283983D03*
X309645Y1071455D03*
X302165D03*
X298425Y1075196D03*
X305906D03*
X298424Y1090157D03*
X302164Y1082677D03*
X298426Y1078936D03*
X302164Y1090157D03*
X302165Y1086417D03*
X305904Y1090157D03*
X309644Y1082677D03*
X305906Y1078936D03*
X309645Y1086417D03*
X309644Y1090157D03*
X302165Y1101377D03*
X298425Y1097637D03*
X302165Y1105117D03*
X309645D03*
Y1101377D03*
X305905Y1097637D03*
X298425Y1093897D03*
X305905D03*
X302165Y1123818D03*
X309645D03*
X305904Y1108857D03*
X309644Y1108858D03*
X302165Y1116338D03*
X298425Y1108858D03*
X302165D03*
X298425Y1112598D03*
X309645D03*
Y1116338D03*
Y1120078D03*
X305905Y1116338D03*
X298425Y1120078D03*
X305905Y1123818D03*
X309645Y1135039D03*
Y1127558D03*
Y1131299D03*
X311515Y1136909D03*
X307775Y1140649D03*
X304035D03*
X305905Y1131299D03*
X300295Y1140649D03*
X298425Y1135039D03*
X302165Y1131299D03*
X298425Y1127558D03*
X311515Y1140649D03*
X296555Y1151869D03*
X304035Y1155610D03*
Y1148129D03*
X300295Y1155610D03*
Y1151869D03*
Y1148129D03*
Y1144389D03*
X296555D03*
X311515D03*
X307775Y1148129D03*
X311515Y1151869D03*
X307775Y1155610D03*
X304035Y1144389D03*
Y1151869D03*
X307775Y1144389D03*
Y1151869D03*
X296555Y1155610D03*
X311515Y1148129D03*
Y1155610D03*
X307775Y1159350D03*
X296555D03*
X300295D03*
X296555Y1166830D03*
X304035Y1170570D03*
X300295D03*
Y1166830D03*
X311515D03*
X307775Y1170570D03*
X311515Y1159350D03*
X304035Y1166830D03*
Y1159350D03*
X307775Y1166830D03*
X296555Y1170570D03*
X311515D03*
X300295Y1185531D03*
Y1181791D03*
Y1178051D03*
Y1174310D03*
X296555D03*
X298425Y1187401D03*
X304035Y1185531D03*
Y1178051D03*
X300295Y1189271D03*
X311515Y1174310D03*
X307775Y1178051D03*
X311515Y1181791D03*
X307775Y1185531D03*
X311515Y1189271D03*
X304035Y1174310D03*
Y1181791D03*
Y1189271D03*
X307775Y1174310D03*
Y1181791D03*
Y1189271D03*
X311515Y1178051D03*
Y1185531D03*
X304035Y1193011D03*
X302165Y1198621D03*
X298425Y1202362D03*
Y1194881D03*
X309645Y1198621D03*
X307775Y1193011D03*
X311515Y1196751D03*
X305905Y1198621D03*
X309645Y1202362D03*
X311515Y1193011D03*
X305905Y1206102D03*
X302165Y1213582D03*
X298425Y1209842D03*
X302165Y1206102D03*
X298425Y1221062D03*
X302165D03*
X298425Y1217322D03*
X309645D03*
Y1209842D03*
X305905Y1213582D03*
X309645D03*
Y1206102D03*
Y1221062D03*
X305905D03*
X298425Y1236023D03*
Y1232283D03*
X302165Y1228543D03*
Y1224803D03*
X305905Y1232283D03*
X309645Y1228543D03*
Y1224803D03*
X305905Y1236023D03*
X309645Y1247243D03*
Y1243503D03*
X298425Y1250984D03*
X302165Y1247243D03*
Y1243503D03*
X305905Y1239763D03*
X302165D03*
X305905Y1250984D03*
X298425Y1254724D03*
X305905D03*
X298425Y1239763D03*
X309645D03*
Y1258465D03*
X302165D03*
X308463Y1348187D03*
X300583D03*
X308463Y1360099D03*
X300583D03*
X308463Y1372385D03*
X300583D03*
Y1384297D03*
X308463D03*
Y1396583D03*
X300583D03*
X308463Y1408495D03*
X300583D03*
X317125Y1071455D03*
X320866Y1075196D03*
X313386D03*
X320866Y1086417D03*
Y1078936D03*
X313384Y1090157D03*
X317125D03*
X317126Y1086417D03*
X317125Y1082677D03*
X313386Y1078936D03*
X324606Y1086417D03*
X328347Y1082677D03*
Y1090158D03*
X324606Y1078936D03*
X320866Y1093897D03*
X313385D03*
X324606D03*
Y1105117D03*
Y1097637D03*
X328347Y1101378D03*
X320866Y1105117D03*
Y1097637D03*
X317126Y1105117D03*
X317125Y1101377D03*
X313385Y1097637D03*
X317125Y1116338D03*
X324606Y1112598D03*
Y1120078D03*
X328347Y1116339D03*
Y1123819D03*
X320866Y1112598D03*
Y1120078D03*
X317125Y1123818D03*
X328347Y1108859D03*
X313385Y1108858D03*
X317125D03*
X313385Y1123818D03*
Y1116338D03*
X328347Y1131300D03*
X320866Y1127558D03*
Y1135039D03*
X322736Y1140649D03*
X318996D03*
X315255Y1136909D03*
X318996D03*
X313384Y1131299D03*
X317125D03*
X324606Y1127558D03*
Y1135039D03*
X326476Y1140649D03*
X322736Y1136909D03*
X326476D03*
X315255Y1140649D03*
X322736Y1155610D03*
X318996Y1144389D03*
X315255D03*
X318996Y1155610D03*
X315255Y1151869D03*
X318996D03*
Y1148129D03*
X326476D03*
Y1155610D03*
X322736Y1148129D03*
Y1144389D03*
Y1151870D03*
X326476Y1144389D03*
X315255Y1148129D03*
X326476Y1151870D03*
X315255Y1155610D03*
X322736Y1170570D03*
Y1166830D03*
X315255Y1159350D03*
X318996D03*
X315255Y1166830D03*
X318996Y1170570D03*
Y1166830D03*
X326476D03*
Y1170570D03*
X322736Y1159350D03*
X326476D03*
X315255Y1170570D03*
Y1181791D03*
Y1189271D03*
X318996D03*
Y1185531D03*
Y1181791D03*
Y1178051D03*
X315255Y1174310D03*
X318996D03*
X326476Y1178051D03*
Y1185531D03*
X322736Y1178051D03*
Y1185531D03*
Y1174310D03*
Y1181791D03*
Y1189271D03*
X326476Y1174310D03*
X315255Y1178051D03*
X326476Y1181791D03*
X315255Y1185531D03*
X326476Y1189271D03*
X328347Y1198621D03*
X322736Y1193011D03*
X320866Y1202362D03*
X318996Y1193011D03*
X313385Y1198621D03*
X317125D03*
X326416Y1193011D03*
X324606Y1202362D03*
X315255Y1193011D03*
X328347Y1206102D03*
X317125D03*
X313385D03*
X328347Y1221062D03*
Y1213582D03*
X320866Y1217322D03*
Y1209842D03*
X313385Y1221062D03*
X317125D03*
X313385Y1213582D03*
X317125D03*
X324606Y1209842D03*
Y1217322D03*
X320866Y1236023D03*
Y1224803D03*
Y1232283D03*
X313385D03*
X317125Y1228543D03*
Y1224803D03*
X313385Y1236023D03*
X324606Y1232283D03*
Y1236023D03*
Y1224803D03*
X328347Y1228543D03*
Y1239762D03*
Y1247243D03*
X320866Y1250984D03*
Y1243503D03*
X313385Y1250984D03*
X317125Y1247243D03*
Y1243503D03*
X324606D03*
Y1250984D03*
X313385Y1254724D03*
X317125Y1239763D03*
X313385D03*
X320866Y1254724D03*
X317125Y1258465D03*
X320703Y1348187D03*
X312823D03*
X325063D03*
X320703Y1360099D03*
X312823D03*
X325063D03*
X320703Y1372385D03*
Y1384297D03*
X312823Y1372385D03*
Y1384297D03*
X325063Y1372385D03*
Y1384297D03*
Y1396583D03*
X320703D03*
X312823D03*
X320703Y1408495D03*
X312823D03*
X325063D03*
X337303Y1348187D03*
X332943D03*
Y1360099D03*
X337303D03*
X332943Y1384297D03*
Y1372385D03*
X337303D03*
Y1384297D03*
X332943Y1396583D03*
X337303D03*
X332943Y1408495D03*
X337303D03*
X349543Y1348187D03*
X357423D03*
X345183D03*
X349543Y1360099D03*
X357423D03*
X345183D03*
Y1372385D03*
Y1384297D03*
X349543D03*
Y1372385D03*
X357423D03*
Y1384297D03*
X345183Y1396583D03*
X349543D03*
X357423D03*
X345183Y1408495D03*
X349543D03*
X357423D03*
X369663Y1348187D03*
X361783D03*
X369663Y1360099D03*
X361783D03*
X369663Y1372385D03*
Y1384297D03*
X361783D03*
Y1372385D03*
X369663Y1396583D03*
X361783D03*
X369663Y1408495D03*
X361783D03*
X425023Y441086D03*
Y433999D03*
Y437543D03*
X422223Y441086D03*
Y433999D03*
Y437543D03*
X425023Y444629D03*
X422223D03*
X438162Y1348187D03*
Y1360099D03*
Y1384297D03*
Y1372385D03*
X450402Y1348187D03*
X458282D03*
X446042D03*
X450402Y1360099D03*
X458282D03*
X446042D03*
X458282Y1372385D03*
X446042D03*
X458282Y1384297D03*
X446042D03*
X450402D03*
Y1372385D03*
X458282Y1396583D03*
X450402D03*
X458282Y1408495D03*
X450402D03*
X462642Y1348187D03*
X474882D03*
X470522D03*
X462642Y1360099D03*
X474882D03*
X470522D03*
X462642Y1384297D03*
X470522D03*
X474882D03*
X462642Y1372385D03*
X470522D03*
X474882D03*
X470522Y1396583D03*
X474882D03*
X462642D03*
X470522Y1408495D03*
X474882D03*
X462642D03*
X482762Y1348187D03*
X487122D03*
X482762Y1360099D03*
X487122D03*
Y1372385D03*
Y1384297D03*
X482762D03*
Y1372385D03*
Y1396583D03*
X487122D03*
X482762Y1408495D03*
X487122D03*
X501750Y620661D03*
X505293D03*
X501750Y617861D03*
X505293D03*
X507242Y1348187D03*
X495002D03*
X499362D03*
X507242Y1360099D03*
X495002D03*
X499362D03*
Y1372385D03*
Y1384297D03*
X495002D03*
X507242D03*
X495002Y1372385D03*
X507242D03*
Y1396583D03*
X495002D03*
X499362D03*
X507242Y1408495D03*
X495002D03*
X499362D03*
X512380Y617861D03*
X508836Y620661D03*
Y617861D03*
X512380Y620661D03*
X519482Y1348187D03*
X511602D03*
X519482Y1360099D03*
X511602D03*
X519482Y1384297D03*
Y1372385D03*
X511602D03*
Y1384297D03*
X519482Y1396583D03*
X511602D03*
X519482Y1408495D03*
X511602D03*
X536082Y1348187D03*
X523842D03*
X531722D03*
X536082Y1360099D03*
X523842D03*
X531722D03*
Y1384297D03*
Y1372385D03*
X523842Y1384297D03*
Y1372385D03*
X536082Y1384297D03*
Y1372385D03*
X531722Y1396583D03*
X536082D03*
X523842D03*
X531722Y1408495D03*
X536082D03*
X523842D03*
X548322Y1348187D03*
X556202D03*
X543962D03*
X548322Y1360099D03*
X556202D03*
X543962D03*
Y1372385D03*
Y1384297D03*
X556202D03*
X548322D03*
X556202Y1372385D03*
X548322D03*
X556202Y1396583D03*
X543962D03*
X548322D03*
X556202Y1408495D03*
X543962D03*
X548322D03*
X568442Y1348187D03*
X560562D03*
X568442Y1360099D03*
X560562D03*
Y1384297D03*
X568442D03*
X560562Y1372385D03*
X568442D03*
Y1396583D03*
X560562D03*
X568442Y1408495D03*
X560562D03*
X600295Y1084547D03*
Y1092027D03*
X604035Y1077066D03*
Y1080806D03*
Y1084547D03*
Y1092027D03*
X600295Y1088287D03*
X604035D03*
Y1103247D03*
X600295D03*
Y1095767D03*
X604035D03*
X600295Y1099507D03*
X604035D03*
X600295Y1106988D03*
X604035D03*
X600295Y1110728D03*
Y1118208D03*
X604035Y1110728D03*
Y1118208D03*
Y1121948D03*
X600295D03*
Y1114468D03*
X604035D03*
X600295Y1125688D03*
Y1133169D03*
Y1140649D03*
X604035Y1125688D03*
Y1133169D03*
Y1140649D03*
X600295Y1136909D03*
X604035D03*
X600295Y1129429D03*
X604035D03*
X600295Y1144389D03*
Y1151870D03*
X604035Y1144389D03*
Y1151870D03*
Y1148129D03*
X600295D03*
Y1159350D03*
X604036Y1166830D03*
X604035Y1159350D03*
X597795Y1170570D03*
X604034D03*
X600294D03*
X604034Y1174310D03*
X597795Y1178050D03*
X602165Y1183661D03*
Y1187401D03*
X604034Y1178051D03*
X600294D03*
X602165Y1202362D03*
Y1194881D03*
X598424Y1198622D03*
Y1191142D03*
X602165Y1217322D03*
Y1209842D03*
X598424Y1221063D03*
Y1213583D03*
Y1206103D03*
X602165Y1224803D03*
Y1236023D03*
Y1232283D03*
X598424Y1228542D03*
X602165Y1243503D03*
Y1250984D03*
X598423Y1239762D03*
Y1247242D03*
X611516Y1073326D03*
X618996D03*
X615256D03*
X607776D03*
X618996Y1088287D03*
Y1092027D03*
X607775Y1077066D03*
X611516D03*
X615256Y1080807D03*
X607776D03*
X615256Y1084547D03*
X607776D03*
X615256Y1088287D03*
X611516D03*
X607776D03*
X611516Y1092027D03*
X618996Y1077066D03*
Y1084547D03*
Y1080807D03*
X615256Y1077066D03*
X611516Y1080807D03*
Y1084547D03*
X607776Y1092027D03*
X615256D03*
X611516Y1106988D03*
X607776D03*
X611516Y1095767D03*
X615256Y1099507D03*
X607776D03*
X615256Y1103247D03*
X607776D03*
X615256Y1106988D03*
X618996Y1095767D03*
Y1106988D03*
X607776Y1095767D03*
X615256D03*
X618996Y1103247D03*
X611516D03*
X618996Y1099507D03*
X611516D03*
X615256Y1110728D03*
Y1114468D03*
X611516D03*
X607776D03*
X615256Y1118208D03*
Y1121948D03*
X611516D03*
X607776D03*
X618996Y1114468D03*
Y1118208D03*
Y1121948D03*
X611516Y1118208D03*
X607776D03*
X611516Y1110728D03*
X618996D03*
X607776D03*
X615256Y1125688D03*
Y1129429D03*
X611516D03*
X607776D03*
Y1136909D03*
X615256Y1140649D03*
X611516D03*
X607776D03*
X618996D03*
Y1125688D03*
Y1129429D03*
Y1133169D03*
X611516Y1125688D03*
X607776D03*
Y1133169D03*
X618996Y1144389D03*
Y1148129D03*
Y1151870D03*
Y1155610D03*
X607776Y1144389D03*
X615256Y1151869D03*
X611516D03*
X607776Y1148129D03*
Y1151870D03*
X615256Y1155610D03*
X611516D03*
X607776D03*
Y1159350D03*
X615256Y1166830D03*
X611516D03*
X607775D03*
X611516Y1170570D03*
X607775D03*
X618996Y1159350D03*
Y1174310D03*
Y1178051D03*
X607775Y1174310D03*
Y1178051D03*
X611516Y1174310D03*
X615256D03*
X613386Y1183661D03*
X617126Y1187401D03*
Y1183661D03*
X613386Y1179921D03*
X620866Y1183661D03*
X609646D03*
X605905D03*
Y1187401D03*
X615256Y1178051D03*
X611516D03*
X613386Y1198621D03*
X609646Y1191141D03*
X613386D03*
X617126Y1202362D03*
Y1194881D03*
Y1198621D03*
X620866D03*
X617126Y1191141D03*
X620866D03*
X605905Y1202362D03*
Y1194881D03*
X609646Y1198621D03*
X613386Y1221062D03*
X609646D03*
Y1213582D03*
X613386D03*
X620866Y1206102D03*
X617126D03*
Y1213582D03*
Y1209842D03*
X620866Y1213582D03*
Y1221062D03*
X617126D03*
Y1217322D03*
X613386Y1206102D03*
X605905Y1217322D03*
Y1209842D03*
X609646Y1206102D03*
X605905Y1224803D03*
Y1232283D03*
Y1236023D03*
X620866D03*
Y1232283D03*
X617126Y1228543D03*
Y1224803D03*
X609646D03*
Y1228543D03*
X613386Y1232283D03*
Y1236023D03*
X617126Y1243503D03*
Y1239763D03*
X620866D03*
X613386D03*
X609646Y1243503D03*
Y1239763D03*
X620866Y1254724D03*
Y1250984D03*
X617126Y1247243D03*
X609646D03*
X613386Y1254724D03*
Y1250984D03*
X605905Y1243503D03*
Y1254724D03*
Y1250984D03*
X617126Y1258465D03*
X609646D03*
X626476Y1073326D03*
X635827Y1075196D03*
X628346D03*
X632085Y1071455D03*
X622736Y1073326D03*
X626476Y1077066D03*
Y1088287D03*
Y1092027D03*
X622736Y1080807D03*
Y1084547D03*
Y1088287D03*
X635827Y1090157D03*
X628346Y1078936D03*
Y1090157D03*
X635827Y1078936D03*
X632086Y1090157D03*
Y1082677D03*
Y1086417D03*
X622736Y1077066D03*
X626476Y1084547D03*
X622736Y1092027D03*
X626476Y1080807D03*
X630216Y1099507D03*
X622736D03*
Y1103247D03*
X626476Y1106988D03*
X622736D03*
X626476Y1095767D03*
Y1099507D03*
X630216Y1103247D03*
X635827Y1093897D03*
X632086Y1101377D03*
Y1105117D03*
X628346Y1097637D03*
Y1093897D03*
X635827Y1097637D03*
X622736Y1095767D03*
X626476Y1103247D03*
X633957Y1110728D03*
X630216D03*
X626476D03*
X622736Y1114468D03*
X630216Y1118208D03*
X626476D03*
Y1121948D03*
X633957Y1114468D03*
Y1118208D03*
Y1121948D03*
X635827Y1108858D03*
X632086D03*
X622736Y1118208D03*
X626476Y1114468D03*
X622736Y1110728D03*
X630216Y1114468D03*
X633957Y1140649D03*
Y1125688D03*
Y1129429D03*
Y1133169D03*
Y1136909D03*
X630216Y1140649D03*
X626476D03*
X622736D03*
X630216Y1129428D03*
X626476D03*
X622736Y1129429D03*
X630216Y1136909D03*
X626476D03*
X630216Y1144389D03*
X626476D03*
X630216Y1148129D03*
Y1155610D03*
Y1151870D03*
X633957D03*
Y1148129D03*
Y1144389D03*
X626476Y1148129D03*
X622736Y1144389D03*
Y1148129D03*
X626476Y1151870D03*
X622736Y1155610D03*
Y1166830D03*
Y1170570D03*
X630216Y1159350D03*
Y1166830D03*
Y1170570D03*
X633957D03*
Y1166830D03*
Y1159350D03*
X626476D03*
X622736Y1174310D03*
X633957Y1185531D03*
X628346Y1183661D03*
X630216Y1174310D03*
Y1178051D03*
Y1181791D03*
X622736Y1178050D03*
X632086Y1187401D03*
X628346D03*
X624606Y1183661D03*
X635827Y1187401D03*
X633957Y1174310D03*
Y1178051D03*
Y1181791D03*
X624606Y1191141D03*
X632086Y1202362D03*
X628346D03*
X624606Y1198621D03*
X632086Y1194881D03*
X628346D03*
X635827Y1191141D03*
Y1194881D03*
Y1198621D03*
Y1202362D03*
X624606Y1206102D03*
Y1213582D03*
X632086Y1209842D03*
X628346D03*
Y1217322D03*
Y1221062D03*
X624606D03*
X632086D03*
Y1217322D03*
X635827Y1221062D03*
Y1206102D03*
Y1209842D03*
Y1213582D03*
Y1217322D03*
X632086Y1228543D03*
Y1224803D03*
X624606D03*
Y1228543D03*
X628346Y1236023D03*
Y1232283D03*
X635827Y1236023D03*
Y1232283D03*
X632086Y1247243D03*
Y1243503D03*
X635827Y1239763D03*
X632086D03*
X628346D03*
Y1250984D03*
X624606Y1243503D03*
Y1239763D03*
X635827Y1254724D03*
Y1250984D03*
X628346Y1254724D03*
X624606Y1247243D03*
X632087Y1258465D03*
X624606D03*
X636288Y1372385D03*
Y1384297D03*
X631928Y1396583D03*
X636288D03*
X624048D03*
X631928Y1408495D03*
X636288D03*
X624048D03*
X643307Y1075196D03*
X650787D03*
X647046Y1071455D03*
X639566D03*
X650787Y1078936D03*
X643307Y1090157D03*
X639567D03*
X647047Y1082677D03*
Y1086417D03*
X643307Y1078936D03*
X650787Y1090157D03*
X647047D03*
X639567Y1086417D03*
Y1082677D03*
Y1101377D03*
Y1105117D03*
X647047D03*
Y1101377D03*
X650787Y1097637D03*
X643307D03*
Y1093897D03*
X650787D03*
X637697Y1114468D03*
X648917Y1118208D03*
X645177D03*
X641437D03*
X637697D03*
X648917Y1121948D03*
X645177D03*
X641437D03*
X637697D03*
Y1110728D03*
X652657Y1118208D03*
Y1121948D03*
X650787Y1108858D03*
X647047D03*
X643307D03*
X639567D03*
X645177Y1114468D03*
X641437D03*
X648917D03*
X652657D03*
X641437Y1133169D03*
X637697D03*
X645177Y1136909D03*
X637697D03*
X645177Y1140649D03*
X641437D03*
X652657Y1133169D03*
Y1129429D03*
Y1125688D03*
Y1136909D03*
X637697Y1140649D03*
X648917Y1125688D03*
X645177D03*
X641437D03*
X637697D03*
X645177Y1129429D03*
X641437D03*
X637697D03*
X645177Y1133169D03*
X648917Y1140649D03*
Y1136909D03*
X652657Y1140649D03*
X641437Y1136909D03*
X648917Y1129429D03*
Y1133169D03*
X637697Y1155610D03*
Y1151870D03*
X645177Y1144389D03*
X637697D03*
Y1148129D03*
X645177Y1151870D03*
X648917Y1155610D03*
Y1148129D03*
X652657Y1151869D03*
Y1144389D03*
Y1148129D03*
Y1155610D03*
X648917Y1144389D03*
Y1151869D03*
X641437Y1144389D03*
Y1151870D03*
X645177Y1155610D03*
Y1148129D03*
Y1170570D03*
X637697Y1166830D03*
X645177Y1159350D03*
X637697D03*
Y1170570D03*
X648917Y1166830D03*
X652657Y1159350D03*
Y1170570D03*
X648917Y1159350D03*
Y1170570D03*
X652657Y1166830D03*
X641437Y1170570D03*
X645177Y1166830D03*
X641437Y1159350D03*
X637697Y1189271D03*
X645177Y1185531D03*
X637697D03*
Y1178051D03*
Y1174310D03*
X645177Y1178051D03*
X637697Y1181791D03*
X652657Y1189271D03*
X648917Y1181791D03*
Y1174310D03*
X652657Y1185531D03*
Y1178051D03*
X648917Y1185531D03*
Y1178051D03*
X652657Y1181791D03*
Y1174310D03*
X641437Y1185531D03*
Y1178051D03*
X645177Y1181791D03*
Y1174310D03*
X652657Y1193011D03*
Y1204232D03*
X637697Y1193011D03*
X645177D03*
Y1196751D03*
Y1200491D03*
X641437D03*
Y1204232D03*
X645177D03*
X648917D03*
Y1196751D03*
Y1200491D03*
X641437Y1193011D03*
Y1196751D03*
X652657Y1200491D03*
Y1196751D03*
X648917Y1193011D03*
X652657Y1211712D03*
X648917Y1219192D03*
X641437D03*
Y1211712D03*
X645177D03*
X648917D03*
Y1207972D03*
X645177D03*
X641437D03*
X652657D03*
X639567Y1221062D03*
X647047D03*
X643307D03*
X650787D03*
X652657Y1215452D03*
Y1219192D03*
X641437Y1215452D03*
X648917D03*
X645177D03*
X639567Y1224803D03*
Y1228543D03*
X643307Y1236023D03*
Y1232283D03*
X650787Y1236023D03*
X647047Y1228543D03*
Y1224803D03*
X650787Y1232283D03*
X639567Y1243503D03*
Y1239763D03*
Y1247243D03*
X647047Y1243503D03*
X650787Y1239763D03*
X647047D03*
X643307D03*
X650787Y1254724D03*
Y1250984D03*
X647047Y1247243D03*
X643307Y1254724D03*
Y1250984D03*
X647047Y1258465D03*
X639567D03*
X648528Y1348187D03*
Y1360099D03*
X644168Y1384297D03*
Y1372385D03*
X648528D03*
Y1384297D03*
X644168Y1396583D03*
X648528D03*
X644168Y1408495D03*
X648528D03*
X658268Y1075196D03*
X665748D03*
X669487Y1071455D03*
X662007D03*
X654526D03*
X669488Y1090157D03*
Y1086417D03*
X665748Y1078936D03*
X669488Y1082677D03*
X665748Y1090157D03*
X654527Y1082677D03*
Y1086417D03*
Y1090157D03*
X658268D03*
X662008Y1082677D03*
Y1086417D03*
Y1090157D03*
X658268Y1078936D03*
X662008Y1101377D03*
X665748Y1093897D03*
X658268D03*
X654527Y1105117D03*
Y1101377D03*
X662008Y1105117D03*
X658268Y1097637D03*
X669488Y1101377D03*
Y1105117D03*
X665748Y1097637D03*
X656398Y1118208D03*
Y1121948D03*
X663878Y1118208D03*
X660138D03*
Y1121948D03*
X663878D03*
X667618Y1118208D03*
Y1121948D03*
X669488Y1108858D03*
X665748D03*
X662008D03*
X658268D03*
X654527D03*
X660138Y1114468D03*
X656398D03*
X663878D03*
X667618D03*
X656398Y1140649D03*
X660138D03*
X663878D03*
X656398Y1125688D03*
X660138D03*
X663878D03*
Y1133169D03*
X660138D03*
X656398D03*
X667618D03*
Y1140649D03*
Y1125688D03*
Y1129429D03*
X660138D03*
X656398D03*
X663878D03*
Y1136909D03*
X660138D03*
X656398D03*
X667618D03*
Y1148129D03*
X660138D03*
X656398D03*
X663878D03*
X656398Y1155610D03*
X663878D03*
X660138D03*
X667618D03*
Y1144389D03*
X663878D03*
X660138D03*
X656398D03*
X667618Y1151870D03*
X663878D03*
X660138D03*
X656398D03*
X663878Y1166830D03*
X660138Y1159350D03*
X656398Y1166830D03*
X660138Y1170570D03*
X667618Y1159350D03*
Y1170570D03*
X663878D03*
X660138Y1166830D03*
X656398Y1170570D03*
X663878Y1159350D03*
X656398D03*
X667618Y1166830D03*
X663878Y1181791D03*
X660138D03*
X656398D03*
X663878Y1189271D03*
X660138D03*
X656398D03*
X667618Y1181791D03*
Y1189271D03*
X656398Y1174310D03*
X663878D03*
X667618D03*
X660138D03*
X667618Y1185531D03*
X660138D03*
X656398D03*
X663878D03*
X667618Y1178051D03*
X663878D03*
X660138D03*
X656398D03*
X663878Y1196751D03*
X660138D03*
X656398D03*
Y1204232D03*
X660138D03*
X663878D03*
X667618Y1196751D03*
Y1204232D03*
Y1200491D03*
X656398D03*
X663878D03*
X660138D03*
X663878Y1193011D03*
X660138D03*
X656398D03*
X667618D03*
X663878Y1207972D03*
X660138D03*
X656398D03*
X667618D03*
Y1211712D03*
X654527Y1221062D03*
X658268D03*
X662008D03*
X665748D03*
X669488D03*
X663878Y1211712D03*
X656398D03*
X660138Y1215452D03*
X656398D03*
X663878D03*
X667618D03*
X660138Y1211712D03*
X654527Y1224803D03*
Y1228543D03*
X658268Y1236023D03*
Y1232283D03*
X662008Y1228543D03*
Y1224803D03*
X665748Y1236023D03*
Y1232283D03*
X669488Y1228543D03*
Y1224803D03*
X654527Y1239763D03*
Y1243503D03*
Y1247243D03*
X662008Y1239763D03*
X658268D03*
X669488D03*
X665748D03*
Y1250984D03*
Y1254724D03*
X669488Y1247243D03*
Y1243503D03*
X662008D03*
Y1247243D03*
X658268Y1254724D03*
Y1250984D03*
X662008Y1258465D03*
X669488D03*
X654528D03*
X660768Y1348187D03*
X668648D03*
X656408D03*
X660768Y1360099D03*
X668648D03*
X656408D03*
Y1384297D03*
Y1372385D03*
X668648D03*
X660768D03*
X668648Y1384297D03*
X660768D03*
X668648Y1396583D03*
X656408D03*
X660768D03*
X668648Y1408495D03*
X656408D03*
X660768D03*
X680709Y1075196D03*
X673228D03*
X684448Y1071455D03*
X676967D03*
X680709Y1090157D03*
X676968D03*
X684449D03*
Y1082677D03*
Y1086417D03*
X673228Y1090157D03*
Y1078936D03*
X680709D03*
X676968Y1082677D03*
Y1086417D03*
Y1105117D03*
X684449Y1101377D03*
Y1105117D03*
X680709Y1093897D03*
X676968Y1101377D03*
X680709Y1097637D03*
X673228D03*
Y1093897D03*
X682579Y1118208D03*
Y1121948D03*
X671358Y1114468D03*
Y1118208D03*
X675098D03*
X678838D03*
X675098Y1121948D03*
X678838D03*
X671358D03*
X684449Y1108858D03*
X680709D03*
X676968D03*
X673228D03*
X682579Y1114468D03*
X678839D03*
X675098D03*
X682579Y1133169D03*
Y1140649D03*
Y1125688D03*
X671358Y1140649D03*
X675098D03*
X678838D03*
X675098Y1125688D03*
X671358D03*
X678838D03*
Y1133169D03*
X675098D03*
X671358D03*
X675098Y1129429D03*
X671358D03*
X678838D03*
X682579D03*
Y1136909D03*
X678838D03*
X675098D03*
X671358D03*
X682579Y1148129D03*
X678838D03*
X675098D03*
X671358D03*
Y1155610D03*
X678838D03*
X682579D03*
X675098D03*
X678839Y1151870D03*
X675098D03*
X671358D03*
X682579D03*
Y1144389D03*
X671358D03*
X678838D03*
X675098D03*
X682579Y1170570D03*
Y1159350D03*
X675098Y1170570D03*
X678839Y1166830D03*
X671358D03*
X675098Y1159350D03*
X682579Y1166830D03*
X678838Y1170570D03*
X671358D03*
X675098Y1166830D03*
X671358Y1159350D03*
X678838D03*
X675098Y1181791D03*
X671358D03*
X678838Y1189271D03*
X675098D03*
X671358D03*
X682579Y1181791D03*
Y1189271D03*
X678838Y1181791D03*
X671358Y1174310D03*
X678838D03*
X682579D03*
X675098D03*
X682579Y1185531D03*
X675098D03*
X671358D03*
X678838D03*
X682579Y1178051D03*
X678838D03*
X675098D03*
X671358D03*
X682579Y1196751D03*
Y1204232D03*
X678838D03*
Y1196751D03*
X675098D03*
X671358D03*
Y1204232D03*
X675098D03*
Y1200491D03*
X671358D03*
X678838D03*
X682579D03*
Y1193011D03*
X678838D03*
X675098D03*
X671358D03*
X682579Y1207972D03*
X675098Y1211712D03*
X678838Y1219192D03*
Y1207972D03*
X675098D03*
X671358D03*
X673228Y1221062D03*
X676968D03*
X680709D03*
X684449D03*
X682579Y1211712D03*
X678839D03*
Y1215452D03*
X671358Y1211712D03*
Y1215452D03*
X675098D03*
X673228Y1236023D03*
Y1232283D03*
X676968Y1224803D03*
Y1228543D03*
X680709Y1236023D03*
Y1232283D03*
X684449Y1224803D03*
Y1228543D03*
X673228Y1239763D03*
X676968D03*
X680709D03*
Y1254724D03*
Y1250984D03*
X676968Y1243503D03*
Y1247243D03*
X673228Y1254724D03*
Y1250984D03*
X684449Y1247243D03*
Y1243503D03*
Y1239763D03*
X684450Y1258465D03*
X676969D03*
X680888Y1348187D03*
X673008D03*
X685248D03*
X680888Y1360099D03*
X673008D03*
X685248D03*
Y1372385D03*
Y1384297D03*
X673008Y1372385D03*
Y1384297D03*
X680888Y1372385D03*
Y1384297D03*
Y1396583D03*
X685248D03*
X673008D03*
X680888Y1408495D03*
X685248D03*
X673008D03*
X688189Y1075196D03*
X695669D03*
X699408Y1071455D03*
X691928Y1071454D03*
X688189Y1078936D03*
Y1090157D03*
X691929Y1082677D03*
Y1086417D03*
X695669Y1090157D03*
X699409D03*
Y1086417D03*
X691929Y1090157D03*
X695669Y1078936D03*
X699409Y1082677D03*
X688189Y1097637D03*
X695669Y1093897D03*
X688189D03*
X699409Y1105117D03*
X691929Y1101377D03*
X699409D03*
X695669Y1097637D03*
X691929Y1105117D03*
X693799Y1121948D03*
X697539D03*
X701279D03*
X686319D03*
Y1118208D03*
Y1114468D03*
X699409Y1108858D03*
X695669D03*
X691929D03*
X688189D03*
X693799Y1114468D03*
Y1118208D03*
X701279Y1114468D03*
X697539Y1118208D03*
Y1114468D03*
X701279Y1118208D03*
X693799Y1133464D03*
X697539Y1133169D03*
X686417Y1132677D03*
X693799Y1140649D03*
X697539D03*
X693799Y1125688D03*
X697539D03*
X701279D03*
Y1140649D03*
Y1133169D03*
X686319Y1140649D03*
Y1125688D03*
X701279Y1129429D03*
X697539D03*
X693799D03*
X686319D03*
X697539Y1136909D03*
X693799D03*
X701279D03*
X686319D03*
X697539Y1148129D03*
X701279D03*
X693799D03*
X697539Y1155610D03*
X686319Y1148129D03*
Y1155610D03*
X701279D03*
X693799D03*
X701279Y1151869D03*
X697539D03*
X693799D03*
X701279Y1144389D03*
X697539D03*
X693799D03*
X686319D03*
Y1151870D03*
X697539Y1166830D03*
X693799Y1170570D03*
Y1159350D03*
X701279D03*
Y1170570D03*
X686319Y1166830D03*
X693799D03*
X697539Y1170570D03*
Y1159350D03*
X701279Y1166830D03*
X686319Y1170570D03*
Y1159350D03*
X693799Y1181791D03*
Y1189271D03*
X697539D03*
X701279D03*
Y1181791D03*
X697539D03*
Y1174310D03*
X686319Y1181791D03*
Y1189271D03*
Y1174310D03*
X701279D03*
X693799D03*
X701279Y1185531D03*
X697539D03*
X693799D03*
X701279Y1178051D03*
X697539D03*
X693799D03*
X686319Y1185531D03*
Y1178051D03*
X697539Y1204232D03*
X693799D03*
Y1196751D03*
X697539D03*
X701279D03*
Y1204232D03*
X686319Y1196751D03*
Y1204232D03*
X701279Y1200491D03*
X697539D03*
X693799D03*
X686319D03*
X701279Y1193011D03*
X697539D03*
X693799D03*
X686319D03*
X693799Y1207972D03*
X697539D03*
Y1211712D03*
X701279Y1207972D03*
Y1211712D03*
X686319Y1207972D03*
X695669Y1221062D03*
X699409D03*
X691929D03*
X688189D03*
X686319Y1211712D03*
Y1215452D03*
X699409Y1217322D03*
X697539Y1215452D03*
X693799D03*
Y1211712D03*
X701279Y1215452D03*
X695669Y1217322D03*
X688189Y1236023D03*
Y1232283D03*
X691929Y1224803D03*
Y1228543D03*
X699409Y1224803D03*
Y1228543D03*
X695669Y1236023D03*
Y1232283D03*
X688189Y1254724D03*
Y1250984D03*
Y1239763D03*
X699409Y1247243D03*
Y1243503D03*
Y1239763D03*
X695669D03*
X691929D03*
Y1243503D03*
Y1247243D03*
X695669Y1250984D03*
Y1254724D03*
X699409Y1258465D03*
X691929D03*
X693128Y1348187D03*
X697488D03*
X693128Y1360099D03*
X697488D03*
Y1384297D03*
Y1372385D03*
X693128D03*
Y1384297D03*
Y1396583D03*
X697488D03*
X693128Y1408495D03*
X697488D03*
X703149Y1075196D03*
X718110D03*
X710630D03*
X714369Y1071455D03*
X706889D03*
X710630Y1078936D03*
X706890Y1082677D03*
Y1086417D03*
Y1090157D03*
X718110Y1078936D03*
X714370Y1082677D03*
Y1086417D03*
Y1090157D03*
X710630D03*
X718110D03*
X703149Y1078936D03*
Y1090157D03*
X706890Y1101377D03*
Y1105117D03*
X714370D03*
Y1101377D03*
X710630Y1097637D03*
Y1093897D03*
X718110Y1097637D03*
Y1093897D03*
X703149D03*
Y1097637D03*
X716240Y1121948D03*
X705020D03*
X708760D03*
X712500D03*
X718110Y1108858D03*
X714370D03*
X710630D03*
X706890D03*
X703149D03*
X708760Y1114468D03*
X716240Y1118208D03*
X705020Y1114468D03*
X712500D03*
X716240D03*
X705020Y1118208D03*
X712500D03*
X708760D03*
X716240Y1140649D03*
Y1125688D03*
Y1133169D03*
X712500Y1125688D03*
X708760D03*
X705020D03*
X712500Y1140649D03*
X708760D03*
X705020D03*
X712500Y1133169D03*
X708760D03*
X705020D03*
Y1129429D03*
X708760D03*
X712500D03*
X716240D03*
Y1136909D03*
X705020D03*
X708760D03*
X712500D03*
X716240Y1148129D03*
X712500D03*
X708760D03*
X705020D03*
X712500Y1155610D03*
X705020D03*
X708760D03*
X716240D03*
Y1151869D03*
X708760D03*
X712500D03*
X705020D03*
X712500Y1144389D03*
X705020D03*
X708760D03*
X716240D03*
Y1170570D03*
Y1159350D03*
X708760D03*
X705020Y1166830D03*
X712500D03*
X708760Y1170570D03*
X716240Y1166830D03*
X705020Y1159350D03*
X712500D03*
X705020Y1170570D03*
X712500D03*
X708760Y1166830D03*
X716240Y1189271D03*
Y1181791D03*
X712500Y1189271D03*
X708760D03*
X705020D03*
X712500Y1181791D03*
X708760D03*
X705020D03*
Y1174310D03*
X712500D03*
X716240D03*
X708760D03*
X716240Y1185531D03*
X708760D03*
X712500D03*
X705020D03*
X716240Y1178051D03*
X712500D03*
X705020D03*
X708760D03*
X716240Y1196751D03*
Y1204232D03*
X712500Y1196751D03*
X708760D03*
X705020D03*
X708760Y1204232D03*
X712500D03*
X705020D03*
X712500Y1200491D03*
X705020D03*
X708760D03*
X716240D03*
X708760Y1193011D03*
X712500D03*
X705020D03*
X716240D03*
Y1211712D03*
Y1207972D03*
X712500D03*
Y1211712D03*
X708760Y1207972D03*
X705020D03*
X703149Y1221062D03*
X706890D03*
X710630D03*
X714370D03*
X718110D03*
X716240Y1215452D03*
X708760D03*
X712500D03*
X705019Y1215451D03*
Y1211711D03*
X708760D03*
X703149Y1236023D03*
Y1232283D03*
X710630Y1236023D03*
X718110D03*
Y1232283D03*
X710630D03*
X714370Y1224803D03*
Y1228543D03*
X706890Y1224803D03*
Y1228543D03*
X703149Y1254724D03*
Y1250984D03*
Y1239763D03*
X714370D03*
X718110Y1250984D03*
Y1239763D03*
X714370Y1243503D03*
Y1247243D03*
X710630Y1254724D03*
Y1250984D03*
Y1239763D03*
X706890Y1247243D03*
Y1243503D03*
Y1239763D03*
X718110Y1254724D03*
X714370Y1258465D03*
X706890D03*
X705368Y1348187D03*
X717608D03*
X709728D03*
X705368Y1360099D03*
X717608D03*
X709728D03*
Y1384297D03*
Y1372385D03*
X705368D03*
Y1384297D03*
X717608Y1372385D03*
Y1384297D03*
Y1396583D03*
X705368D03*
X709728D03*
X717608Y1408495D03*
X705368D03*
X709728D03*
X725590Y1075196D03*
X733071D03*
X729330Y1071455D03*
X721849D03*
X721850Y1082677D03*
X729331Y1086417D03*
Y1082677D03*
X733071Y1090157D03*
Y1078936D03*
X729331Y1090157D03*
X725590D03*
X721850D03*
X725590Y1078936D03*
X721850Y1086417D03*
X729331Y1101377D03*
X725590Y1097637D03*
X721850Y1101377D03*
Y1105117D03*
X725590Y1093897D03*
X729331Y1105117D03*
X733071Y1093897D03*
Y1097637D03*
X734941Y1121948D03*
Y1118208D03*
X727460Y1121948D03*
X719980D03*
X723720D03*
X727460Y1118208D03*
X731201Y1121948D03*
Y1118208D03*
X733071Y1108858D03*
X729331D03*
X725590D03*
X721850D03*
X731201Y1114468D03*
X734941D03*
X727460D03*
X719980Y1118208D03*
Y1114468D03*
X734941Y1129429D03*
Y1125688D03*
Y1140649D03*
Y1133169D03*
Y1136909D03*
X727460Y1140649D03*
X723720Y1125688D03*
X719980D03*
X727460Y1129429D03*
Y1125688D03*
X723720Y1140649D03*
X719980D03*
X727460Y1133169D03*
X723720D03*
X719980D03*
X727460Y1136909D03*
X731201Y1125688D03*
X719980Y1129429D03*
X723720D03*
X731201D03*
X719980Y1136909D03*
X723720D03*
X731201D03*
Y1140649D03*
X727460Y1151869D03*
Y1148129D03*
Y1144389D03*
X723720Y1148129D03*
X719980D03*
X731201D03*
Y1151869D03*
Y1155610D03*
X734941Y1151870D03*
Y1148129D03*
Y1144389D03*
X719980Y1155610D03*
X727460D03*
X723720D03*
X719980Y1151869D03*
X723720D03*
Y1144389D03*
X719980D03*
X734941Y1155610D03*
X731201Y1144389D03*
Y1170570D03*
X719980Y1166830D03*
X731201Y1159350D03*
Y1166830D03*
X719980Y1159350D03*
X727460D03*
X723720D03*
Y1166830D03*
X727460D03*
X719980Y1170570D03*
X727460D03*
X723720D03*
X734941Y1159350D03*
Y1166830D03*
Y1170570D03*
X727460Y1185531D03*
X734941Y1181791D03*
Y1185531D03*
Y1189271D03*
Y1178051D03*
X727460Y1189271D03*
X723720Y1181791D03*
X719980D03*
Y1174310D03*
X727460Y1178051D03*
X723720Y1189271D03*
X719980D03*
X731201Y1174310D03*
Y1181791D03*
X727460Y1174310D03*
X723720D03*
X727460Y1181791D03*
X719980Y1185531D03*
Y1178051D03*
X723720D03*
Y1185531D03*
X734941Y1174310D03*
X731201Y1189271D03*
Y1185531D03*
Y1178051D03*
X719980Y1204232D03*
X727460D03*
X727480Y1196732D03*
X731201Y1196751D03*
Y1204232D03*
X734941Y1193011D03*
X727460D03*
X723720Y1196751D03*
X719980D03*
X727460Y1200491D03*
X723720Y1204232D03*
X719980Y1200491D03*
X723720D03*
X731201D03*
X719980Y1193011D03*
X723720D03*
X731201D03*
X734941Y1196751D03*
Y1204232D03*
Y1200491D03*
Y1211712D03*
X727460Y1207972D03*
X723720Y1211712D03*
Y1207972D03*
X719980Y1211712D03*
Y1207972D03*
X727460Y1211712D03*
X731201Y1207972D03*
X733071Y1221062D03*
X721850D03*
X725590D03*
X729331D03*
X731201Y1215452D03*
X734941D03*
X723720D03*
X719980D03*
X731201Y1211712D03*
X734941Y1207972D03*
X727461Y1215452D03*
X729331Y1224803D03*
Y1228543D03*
X733071Y1236023D03*
Y1232283D03*
X725590Y1236023D03*
Y1232283D03*
X721850Y1224803D03*
Y1228543D03*
X733071Y1239763D03*
X729331Y1243503D03*
X721850D03*
X725590Y1239763D03*
X729331D03*
X721850D03*
X729331Y1247243D03*
X733071Y1250984D03*
Y1254724D03*
X725590D03*
Y1250984D03*
X721850Y1247243D03*
X729331Y1258465D03*
X721850D03*
X734208Y1348187D03*
X729848D03*
X721968D03*
X734208Y1360099D03*
X729848D03*
X721968D03*
X729848Y1372385D03*
Y1384297D03*
X721968D03*
Y1372385D03*
X734208D03*
Y1384297D03*
X729848Y1396489D03*
X721968D03*
X734208D03*
X729848Y1408401D03*
X721968D03*
X734208D03*
X740551Y1075196D03*
X748031D03*
X744290Y1071455D03*
X736810D03*
X748030Y1090157D03*
X744291Y1082677D03*
X748031Y1078936D03*
X744291Y1090157D03*
Y1086417D03*
X740551Y1078936D03*
Y1090157D03*
X736811Y1086417D03*
Y1090157D03*
Y1082677D03*
X744291Y1101377D03*
X740551Y1097637D03*
X748031Y1093897D03*
Y1097637D03*
X740551Y1093897D03*
X744291Y1105117D03*
X736811D03*
Y1101377D03*
X748031Y1123818D03*
Y1120078D03*
Y1116338D03*
Y1112598D03*
Y1108858D03*
X744291D03*
X740551D03*
X736811D03*
X738681Y1118208D03*
X742421D03*
X738681Y1114468D03*
X742421D03*
X738681Y1136909D03*
Y1140649D03*
X748031Y1138779D03*
Y1135039D03*
Y1131299D03*
Y1127558D03*
X742421Y1140649D03*
Y1136909D03*
X746161Y1140649D03*
X749902D03*
X738681Y1155610D03*
Y1148129D03*
X749901Y1144389D03*
Y1151869D03*
X746161Y1144389D03*
Y1155610D03*
Y1151869D03*
X742421D03*
X738681D03*
X742421Y1155610D03*
X746161Y1148129D03*
X738681Y1144389D03*
X742421Y1148129D03*
Y1144389D03*
X749902Y1155610D03*
Y1148129D03*
X738681Y1166830D03*
X746161Y1170570D03*
Y1166830D03*
X738681Y1159350D03*
X749901Y1166830D03*
Y1159350D03*
X738681Y1170570D03*
X746161Y1159350D03*
X742421D03*
Y1166830D03*
Y1170570D03*
X749902D03*
X749901Y1181791D03*
Y1174310D03*
X738681D03*
Y1178051D03*
X742421Y1181791D03*
X738681Y1185531D03*
Y1189271D03*
X746161Y1185531D03*
Y1178051D03*
Y1174310D03*
X742421Y1185531D03*
Y1189271D03*
X746161D03*
X742421Y1174310D03*
X738681Y1181791D03*
X746161D03*
X742421Y1178051D03*
X748031Y1191141D03*
X738681Y1204232D03*
X748031Y1194881D03*
X738681Y1193011D03*
Y1196751D03*
X742421Y1193011D03*
X748031Y1202362D03*
Y1198621D03*
X742421Y1196751D03*
X738681Y1200491D03*
X742421Y1204232D03*
Y1200491D03*
X736811Y1221062D03*
X740551D03*
X748031D03*
X744291D03*
X748031Y1217322D03*
Y1213582D03*
Y1209842D03*
Y1206102D03*
X742421Y1211712D03*
Y1215452D03*
Y1207972D03*
X738681Y1215452D03*
Y1207972D03*
Y1211712D03*
X736811Y1224803D03*
Y1228543D03*
X748031Y1236023D03*
Y1232283D03*
X740551Y1236023D03*
X744291Y1228543D03*
X740551Y1232283D03*
X744291Y1224803D03*
X736811Y1243503D03*
Y1239763D03*
Y1247243D03*
X748031Y1239763D03*
X744291Y1243503D03*
Y1239763D03*
X740551D03*
X748031Y1254724D03*
Y1250984D03*
X744291Y1247243D03*
X740551Y1254724D03*
Y1250984D03*
X744291Y1258465D03*
X736811D03*
X746448Y1348187D03*
X742088D03*
X746448Y1360099D03*
X742088D03*
Y1384297D03*
Y1372385D03*
X746448D03*
Y1384297D03*
X742088Y1396489D03*
Y1408401D03*
X755512Y1075196D03*
X762993D03*
X766732Y1071455D03*
X759252D03*
X751771D03*
X759251Y1082677D03*
X766731Y1090157D03*
X751772Y1086417D03*
X751771Y1090157D03*
Y1082677D03*
X759251Y1090157D03*
X762991D03*
X759252Y1086417D03*
X755511Y1090157D03*
X766732Y1086417D03*
X762993Y1078936D03*
X766731Y1082677D03*
X755513Y1078936D03*
X751771Y1101377D03*
X751772Y1105117D03*
X762992Y1097637D03*
Y1093897D03*
X759252Y1105117D03*
X766732D03*
X755512Y1097637D03*
X759252Y1101377D03*
X766732D03*
X755512Y1093897D03*
X762992Y1116338D03*
X766732Y1120078D03*
X762991Y1108857D03*
X766731Y1108858D03*
X766732Y1116338D03*
Y1123818D03*
X762992D03*
X766732Y1112598D03*
X755512Y1108858D03*
X759252D03*
X751772D03*
X759252Y1116338D03*
X755512Y1120078D03*
X759252Y1123818D03*
X751771Y1112598D03*
Y1120078D03*
X757382Y1140649D03*
X761122D03*
X764862D03*
X762992Y1131299D03*
X766732D03*
Y1135039D03*
Y1127558D03*
X755512D03*
X759252Y1131299D03*
X755512Y1135039D03*
X751772Y1127558D03*
Y1135039D03*
X764862Y1155610D03*
Y1148129D03*
X753642Y1144389D03*
X757382D03*
Y1148129D03*
Y1151869D03*
Y1155610D03*
X761122Y1148129D03*
Y1155610D03*
X753642Y1151869D03*
X761122Y1144389D03*
Y1151869D03*
X753642Y1155610D03*
X764862Y1151869D03*
Y1144389D03*
Y1159350D03*
Y1170570D03*
X757382Y1166830D03*
Y1170570D03*
X761122D03*
X753642Y1166830D03*
X757382Y1159350D03*
X753642D03*
X764862Y1166830D03*
X761122D03*
Y1159350D03*
X753642Y1170570D03*
Y1181791D03*
Y1174310D03*
X757382D03*
Y1178051D03*
Y1181791D03*
Y1185531D03*
X764862D03*
Y1178051D03*
X755512Y1187401D03*
X761122Y1178051D03*
Y1185531D03*
X753642Y1189271D03*
X764862D03*
Y1174310D03*
X761122Y1181791D03*
X764862D03*
X761122Y1174310D03*
X766732Y1194881D03*
X759252Y1191141D03*
X762992D03*
X755512Y1194881D03*
X751772D03*
X755512Y1202362D03*
X766732D03*
Y1198621D03*
X762992D03*
X759252D03*
X751772Y1202362D03*
X766732Y1221062D03*
Y1217322D03*
X762992Y1221062D03*
X759252D03*
X755512D03*
Y1217322D03*
X759252Y1213582D03*
X762992D03*
X766732D03*
Y1209842D03*
X755512D03*
X766732Y1206102D03*
X762992D03*
X759252D03*
X751772Y1221062D03*
Y1217322D03*
Y1209842D03*
X759252Y1224803D03*
Y1228543D03*
X755512Y1232283D03*
Y1236023D03*
X766732Y1224803D03*
Y1228543D03*
X762992Y1232283D03*
Y1236023D03*
X751772Y1224803D03*
Y1228543D03*
X755512Y1250984D03*
Y1254724D03*
X759252Y1247243D03*
Y1243503D03*
X762992Y1250984D03*
Y1254724D03*
X766732Y1247243D03*
Y1243503D03*
X755512Y1239763D03*
X759252D03*
X762992D03*
X766732D03*
X751772Y1247243D03*
Y1243503D03*
Y1239763D03*
X766732Y1258465D03*
X759252D03*
X751772D03*
X766568Y1348187D03*
X758688D03*
X754328D03*
X766568Y1360099D03*
X758688D03*
X754328D03*
Y1372385D03*
Y1384297D03*
X758688Y1372385D03*
X766568D03*
X758688Y1384297D03*
X766568D03*
X777953Y1075196D03*
X770473D03*
X774212Y1071455D03*
Y1090157D03*
X777953Y1078936D03*
X781693D03*
X770473D03*
X774213Y1086417D03*
X774212Y1082677D03*
X770471Y1090157D03*
X781693Y1086417D03*
X777953D03*
X770472Y1097637D03*
X777953Y1093897D03*
X774212Y1101377D03*
X777953Y1105117D03*
X774213D03*
X770472Y1093897D03*
X781693D03*
Y1097637D03*
X777953D03*
X781693Y1105117D03*
Y1112598D03*
X770472Y1123818D03*
X777953Y1120078D03*
X781693D03*
X774212Y1123818D03*
X770472Y1108858D03*
X774212D03*
X770472Y1116338D03*
X774212D03*
X777953Y1112598D03*
X783563Y1140649D03*
X776083D03*
X779823D03*
X781693Y1127558D03*
X777953D03*
X774212Y1131299D03*
X770471D03*
X777953Y1135039D03*
X781693D03*
X770472Y1138779D03*
X768602Y1140649D03*
X772342D03*
X783563Y1155610D03*
Y1148129D03*
X776083D03*
Y1151869D03*
X772342D03*
X776083Y1155610D03*
X772342Y1144389D03*
X768602Y1151869D03*
Y1144389D03*
X776083D03*
X779823Y1155610D03*
Y1148129D03*
X772342D03*
Y1155610D03*
X783563Y1151870D03*
X779823D03*
Y1144389D03*
X783563D03*
X768602Y1155610D03*
Y1148129D03*
X783563Y1170570D03*
Y1166830D03*
X776083D03*
Y1170570D03*
X772342Y1166830D03*
X768602Y1159350D03*
X776083D03*
X772342D03*
X768602Y1166830D03*
X779823D03*
Y1170570D03*
Y1159350D03*
X772342Y1170570D03*
X768602D03*
X783563Y1159350D03*
X776083Y1174310D03*
X772342D03*
X776083Y1178051D03*
Y1181791D03*
Y1185531D03*
X772342Y1181791D03*
X779823Y1185531D03*
Y1178051D03*
X783563Y1185531D03*
Y1178051D03*
X768602Y1181791D03*
Y1174310D03*
X772342Y1189271D03*
X783563D03*
X768602Y1185531D03*
X772342Y1178051D03*
X779823Y1189271D03*
X772342Y1185531D03*
X783563Y1174310D03*
X779823D03*
X783563Y1181791D03*
X768602Y1178051D03*
X779823Y1181791D03*
X783503Y1193011D03*
X776083Y1196751D03*
X772342D03*
X776083Y1193011D03*
X779823D03*
X781693Y1202362D03*
X777953D03*
X774212Y1198621D03*
X770472D03*
X768602Y1193011D03*
X772342D03*
X781693Y1217322D03*
X777953D03*
X774212Y1221062D03*
X770472D03*
X781693Y1209842D03*
X777953D03*
X774212Y1213582D03*
X770472D03*
X774212Y1206102D03*
X770472D03*
X781693Y1224803D03*
X777953D03*
X774212D03*
Y1228543D03*
X770472Y1236023D03*
Y1232283D03*
X781693D03*
X777953D03*
Y1236023D03*
X781693D03*
X770472Y1250984D03*
Y1254724D03*
X781693Y1250984D03*
X777953D03*
X774212Y1247243D03*
Y1243503D03*
X777953D03*
X781693D03*
X770472Y1239763D03*
X774212D03*
X777953Y1254724D03*
X774212Y1258465D03*
X778808Y1348187D03*
X770928D03*
X778808Y1360099D03*
X770928D03*
X785434Y1090158D03*
Y1082677D03*
Y1101378D03*
Y1123819D03*
Y1116339D03*
Y1108859D03*
Y1131300D03*
Y1198621D03*
Y1221062D03*
Y1213582D03*
Y1206102D03*
Y1228543D03*
Y1247243D03*
Y1239762D03*
X920349Y450340D03*
X917549D03*
X920349Y453884D03*
Y457427D03*
X917549Y453884D03*
Y457427D03*
X920349Y460970D03*
X917549D03*
X962380Y617861D03*
X958837D03*
X962380Y620661D03*
X958837D03*
X969467D03*
X965923Y617861D03*
Y620661D03*
X969467Y617861D03*
X1057381Y1092027D03*
Y1084547D03*
Y1088287D03*
Y1095767D03*
Y1103247D03*
Y1106988D03*
Y1099507D03*
Y1118208D03*
Y1110728D03*
Y1114468D03*
Y1121948D03*
Y1140649D03*
Y1133169D03*
Y1125688D03*
Y1129429D03*
Y1136909D03*
Y1151870D03*
Y1144389D03*
Y1148129D03*
X1054881Y1170570D03*
X1057381Y1159350D03*
X1057380Y1170570D03*
X1054881Y1178050D03*
X1059251Y1187401D03*
Y1183661D03*
X1057380Y1178051D03*
X1059251Y1194881D03*
Y1202362D03*
X1055510Y1198622D03*
Y1191142D03*
X1059251Y1209842D03*
Y1217322D03*
X1055510Y1221063D03*
Y1213583D03*
Y1206103D03*
X1059251Y1232283D03*
Y1236023D03*
Y1224803D03*
X1055510Y1228542D03*
X1059251Y1243503D03*
Y1250984D03*
X1055509Y1239762D03*
Y1247242D03*
X1052473Y1348187D03*
Y1360099D03*
Y1384297D03*
Y1372385D03*
X1068602Y1073326D03*
X1072342D03*
X1064862D03*
X1072342Y1088287D03*
Y1084547D03*
Y1080807D03*
X1064861Y1077066D03*
X1061121Y1092027D03*
X1068602D03*
X1064862Y1088287D03*
X1068602D03*
X1061121Y1084547D03*
X1064862D03*
Y1080807D03*
X1061121Y1080806D03*
Y1077066D03*
X1068602D03*
X1064862Y1092027D03*
X1072342Y1077066D03*
X1068602Y1084547D03*
Y1080807D03*
X1061121Y1088287D03*
X1072342Y1092027D03*
Y1099507D03*
Y1106988D03*
Y1103247D03*
X1061121Y1095767D03*
X1068602D03*
X1064862Y1106988D03*
X1068602D03*
X1061121Y1103247D03*
X1064862D03*
Y1099507D03*
X1068602D03*
X1072342Y1095767D03*
X1061121Y1106988D03*
X1068602Y1103247D03*
X1064862Y1095767D03*
X1061121Y1099507D03*
X1072342Y1121948D03*
Y1118208D03*
Y1114468D03*
Y1110728D03*
X1064862Y1121948D03*
X1068602D03*
X1061121Y1118208D03*
X1064862Y1114468D03*
X1068602D03*
X1061121Y1110728D03*
Y1114468D03*
X1068602Y1110728D03*
Y1118208D03*
X1064862Y1110728D03*
Y1118208D03*
X1061121Y1121948D03*
X1072342Y1140649D03*
Y1129429D03*
Y1125688D03*
X1061121D03*
Y1140649D03*
X1064862D03*
X1068602D03*
X1064862Y1136909D03*
X1061121Y1133169D03*
X1064862Y1129429D03*
X1068602D03*
X1064862Y1125688D03*
X1068602D03*
X1061121Y1129429D03*
X1064862Y1133169D03*
X1061121Y1136909D03*
X1072342Y1155610D03*
Y1151869D03*
X1064862Y1155610D03*
X1068602D03*
X1061121Y1151870D03*
X1064862D03*
Y1148129D03*
X1068602Y1151869D03*
X1061121Y1144389D03*
X1064862D03*
X1061121Y1148129D03*
X1072342Y1166830D03*
X1064861Y1170570D03*
X1068602D03*
X1064861Y1166830D03*
X1068602D03*
X1061121Y1159350D03*
X1064862D03*
X1061122Y1166830D03*
X1061120Y1170570D03*
X1072342Y1181791D03*
Y1174310D03*
X1061120Y1181791D03*
X1064861D03*
X1068602D03*
Y1174310D03*
X1064861Y1178051D03*
X1061120Y1174310D03*
X1064861D03*
X1074212Y1187401D03*
X1062991D03*
Y1183661D03*
X1066732D03*
X1070472D03*
X1074212D03*
X1072342Y1178051D03*
X1068602D03*
X1061120D03*
X1074212Y1191141D03*
Y1198621D03*
Y1194881D03*
Y1202362D03*
X1070472Y1191141D03*
X1066732D03*
X1070472Y1198621D03*
X1066732D03*
X1062991Y1194881D03*
Y1202362D03*
X1074212Y1206102D03*
X1066732D03*
X1070472D03*
X1074212Y1217322D03*
Y1209842D03*
Y1213582D03*
X1070472D03*
X1066732D03*
X1062991Y1209842D03*
Y1217322D03*
X1074212Y1221062D03*
X1066732D03*
X1070472D03*
Y1236023D03*
Y1232283D03*
X1066732Y1228543D03*
Y1224803D03*
X1074212D03*
Y1228543D03*
X1062991Y1236023D03*
Y1232283D03*
Y1224803D03*
X1070472Y1250984D03*
Y1254724D03*
X1066732Y1247243D03*
X1074212D03*
X1066732Y1239763D03*
Y1243503D03*
X1070472Y1239763D03*
X1074212D03*
Y1243503D03*
X1062991Y1250984D03*
Y1254724D03*
Y1243503D03*
X1074212Y1258465D03*
X1066732D03*
X1072593Y1348187D03*
X1064713D03*
X1060353D03*
X1072593Y1360099D03*
X1064713D03*
X1060353D03*
X1072593Y1384297D03*
Y1372385D03*
X1064713D03*
Y1384297D03*
X1060353D03*
Y1372385D03*
X1072593Y1396583D03*
X1064713D03*
X1072593Y1408495D03*
X1064713D03*
X1083562Y1073326D03*
X1076082D03*
X1089171Y1071455D03*
X1079822Y1073326D03*
X1083562Y1092027D03*
Y1088287D03*
Y1077066D03*
X1079822Y1088287D03*
Y1084547D03*
Y1080807D03*
X1076082Y1092027D03*
Y1088287D03*
Y1077066D03*
X1089172Y1082677D03*
Y1086417D03*
Y1090157D03*
X1079822Y1092027D03*
X1083562Y1084547D03*
X1079822Y1077066D03*
X1076082Y1084547D03*
Y1080807D03*
X1083562D03*
Y1099507D03*
Y1095767D03*
X1087302Y1106988D03*
X1079822D03*
X1083562D03*
X1079822Y1103247D03*
Y1099507D03*
X1076082Y1106988D03*
Y1095767D03*
X1089172Y1101377D03*
Y1105117D03*
X1076082Y1103247D03*
X1079822Y1095767D03*
X1076082Y1099507D03*
X1083562Y1103247D03*
Y1121948D03*
Y1118208D03*
X1087302D03*
X1079822Y1114468D03*
X1083562Y1110728D03*
X1087302D03*
X1091043D03*
Y1121948D03*
Y1118208D03*
Y1114468D03*
X1076082D03*
X1089172Y1108858D03*
X1079822Y1118208D03*
X1076082Y1121948D03*
Y1118208D03*
X1079822Y1110728D03*
X1083562Y1114468D03*
X1087302D03*
X1076082Y1110728D03*
X1091043Y1125688D03*
Y1140649D03*
X1083562Y1136909D03*
X1087302D03*
X1079822Y1129429D03*
X1083562Y1129428D03*
X1087302D03*
X1079822Y1140649D03*
X1083562D03*
X1087302D03*
X1091043Y1136909D03*
Y1133169D03*
Y1129429D03*
X1076082Y1133169D03*
Y1129429D03*
Y1125688D03*
Y1140649D03*
X1087302Y1151870D03*
Y1155610D03*
Y1148129D03*
X1083562Y1144389D03*
X1087302D03*
X1076082Y1155610D03*
Y1151870D03*
Y1148129D03*
Y1144389D03*
X1091043Y1151870D03*
Y1148129D03*
Y1144389D03*
X1083562Y1148129D03*
X1079822Y1144389D03*
Y1148129D03*
X1083562Y1151870D03*
X1079822Y1155610D03*
X1087302Y1170570D03*
Y1166830D03*
Y1159350D03*
X1079822Y1170570D03*
Y1166830D03*
X1091043Y1170570D03*
X1076082Y1159350D03*
X1091043Y1166830D03*
Y1159350D03*
X1083562D03*
X1079822Y1174310D03*
Y1178050D03*
X1081692Y1179921D03*
X1083562Y1181791D03*
X1087302D03*
Y1178051D03*
Y1174310D03*
X1076082Y1181791D03*
Y1178051D03*
Y1174310D03*
X1077952Y1183661D03*
X1081692D03*
X1085432D03*
X1089172Y1187401D03*
X1085432D03*
X1091043Y1185531D03*
Y1181791D03*
Y1178051D03*
Y1174310D03*
X1077952Y1191141D03*
Y1198621D03*
X1081692D03*
Y1191141D03*
X1085432Y1194881D03*
X1089172D03*
X1085432Y1202362D03*
X1089172D03*
X1077952Y1206102D03*
Y1213582D03*
X1081692Y1206102D03*
Y1213582D03*
X1085432Y1209842D03*
X1089172D03*
X1077952Y1221062D03*
X1089172Y1217322D03*
Y1221062D03*
X1081692D03*
X1085432D03*
Y1217322D03*
X1077952Y1232283D03*
Y1236023D03*
X1085432Y1232283D03*
Y1236023D03*
X1081692Y1228543D03*
Y1224803D03*
X1089172D03*
Y1228543D03*
X1077952Y1250984D03*
Y1254724D03*
Y1239763D03*
X1081692Y1247243D03*
X1085432Y1254724D03*
X1081692Y1239763D03*
Y1243503D03*
X1085432Y1250984D03*
Y1239763D03*
X1089172D03*
Y1243503D03*
Y1247243D03*
X1089173Y1258465D03*
X1081692D03*
X1089193Y1348187D03*
X1084833D03*
X1076953D03*
X1089193Y1360099D03*
X1084833D03*
X1076953D03*
X1089193Y1384297D03*
Y1372385D03*
X1084833Y1384297D03*
Y1372385D03*
X1076953Y1384297D03*
Y1372385D03*
X1089193Y1396583D03*
X1084833D03*
X1076953D03*
X1089193Y1408495D03*
X1084833D03*
X1076953D03*
X1092913Y1075196D03*
X1107873D03*
X1100393D03*
X1104132Y1071455D03*
X1096652D03*
X1092913Y1078936D03*
Y1090157D03*
X1104133Y1086417D03*
Y1090157D03*
Y1082677D03*
X1107873Y1090157D03*
Y1078936D03*
X1100393D03*
Y1090157D03*
X1096653Y1082677D03*
Y1086417D03*
Y1090157D03*
X1092913Y1093897D03*
Y1097637D03*
X1107873Y1093897D03*
Y1097637D03*
X1104133Y1101377D03*
X1100393Y1097637D03*
Y1093897D03*
X1096653Y1101377D03*
X1104133Y1105117D03*
X1096653D03*
X1094783Y1110728D03*
Y1121948D03*
X1098523D03*
X1102263D03*
X1106003D03*
X1094783Y1118208D03*
X1098523D03*
X1102263D03*
X1106003D03*
X1094783Y1114468D03*
X1107873Y1108858D03*
X1104133D03*
X1100393D03*
X1096653D03*
X1092913D03*
X1102263Y1114468D03*
X1098523D03*
X1106003D03*
X1098523Y1140649D03*
X1102263D03*
X1094783Y1136909D03*
X1102263D03*
X1094783Y1133169D03*
X1098523D03*
X1102263D03*
X1094783Y1129429D03*
X1098523D03*
X1102263D03*
X1094783Y1125688D03*
X1098523D03*
X1102263D03*
X1106003D03*
X1094783Y1140649D03*
X1106003D03*
Y1136909D03*
X1098523D03*
X1106003Y1129429D03*
Y1133169D03*
X1094783Y1151870D03*
Y1155610D03*
X1102263Y1151870D03*
X1094783Y1148129D03*
Y1144389D03*
X1102263D03*
X1106003Y1148129D03*
Y1155610D03*
Y1151869D03*
Y1144389D03*
X1098523D03*
Y1151870D03*
X1102263Y1148129D03*
Y1155610D03*
Y1170570D03*
X1094783D03*
Y1159350D03*
X1102263D03*
X1094783Y1166830D03*
X1106003D03*
Y1170570D03*
Y1159350D03*
X1102263Y1166830D03*
X1098523Y1159350D03*
Y1170570D03*
X1102263Y1178051D03*
X1094783Y1181791D03*
X1102263Y1185531D03*
X1094783Y1174310D03*
Y1178051D03*
X1106003Y1181791D03*
Y1174310D03*
X1092913Y1187401D03*
X1106003Y1178051D03*
Y1185531D03*
X1098523D03*
X1102263Y1174310D03*
X1098523Y1178051D03*
X1102263Y1181791D03*
X1098523Y1196751D03*
Y1193011D03*
X1106003Y1200491D03*
Y1196751D03*
Y1204232D03*
X1102263D03*
X1098523D03*
Y1200491D03*
X1102263D03*
Y1196751D03*
Y1193011D03*
X1092913Y1191141D03*
Y1194881D03*
Y1198621D03*
Y1202362D03*
X1106003Y1193011D03*
X1098523Y1207972D03*
X1102263D03*
X1106003D03*
Y1211712D03*
X1102263D03*
X1098523D03*
Y1219192D03*
X1106003D03*
X1092913Y1206102D03*
Y1209842D03*
Y1213582D03*
Y1217322D03*
X1107873Y1221062D03*
X1104133D03*
X1100393D03*
X1096653D03*
X1092913D03*
X1106003Y1215452D03*
X1098523D03*
X1102263D03*
X1092913Y1232283D03*
Y1236023D03*
X1107873Y1232283D03*
X1104133Y1224803D03*
Y1228543D03*
X1107873Y1236023D03*
X1100393Y1232283D03*
Y1236023D03*
X1096653Y1228543D03*
Y1224803D03*
X1092913Y1250984D03*
Y1254724D03*
Y1239763D03*
X1100393Y1250984D03*
Y1254724D03*
X1104133Y1247243D03*
X1107873Y1250984D03*
Y1254724D03*
X1100393Y1239763D03*
X1104133D03*
X1107873D03*
X1104133Y1243503D03*
X1096653Y1247243D03*
Y1239763D03*
Y1243503D03*
X1104133Y1258465D03*
X1096653D03*
X1101433Y1348187D03*
X1097073D03*
X1101433Y1360099D03*
X1097073D03*
X1101433Y1384297D03*
Y1372385D03*
X1097073D03*
Y1384297D03*
X1101433Y1396583D03*
X1097073D03*
X1101433Y1408495D03*
X1097073D03*
X1115354Y1075196D03*
X1122834D03*
X1119093Y1071455D03*
X1111612D03*
X1115354Y1090157D03*
Y1078936D03*
X1119094Y1082677D03*
Y1086417D03*
Y1090157D03*
X1122834D03*
Y1078936D03*
X1111613Y1082677D03*
Y1086417D03*
Y1090157D03*
X1122834Y1093897D03*
X1115354D03*
X1122834Y1097637D03*
X1115354D03*
X1119094Y1101377D03*
X1111613D03*
X1119094Y1105117D03*
X1111613D03*
X1117224Y1121948D03*
Y1118208D03*
X1120964D03*
X1109743Y1121948D03*
X1113484D03*
X1109743Y1118208D03*
X1113484D03*
X1124704Y1121948D03*
Y1118208D03*
X1120964Y1121948D03*
X1122834Y1108858D03*
X1119094D03*
X1115354D03*
X1111613D03*
X1117224Y1114468D03*
X1113484D03*
X1120964D03*
X1124704D03*
X1109743D03*
Y1136909D03*
X1124704Y1125688D03*
Y1140649D03*
Y1133169D03*
X1113484D03*
X1117224D03*
X1120964D03*
X1109743Y1125688D03*
X1120964D03*
X1117224D03*
X1113484D03*
X1120964Y1140649D03*
X1117224D03*
X1113484D03*
X1109743Y1129429D03*
Y1133169D03*
X1120964Y1129429D03*
X1113484D03*
X1117224D03*
X1124704D03*
Y1136909D03*
X1113484D03*
X1117224D03*
X1120964D03*
X1109743Y1140649D03*
X1113484Y1155610D03*
X1109743Y1144389D03*
X1120964Y1155610D03*
X1109743Y1151869D03*
X1120964Y1148129D03*
X1113484D03*
X1117224D03*
X1124704D03*
Y1144389D03*
X1113484D03*
X1117224D03*
X1120964D03*
X1113484Y1151870D03*
X1117224D03*
X1120964D03*
X1124704D03*
Y1155610D03*
X1109743D03*
Y1148129D03*
X1117224Y1155610D03*
Y1170570D03*
X1109743D03*
X1113484Y1166830D03*
X1117224Y1159350D03*
X1120964Y1166830D03*
X1109743Y1159350D03*
X1124704Y1170570D03*
Y1159350D03*
X1113484D03*
X1120964D03*
X1109743Y1166830D03*
X1113484Y1170570D03*
X1117224Y1166830D03*
X1120964Y1170570D03*
X1124704Y1166830D03*
X1109743Y1189271D03*
X1113484D03*
X1117224D03*
X1120964D03*
X1113484Y1181791D03*
X1117224D03*
X1120964D03*
X1124704Y1189271D03*
Y1181791D03*
X1109743Y1178051D03*
X1120964Y1174310D03*
X1109743Y1185531D03*
X1113484Y1174310D03*
Y1178051D03*
X1117224D03*
X1120964D03*
X1124704D03*
X1120964Y1185531D03*
X1113484D03*
X1117224D03*
X1124704D03*
X1109743Y1174310D03*
Y1181791D03*
X1117224Y1174310D03*
X1124704D03*
Y1204232D03*
Y1196751D03*
X1120964Y1204232D03*
X1117224D03*
X1113484D03*
X1109743D03*
Y1193011D03*
Y1196751D03*
Y1200491D03*
X1113484Y1196751D03*
X1117224D03*
X1120964D03*
X1117224Y1200491D03*
X1120964D03*
X1113484D03*
X1124704D03*
X1120964Y1193011D03*
X1117224D03*
X1113484D03*
X1124704D03*
X1113484Y1207972D03*
X1117224D03*
X1120964D03*
X1109743Y1211712D03*
Y1207972D03*
X1124704Y1211712D03*
Y1207972D03*
X1122834Y1221062D03*
X1119094D03*
X1115354D03*
X1111613D03*
X1124704Y1215452D03*
X1120964D03*
Y1211712D03*
X1117224Y1215452D03*
X1109743D03*
X1113484Y1211712D03*
X1111613Y1217322D03*
X1115354D03*
X1117224Y1211712D03*
X1122834Y1232283D03*
Y1236023D03*
X1119094Y1224803D03*
Y1228543D03*
X1115354Y1232283D03*
Y1236023D03*
X1111613Y1228543D03*
Y1224803D03*
X1115354Y1250984D03*
Y1254724D03*
X1119094Y1247243D03*
Y1243503D03*
X1122834Y1254724D03*
Y1250984D03*
Y1239763D03*
X1115354D03*
X1119094D03*
X1111613Y1247243D03*
Y1243503D03*
Y1239763D03*
X1119094Y1258465D03*
X1111614D03*
X1113673Y1348187D03*
X1121553D03*
X1109313D03*
X1113673Y1360099D03*
X1121553D03*
X1109313D03*
X1113673Y1372385D03*
Y1384297D03*
X1121553Y1372385D03*
Y1384297D03*
X1109313D03*
Y1372385D03*
X1113673Y1396583D03*
X1121553D03*
X1109313D03*
X1113673Y1408495D03*
X1121553D03*
X1109313D03*
X1130314Y1075196D03*
X1137795D03*
X1134053Y1071455D03*
X1126573D03*
X1126574Y1090157D03*
Y1086417D03*
Y1082677D03*
X1130314Y1090157D03*
Y1078936D03*
X1134054Y1082677D03*
Y1086417D03*
Y1090157D03*
X1137795D03*
Y1078936D03*
X1126574Y1101377D03*
X1130314Y1097637D03*
Y1093897D03*
X1137795D03*
Y1097637D03*
X1134054Y1101377D03*
X1126574Y1105117D03*
X1134054D03*
X1139665Y1121948D03*
X1128444Y1114468D03*
X1130314Y1112598D03*
X1128444Y1118208D03*
X1132184D03*
X1135924D03*
X1132184Y1121948D03*
X1135924D03*
X1128444D03*
X1139665Y1118208D03*
X1137795Y1108858D03*
X1134054D03*
X1130314D03*
X1126574D03*
X1139665Y1114468D03*
X1135925D03*
X1132184D03*
X1139665Y1125688D03*
X1128444Y1140649D03*
X1132184D03*
X1135924D03*
X1132184Y1125688D03*
X1128444D03*
X1135924D03*
Y1133169D03*
X1132184D03*
X1128444D03*
X1139665D03*
Y1140649D03*
X1132184Y1129429D03*
X1128444D03*
X1135924D03*
X1139665D03*
Y1136909D03*
X1135924D03*
X1132184D03*
X1128444D03*
X1135924Y1148129D03*
X1132184D03*
X1128444D03*
X1139665D03*
X1128444Y1155610D03*
X1135924D03*
X1128444Y1144389D03*
X1135924D03*
X1132184D03*
X1139665D03*
X1135925Y1151870D03*
X1132184D03*
X1128444D03*
X1139665D03*
Y1155610D03*
X1132184D03*
X1139665Y1170570D03*
Y1159350D03*
X1132184Y1170570D03*
X1135925Y1166830D03*
X1128444D03*
X1132184Y1159350D03*
X1139665Y1166830D03*
X1135924Y1170570D03*
X1128444D03*
X1132184Y1166830D03*
X1128444Y1159350D03*
X1135924D03*
Y1181791D03*
X1132184D03*
X1128444D03*
X1135924Y1189271D03*
X1132184D03*
X1128444D03*
Y1174310D03*
X1135924D03*
X1139665Y1181791D03*
Y1189271D03*
Y1178051D03*
X1135924D03*
X1132184D03*
X1128444D03*
X1139665Y1185531D03*
X1132184D03*
X1128444D03*
X1135924D03*
X1139665Y1174310D03*
X1132184D03*
X1139665Y1196751D03*
Y1204232D03*
X1135924D03*
Y1196751D03*
X1132184D03*
X1128444D03*
Y1204232D03*
X1132184D03*
Y1200491D03*
X1128444D03*
X1135924D03*
X1139665D03*
X1128444Y1193011D03*
X1132184D03*
X1135924D03*
X1139665D03*
Y1207972D03*
X1132184Y1211712D03*
X1134054Y1217322D03*
X1135924Y1207972D03*
X1132184D03*
X1128444D03*
X1137795Y1221062D03*
X1134054D03*
X1130314D03*
X1126574D03*
X1139665Y1211712D03*
X1135925D03*
Y1215452D03*
X1128444D03*
X1132184D03*
X1128444Y1211712D03*
X1126574Y1224803D03*
Y1228543D03*
X1137795Y1232283D03*
Y1236023D03*
X1134054Y1228543D03*
Y1224803D03*
X1130314Y1232283D03*
Y1236023D03*
X1126574Y1243503D03*
Y1247243D03*
Y1239763D03*
X1130314Y1250984D03*
Y1254724D03*
X1134054Y1247243D03*
Y1243503D03*
X1137795Y1250984D03*
Y1254724D03*
Y1239763D03*
X1134054D03*
X1130314D03*
X1134055Y1258465D03*
X1126574D03*
X1138153Y1348187D03*
X1133793D03*
X1125913D03*
X1138153Y1360099D03*
X1133793D03*
X1125913D03*
X1138153Y1384297D03*
Y1372385D03*
X1133793Y1384297D03*
Y1372385D03*
X1125913Y1384297D03*
Y1372385D03*
X1138153Y1396583D03*
X1133793D03*
X1125913D03*
X1138153Y1408495D03*
X1133793D03*
X1125913D03*
X1152755Y1075196D03*
X1145275D03*
X1156494Y1071455D03*
X1149014Y1071454D03*
X1141534Y1071455D03*
X1141535Y1082677D03*
Y1086417D03*
Y1090157D03*
X1149015Y1082677D03*
Y1086417D03*
X1152755Y1090157D03*
X1156495D03*
Y1086417D03*
X1149015Y1090157D03*
X1152755Y1078936D03*
X1156495Y1082677D03*
X1145275Y1090157D03*
Y1078936D03*
X1141535Y1101377D03*
X1149015D03*
X1152755Y1093897D03*
Y1097637D03*
X1156495Y1101377D03*
X1145275Y1093897D03*
Y1097637D03*
X1141535Y1105117D03*
X1149015D03*
X1156495D03*
X1150885Y1121948D03*
X1143405D03*
Y1118208D03*
Y1114468D03*
X1154625Y1121948D03*
X1156495Y1108858D03*
X1152755D03*
X1149015D03*
X1145275D03*
X1141535D03*
X1154625Y1118208D03*
X1150885D03*
X1154625Y1114468D03*
X1150885D03*
X1154625Y1125688D03*
X1150885Y1133464D03*
X1154625Y1133169D03*
X1143503Y1132677D03*
X1143405Y1140649D03*
Y1125688D03*
X1150885Y1140649D03*
X1154625D03*
X1150885Y1125688D03*
X1154625Y1129429D03*
X1150885D03*
X1143405D03*
Y1136909D03*
X1154625D03*
X1150885D03*
X1143405Y1148129D03*
X1150885D03*
X1154625D03*
X1143405Y1155610D03*
X1154625D03*
X1143405Y1144389D03*
X1150885Y1151869D03*
X1154625D03*
Y1144389D03*
X1150885D03*
X1143405Y1151870D03*
X1150885Y1155610D03*
X1154625Y1166830D03*
X1150885Y1170570D03*
X1143405Y1166830D03*
X1150885Y1159350D03*
X1143405Y1170570D03*
X1154625Y1159350D03*
X1143405D03*
X1150885Y1166830D03*
X1154625Y1170570D03*
X1143405Y1181791D03*
X1154625D03*
X1150885D03*
Y1189271D03*
X1154625D03*
X1143405D03*
Y1174310D03*
X1154625D03*
X1143405Y1178051D03*
Y1185531D03*
X1154625D03*
X1150885D03*
X1154625Y1178051D03*
X1150885D03*
Y1174310D03*
Y1196751D03*
X1154625Y1204232D03*
X1150885D03*
X1154625Y1196751D03*
X1143405D03*
Y1204232D03*
Y1200491D03*
X1154625D03*
X1150885D03*
Y1193011D03*
X1154625D03*
X1143405D03*
X1150885Y1207972D03*
X1154625D03*
Y1211712D03*
X1143405Y1207972D03*
X1149015Y1221062D03*
X1156495D03*
X1152755D03*
X1145275D03*
X1141535D03*
X1143405Y1211712D03*
Y1215452D03*
X1150885Y1211712D03*
Y1215452D03*
X1154625D03*
X1156495Y1217322D03*
X1152755D03*
X1141535Y1228543D03*
Y1224803D03*
X1152755Y1232283D03*
Y1236023D03*
X1156495Y1228543D03*
Y1224803D03*
X1149015Y1228543D03*
Y1224803D03*
X1145275Y1232283D03*
Y1236023D03*
X1141535Y1239763D03*
Y1243503D03*
Y1247243D03*
X1152755Y1254724D03*
Y1250984D03*
X1149015Y1247243D03*
Y1243503D03*
Y1239763D03*
X1152755D03*
X1156495D03*
Y1243503D03*
Y1247243D03*
X1145275Y1239763D03*
Y1250984D03*
Y1254724D03*
X1156495Y1258465D03*
X1149015D03*
X1141536D03*
X1150393Y1348187D03*
X1146033D03*
X1150393Y1360099D03*
X1146033D03*
X1150393Y1384297D03*
Y1372385D03*
X1146033D03*
Y1384297D03*
X1150393Y1396583D03*
X1146033D03*
X1150393Y1408495D03*
X1146033D03*
X1167716Y1075196D03*
X1160235D03*
X1171455Y1071455D03*
X1163975D03*
X1167716Y1078936D03*
X1163976Y1082677D03*
Y1086417D03*
Y1090157D03*
X1171456Y1082677D03*
Y1086417D03*
Y1090157D03*
X1167716D03*
X1160235Y1078936D03*
Y1090157D03*
X1163976Y1101377D03*
X1171456D03*
X1167716Y1097637D03*
Y1093897D03*
X1160235D03*
Y1097637D03*
X1163976Y1105117D03*
X1171456D03*
X1169586Y1121948D03*
X1165846D03*
X1162106D03*
X1158365D03*
X1173326D03*
X1171456Y1108858D03*
X1167716D03*
X1163976D03*
X1160235D03*
X1162106Y1114468D03*
X1169586D03*
X1162106Y1118208D03*
X1173326Y1114468D03*
X1158365Y1118208D03*
X1173326D03*
X1165846Y1114468D03*
X1158365D03*
X1169586Y1118208D03*
X1165846D03*
X1162106Y1133169D03*
X1165846D03*
X1169586D03*
X1158365Y1140649D03*
X1162106D03*
X1165846D03*
X1169586D03*
X1158365Y1125688D03*
X1162106D03*
X1165846D03*
X1169586D03*
X1173326Y1133169D03*
Y1125688D03*
Y1140649D03*
X1158365Y1133169D03*
X1169586Y1129429D03*
X1165846D03*
X1162106D03*
X1158365D03*
X1173326D03*
Y1136909D03*
X1169586D03*
X1165846D03*
X1158365D03*
X1162106D03*
X1173326Y1148129D03*
X1158365D03*
X1162106D03*
X1165846D03*
X1169586D03*
X1162106Y1155610D03*
X1169586D03*
X1173326Y1151869D03*
X1158365D03*
X1162106D03*
X1169586D03*
X1165846D03*
X1173326Y1144389D03*
X1165846D03*
X1158365D03*
X1162106D03*
X1169586D03*
X1173326Y1155610D03*
X1165846D03*
X1158365D03*
Y1170570D03*
X1165846D03*
X1169586Y1166830D03*
X1158365Y1159350D03*
X1162106Y1166830D03*
X1165846Y1159350D03*
X1173326D03*
Y1170570D03*
Y1166830D03*
X1165846D03*
X1169586Y1170570D03*
X1158365Y1166830D03*
X1162106Y1170570D03*
X1169586Y1159350D03*
X1162106D03*
X1173326Y1189271D03*
X1158365Y1181791D03*
X1162106D03*
X1165846D03*
X1169586D03*
X1158365Y1189271D03*
X1162106D03*
X1165846D03*
X1169586D03*
X1173326Y1181791D03*
X1169586Y1174310D03*
X1162106D03*
X1158365Y1185531D03*
X1162106D03*
X1169586D03*
X1165846D03*
X1173326D03*
X1165846Y1178051D03*
X1158365D03*
X1162106D03*
X1169586D03*
X1173326D03*
X1165846Y1174310D03*
X1158365D03*
X1173326D03*
X1162106Y1204232D03*
X1158365D03*
X1169586D03*
X1165846D03*
X1158365Y1196751D03*
X1162106D03*
X1165846D03*
X1169586D03*
X1173326Y1204232D03*
Y1196751D03*
Y1200491D03*
X1165846D03*
X1162106D03*
X1158365D03*
X1169586D03*
X1165846Y1193011D03*
X1169586D03*
X1158365D03*
X1162106D03*
X1173326D03*
X1158365Y1211712D03*
Y1207972D03*
X1173326D03*
Y1211712D03*
X1162106Y1207972D03*
X1165846D03*
X1169586Y1211712D03*
Y1207972D03*
X1171456Y1221062D03*
X1167716D03*
X1163976D03*
X1160235D03*
X1173326Y1215452D03*
X1165846D03*
X1169586D03*
X1162105Y1215451D03*
X1158365Y1215452D03*
X1162105Y1211711D03*
X1165846D03*
X1163976Y1228543D03*
Y1224803D03*
X1171456Y1228543D03*
Y1224803D03*
X1167716Y1232283D03*
Y1236023D03*
X1160235Y1232283D03*
Y1236023D03*
X1163976Y1239763D03*
Y1243503D03*
Y1247243D03*
X1167716Y1239763D03*
Y1250984D03*
Y1254724D03*
X1171456Y1247243D03*
Y1243503D03*
Y1239763D03*
X1160235D03*
Y1250984D03*
Y1254724D03*
X1171456Y1258465D03*
X1163976D03*
X1162633Y1348187D03*
X1170513D03*
X1158273D03*
X1162633Y1360099D03*
X1170513D03*
X1158273D03*
X1162633Y1372385D03*
Y1384297D03*
X1170513Y1372385D03*
Y1384297D03*
X1158273D03*
Y1372385D03*
X1162633Y1396583D03*
X1170513D03*
X1158273D03*
X1162633Y1408495D03*
X1170513D03*
X1158273D03*
X1175196Y1075196D03*
X1182676D03*
X1186416Y1071455D03*
X1178935D03*
X1175196Y1078936D03*
Y1090157D03*
X1178936D03*
X1182676Y1078936D03*
X1178936Y1082677D03*
Y1086417D03*
X1182676Y1090157D03*
X1186417D03*
Y1086417D03*
Y1082677D03*
X1175196Y1097637D03*
Y1093897D03*
X1178936Y1101377D03*
X1186417D03*
X1182676Y1097637D03*
Y1093897D03*
X1178936Y1105117D03*
X1186417D03*
X1188287Y1118208D03*
Y1121948D03*
X1184546Y1118208D03*
X1180806Y1121948D03*
X1177066D03*
X1184546D03*
X1186417Y1108858D03*
X1182676D03*
X1178936D03*
X1175196D03*
X1188287Y1114468D03*
X1177066D03*
Y1118208D03*
X1184546Y1114468D03*
X1188287Y1125688D03*
X1184546Y1136909D03*
X1177066Y1133169D03*
X1180806D03*
X1184546D03*
X1177066Y1140649D03*
X1180806D03*
X1184546Y1125688D03*
Y1129429D03*
X1177066Y1125688D03*
X1180806D03*
X1184546Y1140649D03*
X1180806Y1129429D03*
X1177066D03*
X1188287D03*
X1180806Y1136909D03*
X1177066D03*
X1188287D03*
Y1140649D03*
Y1155610D03*
Y1151869D03*
Y1148129D03*
X1177066D03*
X1180806D03*
X1184546Y1144389D03*
Y1148129D03*
Y1151869D03*
X1177066Y1155610D03*
X1184546D03*
X1180806Y1151869D03*
X1177066D03*
Y1144389D03*
X1180806D03*
Y1155610D03*
X1188287Y1144389D03*
X1177066Y1166830D03*
X1188287D03*
Y1159350D03*
Y1170570D03*
X1180806D03*
X1184546D03*
X1177066D03*
X1184546Y1166830D03*
X1180806D03*
X1177066Y1159350D03*
X1180806D03*
X1184546D03*
X1188287Y1181791D03*
Y1174310D03*
X1177066Y1189271D03*
X1180806D03*
X1184546Y1178051D03*
X1177066Y1174310D03*
X1184546Y1185531D03*
X1177066Y1181791D03*
X1180806D03*
X1184546Y1189271D03*
Y1174310D03*
X1177066Y1185531D03*
Y1178051D03*
X1180806Y1185531D03*
Y1178051D03*
Y1174310D03*
X1184546Y1181791D03*
X1188287Y1185531D03*
Y1189271D03*
Y1178051D03*
X1184546Y1204232D03*
X1177066D03*
X1180806D03*
X1184546Y1200491D03*
X1177066Y1196751D03*
X1180806D03*
X1184546Y1193011D03*
X1188287Y1204232D03*
Y1196751D03*
X1184566Y1196732D03*
X1180806Y1200491D03*
X1177066D03*
X1188287D03*
X1177066Y1193011D03*
X1180806D03*
X1188287D03*
Y1207972D03*
X1184546Y1211712D03*
X1177066Y1207972D03*
Y1211712D03*
X1180806Y1207972D03*
Y1211712D03*
X1184546Y1207972D03*
X1186417Y1221062D03*
X1182676D03*
X1178936D03*
X1175196D03*
X1188287Y1215452D03*
X1180806D03*
X1177066D03*
X1188287Y1211712D03*
X1175196Y1232283D03*
Y1236023D03*
X1178936Y1228543D03*
Y1224803D03*
X1182676Y1232283D03*
Y1236023D03*
X1186417Y1228543D03*
Y1224803D03*
X1175196Y1254724D03*
Y1239763D03*
Y1250984D03*
X1178936Y1247243D03*
X1182676Y1250984D03*
Y1254724D03*
X1186417Y1247243D03*
X1178936Y1239763D03*
X1186417D03*
X1182676D03*
X1178936Y1243503D03*
X1186417D03*
Y1258465D03*
X1178936D03*
X1182753Y1348187D03*
X1174873D03*
X1182753Y1360099D03*
X1174873D03*
X1182753Y1384297D03*
Y1372385D03*
X1174873Y1384297D03*
Y1372385D03*
X1182753Y1396583D03*
X1174873D03*
X1182753Y1408495D03*
X1174873D03*
X1190157Y1075196D03*
X1197637D03*
X1205117D03*
X1201376Y1071455D03*
X1193896D03*
X1190157Y1078936D03*
Y1090157D03*
X1197637Y1078936D03*
Y1090157D03*
X1201377D03*
Y1086417D03*
Y1082677D03*
X1205117Y1078936D03*
X1205116Y1090157D03*
X1193897Y1082677D03*
Y1086417D03*
Y1090157D03*
X1190157Y1093897D03*
Y1097637D03*
X1197637D03*
X1201377Y1101377D03*
X1197637Y1093897D03*
X1205117D03*
Y1097637D03*
X1193897Y1101377D03*
X1201377Y1105117D03*
X1193897D03*
X1192027Y1118208D03*
Y1121948D03*
X1205117Y1123818D03*
Y1120078D03*
Y1116338D03*
Y1108858D03*
X1201377D03*
X1197637D03*
X1193897D03*
X1190157D03*
X1199507Y1118208D03*
X1195767D03*
Y1114468D03*
X1192027D03*
X1199507D03*
X1192027Y1136909D03*
X1195767Y1140649D03*
X1192027Y1133169D03*
Y1140649D03*
X1195767Y1136909D03*
X1192027Y1125688D03*
Y1129429D03*
X1205117Y1135039D03*
Y1131299D03*
Y1127558D03*
X1199507Y1140649D03*
Y1136909D03*
X1203247Y1140649D03*
X1195767Y1148129D03*
X1192027Y1144389D03*
X1195767Y1155610D03*
X1192027Y1148129D03*
X1195767Y1151869D03*
X1199507D03*
X1203247D03*
Y1155610D03*
Y1144389D03*
X1192027Y1151870D03*
X1199507Y1155610D03*
X1192027D03*
X1203247Y1148129D03*
X1195767Y1144389D03*
X1199507Y1148129D03*
Y1144389D03*
X1195767Y1170570D03*
Y1159350D03*
X1203247Y1166830D03*
Y1170570D03*
Y1159350D03*
X1195767Y1166830D03*
X1199507Y1170570D03*
Y1166830D03*
Y1159350D03*
X1192027Y1166830D03*
Y1170570D03*
Y1159350D03*
Y1181791D03*
X1199507Y1185531D03*
X1203247Y1174310D03*
Y1178051D03*
Y1185531D03*
X1192027Y1178051D03*
Y1189271D03*
X1195767D03*
X1192027Y1185531D03*
X1195767D03*
X1199507Y1181791D03*
X1195767Y1178051D03*
Y1174310D03*
X1203247Y1189271D03*
X1199507D03*
Y1174310D03*
X1195767Y1181791D03*
X1192027Y1174310D03*
X1199507Y1178051D03*
X1203247Y1181791D03*
X1195767Y1204232D03*
X1199507Y1193011D03*
X1203247D03*
X1195767Y1196751D03*
Y1193011D03*
X1192027D03*
X1205117Y1198621D03*
Y1202362D03*
X1199507Y1196751D03*
Y1204232D03*
X1195767Y1200491D03*
X1192027Y1196751D03*
Y1200491D03*
Y1204232D03*
X1199507Y1200491D03*
X1192027Y1211712D03*
X1205117Y1206102D03*
Y1209842D03*
Y1213582D03*
Y1217322D03*
Y1221062D03*
X1201377D03*
X1197637D03*
X1193897D03*
X1190157D03*
X1192027Y1215452D03*
X1199507Y1211712D03*
Y1215452D03*
Y1207972D03*
X1195767Y1215452D03*
X1192027Y1207972D03*
X1195767D03*
Y1211712D03*
X1190157Y1232283D03*
Y1236023D03*
X1197637Y1232283D03*
X1201377Y1228543D03*
X1197637Y1236023D03*
X1201377Y1224803D03*
X1205117Y1232283D03*
Y1236023D03*
X1193897Y1228543D03*
Y1224803D03*
X1190157Y1254724D03*
Y1250984D03*
Y1239763D03*
X1197637Y1250984D03*
Y1254724D03*
X1201377Y1247243D03*
X1205117Y1250984D03*
Y1254724D03*
X1197637Y1239763D03*
X1201377D03*
Y1243503D03*
X1205117Y1239763D03*
X1193897Y1247243D03*
Y1239763D03*
Y1243503D03*
X1201377Y1258465D03*
X1193897D03*
X1212598Y1075196D03*
X1220079D03*
X1216338Y1071455D03*
X1208857D03*
X1220079Y1078936D03*
X1212599D03*
X1216337Y1082677D03*
X1216338Y1086417D03*
X1212597Y1090157D03*
X1216337D03*
X1220077D03*
X1208857Y1082677D03*
X1208858Y1086417D03*
X1208857Y1090157D03*
X1212598Y1093897D03*
X1220078D03*
X1212598Y1097637D03*
X1220078D03*
X1216338Y1101377D03*
X1208857D03*
X1216338Y1105117D03*
X1208858D03*
X1212598Y1108858D03*
X1216338D03*
Y1116338D03*
X1212598Y1120078D03*
X1216338Y1123818D03*
X1208857Y1112598D03*
Y1120078D03*
X1220077Y1108857D03*
X1220078Y1116338D03*
Y1123818D03*
X1208858Y1108858D03*
X1221948Y1140649D03*
X1218208D03*
X1214468D03*
X1206987Y1136909D03*
X1212598Y1127558D03*
X1216338Y1131299D03*
X1208858Y1127558D03*
X1220078Y1131299D03*
X1212598Y1135039D03*
X1208858D03*
X1206988Y1140649D03*
X1221948Y1155610D03*
X1210728Y1151869D03*
X1206987D03*
X1218208Y1155610D03*
Y1148129D03*
X1214468Y1155610D03*
Y1151869D03*
Y1148129D03*
Y1144389D03*
X1206987D03*
X1210728D03*
X1221948Y1148129D03*
X1218208Y1144389D03*
Y1151869D03*
X1206988Y1155610D03*
Y1148129D03*
X1210728Y1155610D03*
X1221948Y1151869D03*
Y1144389D03*
X1206987Y1159350D03*
X1210728D03*
X1214468D03*
X1210728Y1166830D03*
X1206987D03*
X1218208Y1170570D03*
X1214468D03*
Y1166830D03*
X1221948Y1170570D03*
Y1159350D03*
X1218208Y1166830D03*
Y1159350D03*
X1221948Y1166830D03*
X1210728Y1170570D03*
X1206988D03*
X1210728Y1181791D03*
X1206987D03*
X1210728Y1189271D03*
X1218208Y1185531D03*
Y1178051D03*
X1214468Y1189271D03*
X1221948Y1178051D03*
Y1185531D03*
X1206987Y1174310D03*
Y1189271D03*
X1214468Y1185531D03*
Y1181791D03*
Y1178051D03*
Y1174310D03*
X1210728D03*
X1218208Y1189271D03*
Y1174310D03*
X1221948Y1181791D03*
Y1174310D03*
X1218208Y1181791D03*
X1221948Y1189271D03*
X1208858Y1194881D03*
X1212598D03*
X1218208Y1193011D03*
X1214468D03*
X1221948D03*
X1212598Y1202362D03*
X1220078Y1198621D03*
X1216338D03*
X1208858Y1202362D03*
X1220078Y1206102D03*
X1216338D03*
X1220078Y1221062D03*
X1216338D03*
X1212598D03*
Y1217322D03*
X1216338Y1213582D03*
X1220078D03*
X1212598Y1209842D03*
X1208858Y1221062D03*
Y1217322D03*
Y1209842D03*
X1216338Y1224803D03*
Y1228543D03*
X1212598Y1232283D03*
Y1236023D03*
X1220078Y1232283D03*
Y1236023D03*
X1208858Y1224803D03*
Y1228543D03*
X1212598Y1250984D03*
Y1254724D03*
X1216338Y1247243D03*
Y1243503D03*
X1220078Y1250984D03*
Y1254724D03*
X1212598Y1239763D03*
X1216338D03*
X1220078D03*
X1208858Y1247243D03*
Y1243503D03*
Y1239763D03*
X1216338Y1258465D03*
X1208858D03*
X1227559Y1075196D03*
X1235039D03*
X1231298Y1071455D03*
X1223818D03*
X1223817Y1082677D03*
X1223818Y1086417D03*
X1223817Y1090157D03*
X1235039Y1078936D03*
X1227559D03*
X1231298Y1082677D03*
X1235039Y1086417D03*
X1231299D03*
X1227557Y1090157D03*
X1231298D03*
X1223818Y1101377D03*
X1227558Y1093897D03*
Y1097637D03*
X1231298Y1101377D03*
X1235039Y1093897D03*
Y1097637D03*
X1223818Y1105117D03*
X1231299D03*
X1235039D03*
X1223817Y1108858D03*
X1223818Y1116338D03*
Y1112598D03*
Y1123818D03*
Y1120078D03*
X1227558Y1108858D03*
X1231298D03*
X1227558Y1116338D03*
X1231298D03*
X1235039Y1112598D03*
X1227558Y1123818D03*
X1231298D03*
X1235039Y1120078D03*
X1236909Y1140649D03*
X1233169D03*
X1229428Y1136909D03*
X1233169D03*
X1223818Y1127558D03*
Y1131299D03*
X1235039Y1127558D03*
X1231298Y1131299D03*
X1227557D03*
X1223818Y1135039D03*
X1235039D03*
X1236909Y1136909D03*
X1225688Y1140649D03*
X1229428D03*
X1236909Y1148129D03*
Y1155610D03*
X1233169Y1144389D03*
X1225688D03*
Y1151869D03*
X1229428Y1144389D03*
X1233169Y1155610D03*
X1229428Y1151869D03*
X1233169D03*
Y1148129D03*
X1236909Y1151870D03*
X1225688Y1148129D03*
X1229428D03*
X1225688Y1155610D03*
X1236909Y1144389D03*
X1229428Y1155610D03*
X1236909Y1170570D03*
Y1166830D03*
X1225688D03*
X1229428Y1159350D03*
X1233169D03*
X1225688D03*
X1229428Y1166830D03*
X1233169Y1170570D03*
Y1166830D03*
X1229428Y1170570D03*
X1225688D03*
X1236909Y1159350D03*
Y1178051D03*
Y1185531D03*
X1229428Y1181791D03*
Y1189271D03*
X1233169D03*
Y1185531D03*
Y1181791D03*
Y1178051D03*
X1229428Y1174310D03*
X1233169D03*
X1225688D03*
Y1181791D03*
Y1189271D03*
X1236909Y1181791D03*
X1225688Y1185531D03*
X1236909Y1189271D03*
X1229428Y1178051D03*
Y1185531D03*
X1236909Y1174310D03*
X1225688Y1178051D03*
X1233169Y1193011D03*
X1223818Y1194881D03*
X1229428Y1196751D03*
X1233169D03*
X1236909Y1193011D03*
X1223818Y1202362D03*
Y1198621D03*
X1235039Y1202362D03*
X1231298Y1198621D03*
X1227558D03*
X1225688Y1193011D03*
X1229428D03*
X1223818Y1206102D03*
Y1221062D03*
Y1217322D03*
Y1213582D03*
Y1209842D03*
X1231298Y1206102D03*
X1227558D03*
X1235039Y1217322D03*
X1231298Y1221062D03*
X1227558D03*
X1235039Y1209842D03*
X1231298Y1213582D03*
X1227558D03*
X1223818Y1224803D03*
Y1228543D03*
X1235039Y1224803D03*
X1231298D03*
Y1228543D03*
X1227558Y1236023D03*
Y1232283D03*
X1235039D03*
Y1236023D03*
X1225688Y1222932D03*
X1223818Y1247243D03*
Y1243503D03*
Y1239763D03*
X1227558Y1250984D03*
Y1254724D03*
X1235039Y1250984D03*
X1231298Y1247243D03*
Y1243503D03*
X1235039D03*
X1227558Y1239763D03*
X1231298D03*
X1235039Y1254724D03*
X1231298Y1258465D03*
X1223818D03*
X1235966Y1348187D03*
X1228086D03*
X1235966Y1360099D03*
X1228086D03*
X1235966Y1372385D03*
Y1384297D03*
X1228086Y1372385D03*
Y1384297D03*
X1238779Y1086417D03*
Y1078936D03*
X1242520Y1090158D03*
Y1082677D03*
X1238779Y1093897D03*
Y1097637D03*
Y1105117D03*
X1242520Y1101378D03*
X1238779Y1112598D03*
Y1120078D03*
X1242520Y1123819D03*
Y1116339D03*
Y1108859D03*
X1243149Y1136909D03*
X1240649Y1140649D03*
X1238779Y1127558D03*
Y1135039D03*
X1242520Y1131300D03*
X1240649Y1136909D03*
Y1148129D03*
Y1155610D03*
Y1151870D03*
Y1144389D03*
Y1166830D03*
Y1170570D03*
Y1159350D03*
Y1178051D03*
Y1185531D03*
Y1174310D03*
Y1181791D03*
Y1189271D03*
X1240589Y1193011D03*
X1238779Y1202362D03*
X1242520Y1198621D03*
X1238779Y1217322D03*
Y1209842D03*
X1242520Y1221062D03*
Y1213582D03*
Y1206102D03*
X1238779Y1224803D03*
Y1232283D03*
Y1236023D03*
X1242520Y1228543D03*
X1238779Y1250984D03*
Y1243503D03*
X1242520Y1247243D03*
Y1239762D03*
X1252566Y1348187D03*
X1240326D03*
X1248206D03*
X1252566Y1360099D03*
X1240326D03*
X1248206D03*
X1252566Y1372385D03*
Y1384297D03*
X1240326D03*
Y1372385D03*
X1248206D03*
Y1384297D03*
X1252566Y1396583D03*
X1240326D03*
X1248206D03*
X1252566Y1408495D03*
X1240326D03*
X1248206D03*
X1264806Y1348187D03*
X1260446D03*
X1264806Y1360099D03*
X1260446D03*
X1264806Y1372385D03*
Y1384297D03*
X1260446Y1372385D03*
Y1384297D03*
X1264806Y1396583D03*
X1260446D03*
X1264806Y1408495D03*
X1260446D03*
X1284926Y1348187D03*
X1277046D03*
X1272686D03*
X1284926Y1360099D03*
X1277046D03*
X1272686D03*
X1284926Y1372385D03*
Y1384297D03*
X1277046Y1372385D03*
Y1384297D03*
X1272686D03*
Y1372385D03*
X1284926Y1396583D03*
X1277046D03*
X1272686D03*
X1284926Y1408495D03*
X1277046D03*
X1272686D03*
X1301526Y1348187D03*
X1289286D03*
X1297166D03*
X1301526Y1360099D03*
X1289286D03*
X1297166D03*
X1301526Y1372385D03*
Y1384297D03*
X1289286D03*
Y1372385D03*
X1297166Y1384297D03*
Y1372385D03*
X1301526Y1396583D03*
X1289286D03*
X1297166D03*
X1301526Y1408495D03*
X1289286D03*
X1297166D03*
X1313766Y1348187D03*
X1309406D03*
X1313766Y1360099D03*
X1309406D03*
X1313766Y1372385D03*
Y1384297D03*
X1309406Y1372385D03*
Y1384297D03*
X1313766Y1396583D03*
X1309406D03*
X1313766Y1408495D03*
X1309406D03*
X1333886Y1348187D03*
X1326006D03*
X1321646D03*
X1333886Y1360099D03*
X1326006D03*
X1321646D03*
X1333886Y1372385D03*
Y1384297D03*
X1326006Y1372385D03*
Y1384297D03*
X1321646D03*
Y1372385D03*
X1333886Y1396583D03*
X1326006D03*
X1321646D03*
X1333886Y1408495D03*
X1326006D03*
X1321646D03*
X1339196Y441086D03*
Y433999D03*
Y437543D03*
X1336396Y441086D03*
Y433999D03*
Y437543D03*
X1339196Y444629D03*
X1336396D03*
X1350486Y1348187D03*
X1338246D03*
X1346126D03*
X1350486Y1360099D03*
X1338246D03*
X1346126D03*
X1350486Y1372385D03*
Y1384297D03*
X1338246D03*
Y1372385D03*
X1346126Y1384297D03*
Y1372385D03*
X1350486Y1396583D03*
X1338246D03*
X1346126D03*
X1350486Y1408495D03*
X1338246D03*
X1346126D03*
X1358366Y1348187D03*
Y1360099D03*
Y1372385D03*
Y1384297D03*
Y1396583D03*
Y1408495D03*
X1415924Y620661D03*
Y617861D03*
X1423010Y620661D03*
X1419467Y617861D03*
X1423010D03*
X1426554Y620661D03*
Y617861D03*
X1419467Y620661D03*
X1459130Y1348187D03*
Y1360099D03*
Y1384297D03*
Y1372385D03*
X1479250Y1348187D03*
X1471370D03*
X1467010D03*
X1479250Y1360099D03*
X1471370D03*
X1467010D03*
X1479250Y1384297D03*
Y1372385D03*
X1471370D03*
Y1384297D03*
X1467010D03*
Y1372385D03*
X1479250Y1396583D03*
X1471370D03*
X1479250Y1408495D03*
X1471370D03*
X1495850Y1348187D03*
X1483610D03*
X1491490D03*
X1495850Y1360099D03*
X1483610D03*
X1491490D03*
X1483610Y1384297D03*
Y1372385D03*
X1491490Y1384297D03*
Y1372385D03*
X1495850Y1384297D03*
Y1372385D03*
Y1396583D03*
X1483610D03*
X1491490D03*
X1495850Y1408495D03*
X1483610D03*
X1491490D03*
X1514468Y1084547D03*
Y1092027D03*
Y1088287D03*
Y1095767D03*
Y1103247D03*
Y1099507D03*
Y1106988D03*
Y1110728D03*
Y1118208D03*
Y1121948D03*
Y1114468D03*
Y1125688D03*
Y1133169D03*
Y1140649D03*
Y1129429D03*
Y1136909D03*
Y1144389D03*
Y1151870D03*
Y1148129D03*
Y1155610D03*
X1511968Y1170570D03*
X1514468Y1159350D03*
Y1166829D03*
X1514467Y1170570D03*
X1511968Y1178050D03*
X1514468Y1174309D03*
Y1181790D03*
X1514467Y1178051D03*
X1512597Y1198622D03*
Y1191142D03*
Y1221063D03*
Y1213583D03*
Y1206103D03*
Y1228542D03*
X1512596Y1239762D03*
Y1247242D03*
X1508090Y1348187D03*
X1503730D03*
X1508090Y1360099D03*
X1503730D03*
X1508090Y1384297D03*
Y1372385D03*
X1503730D03*
Y1384297D03*
X1508090Y1396583D03*
X1503730D03*
X1508090Y1408495D03*
X1503730D03*
X1525689Y1073326D03*
X1521949D03*
X1529429D03*
X1521948Y1077066D03*
X1525689D03*
X1518208D03*
Y1080806D03*
X1529429Y1080807D03*
X1521949D03*
X1529429Y1084547D03*
X1521949D03*
X1518208D03*
X1529429Y1088287D03*
X1525689D03*
X1521949D03*
X1525689Y1092027D03*
X1518208D03*
X1529429Y1077066D03*
X1525689Y1084547D03*
X1529429Y1092027D03*
X1521949D03*
X1518208Y1088287D03*
X1525689Y1080807D03*
X1521949Y1103247D03*
X1518208D03*
X1529429Y1106988D03*
X1525689D03*
X1521949D03*
X1525689Y1095767D03*
X1518208D03*
X1529429Y1099507D03*
X1521949D03*
X1529429Y1103247D03*
X1518208Y1099507D03*
X1525689D03*
X1529429Y1095767D03*
X1525689Y1103247D03*
X1518208Y1106988D03*
X1521949Y1095767D03*
X1529429Y1110728D03*
X1518208D03*
X1529429Y1114468D03*
X1525689D03*
X1521949D03*
X1529429Y1118208D03*
X1518208D03*
X1529429Y1121948D03*
X1525689D03*
X1521949D03*
Y1110728D03*
X1518208Y1114468D03*
X1525689Y1110728D03*
X1518208Y1121948D03*
X1521949Y1118208D03*
X1525689D03*
X1529429Y1125688D03*
X1518208D03*
X1529429Y1129429D03*
X1525689D03*
X1521949D03*
X1518208Y1133169D03*
X1521949Y1136909D03*
X1529429Y1140649D03*
X1525689D03*
X1521949D03*
X1518208D03*
X1525689Y1125688D03*
X1518208Y1129429D03*
X1521949Y1125688D03*
X1518208Y1136909D03*
X1521949Y1133169D03*
Y1144389D03*
X1518208D03*
X1529429Y1151869D03*
X1525689D03*
X1521949Y1148129D03*
Y1151870D03*
X1518208D03*
X1529429Y1155610D03*
X1525689D03*
X1521949D03*
X1518208Y1148129D03*
Y1155610D03*
X1521949Y1159350D03*
X1518208D03*
X1529429Y1166830D03*
X1525689D03*
X1521948D03*
X1525689Y1170570D03*
X1521948D03*
X1518209Y1166830D03*
X1518207Y1170570D03*
X1521948Y1174310D03*
X1518207D03*
X1521948Y1178051D03*
X1525689Y1174310D03*
X1529429D03*
X1527559Y1179921D03*
X1523819D03*
X1518207Y1181791D03*
X1516338Y1187401D03*
X1520078D03*
X1527559Y1183661D03*
X1523819D03*
X1520078D03*
X1516338D03*
X1527559Y1176180D03*
X1518207Y1178051D03*
X1516338Y1194881D03*
Y1202362D03*
X1527559Y1191141D03*
X1523819D03*
X1527559Y1198621D03*
X1523819D03*
X1520078Y1194881D03*
Y1202362D03*
X1516338Y1209842D03*
Y1217322D03*
X1523819Y1206102D03*
X1527559D03*
Y1213582D03*
X1523819D03*
X1520078Y1209842D03*
Y1217322D03*
X1523819Y1221062D03*
X1527559D03*
X1516338Y1232283D03*
Y1236023D03*
Y1224803D03*
X1527559Y1236023D03*
Y1232283D03*
X1523819Y1228543D03*
Y1224803D03*
X1520078Y1236023D03*
Y1232283D03*
Y1224803D03*
X1516338Y1243503D03*
Y1250984D03*
X1527559D03*
Y1254724D03*
X1523819Y1247243D03*
Y1239763D03*
Y1243503D03*
X1527559Y1239763D03*
X1520078Y1250984D03*
Y1254724D03*
Y1243503D03*
X1523819Y1258465D03*
X1528210Y1348187D03*
X1520330D03*
X1515970D03*
X1528210Y1360099D03*
X1520330D03*
X1515970D03*
X1528210Y1372385D03*
Y1384297D03*
X1520330Y1372385D03*
Y1384297D03*
X1515970D03*
Y1372385D03*
X1528210Y1396583D03*
X1520330D03*
X1515970D03*
X1528210Y1408495D03*
X1520330D03*
X1515970D03*
X1533169Y1073326D03*
X1540649D03*
X1546258Y1071455D03*
X1536909Y1073326D03*
X1540649Y1088287D03*
X1533169Y1077066D03*
X1536909Y1080807D03*
Y1084547D03*
Y1088287D03*
X1533169D03*
Y1092027D03*
X1540649Y1077066D03*
Y1092027D03*
X1546259Y1082677D03*
Y1086417D03*
Y1090157D03*
X1533169Y1080807D03*
Y1084547D03*
X1540649Y1080807D03*
X1536909Y1077066D03*
X1540649Y1084547D03*
X1536909Y1092027D03*
X1544389Y1099507D03*
X1533169Y1095767D03*
X1536909Y1099507D03*
Y1103247D03*
X1540649Y1106988D03*
X1536909D03*
X1533169D03*
X1544389D03*
X1540649Y1095767D03*
Y1099507D03*
X1546259Y1101377D03*
Y1105117D03*
X1536909Y1095767D03*
X1533169Y1099507D03*
X1540649Y1103247D03*
X1533169D03*
X1544389Y1118208D03*
X1540649D03*
Y1121948D03*
X1544389Y1110728D03*
X1540649D03*
X1536909Y1114468D03*
X1533169D03*
X1536909Y1118208D03*
X1533169D03*
Y1121948D03*
X1544389Y1114468D03*
X1536909Y1110728D03*
X1533169D03*
X1540649Y1114468D03*
X1544389Y1140649D03*
X1540649D03*
X1536909D03*
X1533169D03*
Y1125688D03*
X1544389Y1129428D03*
X1540649D03*
X1536909Y1129429D03*
X1533169D03*
X1544389Y1136909D03*
X1533169Y1133169D03*
X1540649Y1136909D03*
X1544389Y1144389D03*
X1540649D03*
X1533169D03*
Y1148129D03*
Y1151870D03*
Y1155610D03*
X1544389Y1148129D03*
Y1155610D03*
Y1151870D03*
X1536909Y1148129D03*
X1540649Y1151870D03*
Y1148129D03*
X1536909Y1144389D03*
Y1155610D03*
X1533169Y1159350D03*
X1536909Y1166830D03*
Y1170570D03*
X1544389Y1159350D03*
Y1166830D03*
Y1170570D03*
X1540649Y1159350D03*
Y1170570D03*
X1536909Y1174310D03*
X1533169D03*
Y1178051D03*
X1544389Y1174310D03*
Y1178051D03*
Y1181791D03*
X1540649D03*
X1538779Y1179921D03*
X1535039Y1176180D03*
X1531299Y1179921D03*
Y1187401D03*
X1546259D03*
X1542519D03*
Y1183661D03*
X1538779D03*
X1535039D03*
X1531299D03*
X1540649Y1174310D03*
Y1178050D03*
X1531299Y1176180D03*
X1535039Y1191141D03*
X1531299D03*
X1535039Y1198621D03*
X1531299D03*
Y1194881D03*
Y1202362D03*
X1538779Y1198621D03*
Y1191141D03*
X1542519Y1194881D03*
X1546259D03*
X1542519Y1202362D03*
X1546259D03*
X1531299Y1206102D03*
X1535039D03*
X1531299Y1217322D03*
X1535039Y1213582D03*
X1531299Y1209842D03*
Y1213582D03*
X1538779Y1206102D03*
Y1213582D03*
X1542519Y1209842D03*
X1546259D03*
X1531299Y1221062D03*
X1535039D03*
X1546259Y1217322D03*
Y1221062D03*
X1538779D03*
X1542519D03*
Y1217322D03*
X1531299Y1224803D03*
Y1228543D03*
X1535039Y1232283D03*
Y1236023D03*
X1542519Y1232283D03*
Y1236023D03*
X1538779Y1228543D03*
Y1224803D03*
X1546259D03*
Y1228543D03*
X1531299Y1247243D03*
X1535039Y1250984D03*
Y1254724D03*
Y1239763D03*
X1531299D03*
Y1243503D03*
X1538779Y1247243D03*
X1542519Y1254724D03*
X1538779Y1239763D03*
Y1243503D03*
X1542519Y1250984D03*
Y1239763D03*
X1546259D03*
Y1243503D03*
Y1247243D03*
X1546260Y1258465D03*
X1538779D03*
X1531299D03*
X1544810Y1348187D03*
X1532570D03*
X1540450D03*
X1544810Y1360099D03*
X1532570D03*
X1540450D03*
X1544810Y1384297D03*
Y1372385D03*
X1532570Y1384297D03*
Y1372385D03*
X1540450Y1384297D03*
Y1372385D03*
X1544810Y1396583D03*
X1532570D03*
X1540450D03*
X1544810Y1408495D03*
X1532570D03*
X1540450D03*
X1557480Y1075196D03*
X1550000D03*
X1561219Y1071455D03*
X1553739D03*
X1561220Y1086417D03*
Y1090157D03*
Y1082677D03*
X1557480Y1078936D03*
Y1090157D03*
X1553740Y1082677D03*
Y1086417D03*
Y1090157D03*
X1550000Y1078936D03*
Y1090157D03*
X1561220Y1105117D03*
X1553740D03*
X1561220Y1101377D03*
X1557480Y1097637D03*
Y1093897D03*
X1553740Y1101377D03*
X1550000Y1093897D03*
Y1097637D03*
X1551870Y1114468D03*
X1548130D03*
X1563090Y1118208D03*
X1559350D03*
X1555610D03*
X1551870D03*
X1548130D03*
X1563090Y1121948D03*
X1559350D03*
X1555610D03*
X1551870D03*
X1548130D03*
Y1110728D03*
X1561220Y1108858D03*
X1557480D03*
X1553740D03*
X1550000D03*
X1551870Y1110728D03*
X1559350Y1114468D03*
X1555610D03*
X1563090D03*
X1548130Y1140649D03*
X1563090Y1125688D03*
X1559350D03*
X1555610D03*
X1551870D03*
X1548130D03*
X1559350Y1129429D03*
X1555610D03*
X1551870D03*
X1548130D03*
X1559350Y1133169D03*
X1555610D03*
X1551870D03*
X1548130D03*
X1559350Y1136909D03*
X1551870D03*
X1548130D03*
X1559350Y1140649D03*
X1555610D03*
X1551870D03*
X1563090D03*
Y1136909D03*
X1555610D03*
X1563090Y1129429D03*
Y1133169D03*
X1551870Y1155610D03*
Y1151870D03*
X1559350Y1144389D03*
X1551870D03*
Y1148129D03*
X1559350Y1151870D03*
X1563090Y1155610D03*
Y1148129D03*
Y1144389D03*
Y1151869D03*
X1555610Y1144389D03*
X1548130Y1151870D03*
Y1148129D03*
Y1144389D03*
X1559350Y1155610D03*
X1555610Y1151870D03*
X1559350Y1148129D03*
Y1170570D03*
X1551870Y1166830D03*
X1559350Y1159350D03*
X1551870D03*
X1548130Y1170570D03*
X1551870D03*
X1563090Y1166830D03*
Y1159350D03*
Y1170570D03*
X1548130Y1166830D03*
Y1159350D03*
X1555610Y1170570D03*
X1559350Y1166830D03*
X1555610Y1159350D03*
X1551870Y1189271D03*
X1559350Y1185531D03*
X1551870D03*
Y1178051D03*
Y1174310D03*
X1559350Y1178051D03*
X1551870Y1181791D03*
X1563090D03*
Y1174310D03*
X1550000Y1187401D03*
X1548130Y1185531D03*
Y1174310D03*
Y1178051D03*
Y1181791D03*
X1563090Y1185531D03*
Y1178051D03*
X1555610Y1185531D03*
X1559350Y1174310D03*
Y1181791D03*
X1555610Y1178051D03*
X1551870Y1193011D03*
X1559350D03*
Y1196751D03*
Y1200491D03*
X1555610D03*
Y1204232D03*
X1559350D03*
X1563090D03*
Y1196751D03*
Y1200491D03*
X1555610Y1193011D03*
Y1196751D03*
X1550000Y1191141D03*
Y1194881D03*
Y1198621D03*
Y1202362D03*
X1563090Y1193011D03*
X1555610Y1211712D03*
X1559350D03*
X1563090D03*
Y1207972D03*
X1559350D03*
X1555610D03*
X1563090Y1219192D03*
X1550000Y1221062D03*
X1553740D03*
X1557480D03*
X1561220D03*
X1550000Y1206102D03*
Y1209842D03*
Y1213582D03*
Y1217322D03*
X1553740D03*
X1555610Y1215452D03*
X1563090D03*
X1559350D03*
X1550000Y1232283D03*
Y1236023D03*
X1561220Y1224803D03*
Y1228543D03*
X1557480Y1232283D03*
Y1236023D03*
X1553740Y1228543D03*
Y1224803D03*
X1550000Y1250984D03*
Y1254724D03*
Y1239763D03*
X1557480Y1250984D03*
Y1254724D03*
X1561220Y1247243D03*
X1557480Y1239763D03*
X1561220D03*
Y1243503D03*
X1553740Y1247243D03*
Y1239763D03*
Y1243503D03*
X1561220Y1258465D03*
X1553740D03*
X1557050Y1348187D03*
X1552690D03*
Y1360099D03*
X1557050D03*
Y1384297D03*
Y1372385D03*
X1552690D03*
Y1384297D03*
X1557050Y1396583D03*
X1552690D03*
X1557050Y1408495D03*
X1552690D03*
X1572441Y1075196D03*
X1564960D03*
X1576180Y1071455D03*
X1568699D03*
X1564960Y1090157D03*
Y1078936D03*
X1572441Y1090157D03*
Y1078936D03*
X1576181Y1082677D03*
Y1086417D03*
Y1090157D03*
X1568700Y1082677D03*
Y1086417D03*
Y1090157D03*
X1576181Y1105117D03*
X1568700D03*
X1564960Y1093897D03*
Y1097637D03*
X1572441Y1093897D03*
Y1097637D03*
X1576181Y1101377D03*
X1568700D03*
X1566830Y1121948D03*
X1578051Y1118208D03*
X1574311D03*
Y1121948D03*
X1578051D03*
X1570571Y1118208D03*
X1566830D03*
X1570571Y1121948D03*
X1576181Y1108858D03*
X1572441D03*
X1568700D03*
X1564960D03*
X1574311Y1114468D03*
X1570571D03*
X1578051D03*
X1566830D03*
Y1133169D03*
Y1129429D03*
X1570571Y1140649D03*
X1574311D03*
X1578051D03*
X1570571Y1125688D03*
X1574311D03*
X1578051D03*
X1566830D03*
X1578051Y1133169D03*
X1574311D03*
X1570571D03*
X1566830Y1136909D03*
X1578051D03*
X1574311D03*
X1570571D03*
X1574311Y1129429D03*
X1570571D03*
X1578051D03*
X1566830Y1140649D03*
X1574311Y1148129D03*
X1570571D03*
X1578051D03*
X1570571Y1155610D03*
X1566830Y1151869D03*
X1578051Y1155610D03*
X1566830Y1144389D03*
X1578051D03*
X1574311D03*
X1570571D03*
X1578051Y1151870D03*
X1574311D03*
X1570571D03*
X1574311Y1155610D03*
X1566830Y1148129D03*
Y1155610D03*
Y1159350D03*
X1578051Y1166830D03*
X1574311Y1159350D03*
X1570571Y1166830D03*
X1566830Y1170570D03*
X1574311D03*
X1578051D03*
X1574311Y1166830D03*
X1570571Y1170570D03*
X1566830Y1166830D03*
X1578051Y1159350D03*
X1570571D03*
X1578051Y1181791D03*
X1574311D03*
X1570571D03*
X1578051Y1189271D03*
X1574311D03*
X1570571D03*
X1566830D03*
Y1178051D03*
X1570571Y1174310D03*
X1566830Y1185531D03*
X1578051Y1174310D03*
X1574311Y1185531D03*
X1570571D03*
X1578051D03*
Y1178051D03*
X1574311D03*
X1570571D03*
X1574311Y1174310D03*
X1566830Y1181791D03*
Y1174310D03*
X1574311Y1204232D03*
X1578051D03*
Y1196751D03*
X1574311D03*
X1570571D03*
X1566830Y1200491D03*
Y1196751D03*
Y1193011D03*
Y1204232D03*
X1570571D03*
Y1193011D03*
X1574311D03*
X1578051D03*
X1570571Y1200491D03*
X1578051D03*
X1574311D03*
X1566830Y1207972D03*
Y1211712D03*
X1578051Y1207972D03*
X1574311D03*
X1570571D03*
X1564960Y1221062D03*
X1568700D03*
X1572441D03*
X1576181D03*
X1578051Y1215452D03*
X1566830D03*
X1570571Y1211712D03*
X1566830Y1219192D03*
X1574311Y1215452D03*
X1570571D03*
X1578051Y1211712D03*
X1574311D03*
X1564960Y1232283D03*
Y1236023D03*
X1576181Y1224803D03*
Y1228543D03*
X1572441Y1232283D03*
Y1236023D03*
X1568700Y1228543D03*
Y1224803D03*
X1564960Y1250984D03*
Y1254724D03*
Y1239763D03*
X1572441Y1250984D03*
Y1254724D03*
X1576181Y1247243D03*
Y1243503D03*
X1572441Y1239763D03*
X1576181D03*
X1568700Y1247243D03*
Y1243503D03*
Y1239763D03*
X1576181Y1258465D03*
X1568701D03*
X1564930Y1348187D03*
X1569290D03*
X1577170D03*
X1569290Y1360099D03*
X1577170D03*
X1564930D03*
X1577170Y1372385D03*
Y1384297D03*
X1569290Y1372385D03*
Y1384297D03*
X1564930D03*
Y1372385D03*
X1577170Y1396583D03*
X1569290D03*
X1564930D03*
X1577170Y1408495D03*
X1569290D03*
X1564930D03*
X1579921Y1075196D03*
X1587401D03*
X1594882D03*
X1591140Y1071455D03*
X1583660D03*
X1579921Y1090157D03*
X1583661D03*
Y1086417D03*
Y1082677D03*
X1579921Y1078936D03*
X1587401Y1090157D03*
Y1078936D03*
X1591141Y1082677D03*
Y1086417D03*
Y1090157D03*
X1594882D03*
Y1078936D03*
X1583661Y1105117D03*
X1591141D03*
X1579921Y1093897D03*
Y1097637D03*
X1583661Y1101377D03*
X1587401Y1097637D03*
Y1093897D03*
X1594882D03*
Y1097637D03*
X1591141Y1101377D03*
X1581791Y1121948D03*
X1585531Y1118208D03*
X1589271D03*
X1593011D03*
X1589271Y1121948D03*
X1593011D03*
X1585531D03*
X1581791Y1118208D03*
X1585531Y1114468D03*
X1594882Y1108858D03*
X1591141D03*
X1587401D03*
X1583661D03*
X1579921D03*
X1587401Y1112598D03*
X1593012Y1114468D03*
X1589271D03*
X1581791D03*
Y1133169D03*
Y1140649D03*
X1585531D03*
X1589271D03*
X1593011D03*
X1589271Y1125688D03*
X1585531D03*
X1581791D03*
X1593011D03*
Y1133169D03*
X1589271D03*
X1585531D03*
X1593011Y1136909D03*
X1589271D03*
X1585531D03*
X1581791D03*
X1589271Y1129429D03*
X1585531D03*
X1581791D03*
X1593011D03*
Y1148129D03*
X1589271D03*
X1585531D03*
X1581791D03*
X1593011Y1155610D03*
X1585531D03*
Y1144389D03*
X1581791D03*
X1593011D03*
X1589271D03*
X1593012Y1151870D03*
X1589271D03*
X1585531D03*
X1581791D03*
Y1155610D03*
X1589271D03*
Y1170570D03*
X1593012Y1166830D03*
X1585531D03*
X1581791Y1159350D03*
X1589271D03*
X1581791Y1170570D03*
X1593011D03*
X1585531D03*
X1589271Y1166830D03*
X1581791D03*
X1585531Y1159350D03*
X1593011D03*
Y1181791D03*
X1589271D03*
X1585531D03*
X1581791D03*
X1593011Y1189271D03*
X1589271D03*
X1585531D03*
X1581791D03*
X1585531Y1174310D03*
X1593011D03*
X1589271Y1185531D03*
X1585531D03*
X1581791D03*
X1593011D03*
X1581791Y1178051D03*
X1593011D03*
X1589271D03*
X1585531D03*
X1589271Y1174310D03*
X1581791D03*
X1593011Y1204232D03*
Y1196751D03*
X1589271D03*
X1585531D03*
X1581791D03*
Y1204232D03*
X1585531D03*
X1589271D03*
X1585531Y1193011D03*
X1589271D03*
X1593011D03*
X1581791D03*
X1589271Y1200491D03*
X1585531D03*
X1581791D03*
X1593011D03*
Y1219192D03*
X1591141Y1217322D03*
X1593011Y1207972D03*
X1589271D03*
X1585531D03*
X1589271Y1211712D03*
X1581791Y1207972D03*
Y1211712D03*
X1591141Y1221062D03*
X1587401D03*
X1579921D03*
X1583661D03*
X1594882D03*
X1593012Y1211712D03*
Y1215452D03*
X1581791D03*
X1589271D03*
X1585531D03*
Y1211712D03*
X1583661Y1224803D03*
Y1228543D03*
X1579921Y1232283D03*
Y1236023D03*
X1594882Y1232283D03*
Y1236023D03*
X1591141Y1228543D03*
Y1224803D03*
X1587401Y1232283D03*
Y1236023D03*
X1583661Y1243503D03*
Y1247243D03*
X1579921Y1254724D03*
Y1250984D03*
Y1239763D03*
X1583661D03*
X1587401Y1250984D03*
Y1254724D03*
X1591141Y1247243D03*
Y1243503D03*
X1594882Y1250984D03*
Y1254724D03*
Y1239763D03*
X1591141D03*
X1587401D03*
X1591142Y1258465D03*
X1583661D03*
X1589410Y1348187D03*
X1581530D03*
X1589410Y1360099D03*
X1581530D03*
Y1384297D03*
Y1372385D03*
X1589410Y1384297D03*
Y1372385D03*
X1581530Y1396583D03*
X1589410D03*
X1581530Y1408495D03*
X1589410D03*
X1609842Y1075196D03*
X1602362D03*
X1606101Y1071454D03*
X1598621Y1071455D03*
X1598622Y1082677D03*
Y1086417D03*
Y1090157D03*
X1606102Y1082677D03*
Y1086417D03*
X1609842Y1090157D03*
X1606102D03*
X1609842Y1078936D03*
X1602362Y1090157D03*
Y1078936D03*
X1598622Y1105117D03*
X1606102D03*
X1598622Y1101377D03*
X1606102D03*
X1609842Y1093897D03*
Y1097637D03*
X1602362Y1093897D03*
Y1097637D03*
X1596752Y1121948D03*
X1600492Y1118208D03*
Y1114468D03*
X1611712Y1121948D03*
X1607972D03*
X1596752Y1118208D03*
X1600492Y1121948D03*
X1609842Y1108858D03*
X1606102D03*
X1602362D03*
X1598622D03*
X1596752Y1114468D03*
X1607972D03*
X1611712Y1118208D03*
X1607972D03*
X1611712Y1114468D03*
X1607972Y1125688D03*
X1611712D03*
X1607972Y1133464D03*
X1611712Y1133169D03*
X1600590Y1132677D03*
X1596752Y1133169D03*
Y1140649D03*
X1600492D03*
Y1125688D03*
X1596752D03*
X1607972Y1140649D03*
X1611712D03*
X1600492Y1136909D03*
X1596752D03*
X1611712D03*
X1607972D03*
X1611712Y1129429D03*
X1607972D03*
X1600492D03*
X1596752D03*
X1600492Y1148129D03*
X1596752D03*
X1607972D03*
X1611712D03*
X1600492Y1155610D03*
X1611712D03*
X1600492Y1144389D03*
X1596752D03*
X1611712Y1151869D03*
X1607972D03*
X1611712Y1144389D03*
X1607972D03*
X1600492Y1151870D03*
X1596752D03*
Y1155610D03*
X1607972D03*
X1596752Y1170570D03*
Y1159350D03*
X1611712Y1166830D03*
X1607972Y1170570D03*
X1600492Y1166830D03*
X1607972Y1159350D03*
Y1166830D03*
X1611712Y1170570D03*
X1600492D03*
X1596752Y1166830D03*
X1611712Y1159350D03*
X1600492D03*
Y1181791D03*
X1611712D03*
X1607972D03*
Y1189271D03*
X1611712D03*
X1596752Y1181791D03*
X1600492Y1189271D03*
X1596752D03*
X1600492Y1174310D03*
X1611712D03*
X1600492Y1185531D03*
X1596752D03*
X1600492Y1178051D03*
X1596752D03*
X1611712Y1185531D03*
X1607972D03*
X1611712Y1178051D03*
X1607972D03*
Y1174310D03*
X1596752D03*
X1611712Y1204232D03*
X1607972D03*
Y1196751D03*
X1611712D03*
X1600492D03*
X1596752D03*
Y1204232D03*
X1600492D03*
X1607972Y1193011D03*
X1611712D03*
X1600492D03*
X1596752D03*
X1600492Y1200491D03*
X1596752D03*
X1611712D03*
X1607972D03*
X1606102Y1221062D03*
X1596752Y1207972D03*
X1607972D03*
X1611712D03*
Y1211712D03*
X1596752Y1219192D03*
X1600492Y1207972D03*
X1598622Y1221062D03*
X1609842D03*
X1602362D03*
X1600492Y1211712D03*
Y1215452D03*
X1596752Y1211712D03*
X1611712Y1215452D03*
X1607972D03*
Y1211712D03*
X1609842Y1217322D03*
X1598622Y1228543D03*
Y1224803D03*
X1609842Y1232283D03*
Y1236023D03*
X1606102Y1228543D03*
Y1224803D03*
X1602362Y1232283D03*
Y1236023D03*
X1598622Y1239763D03*
Y1243503D03*
Y1247243D03*
X1609842Y1254724D03*
Y1250984D03*
X1606102Y1247243D03*
Y1243503D03*
Y1239763D03*
X1609842D03*
X1602362D03*
Y1250984D03*
Y1254724D03*
X1606102Y1258465D03*
X1598623D03*
X1609158Y1348187D03*
Y1360099D03*
Y1384297D03*
Y1372385D03*
X1624803Y1075196D03*
X1617322D03*
X1621062Y1071455D03*
X1613581D03*
X1617322Y1090157D03*
Y1078936D03*
X1613582Y1090157D03*
Y1086417D03*
Y1082677D03*
X1624803Y1078936D03*
X1621063Y1082677D03*
Y1086417D03*
Y1090157D03*
X1624803D03*
X1617322Y1093897D03*
Y1097637D03*
X1624803Y1093897D03*
Y1097637D03*
X1621063Y1101377D03*
Y1105117D03*
X1613582D03*
Y1101377D03*
X1626673Y1121948D03*
X1622933D03*
X1619193D03*
X1615452D03*
X1624803Y1108858D03*
X1621063D03*
X1617322D03*
X1613582D03*
X1615452Y1118208D03*
X1619193D03*
X1615452Y1114468D03*
X1619193D03*
X1622933D03*
X1626673D03*
Y1118208D03*
X1622933D03*
X1615452Y1133169D03*
X1619193D03*
X1622933D03*
X1626673D03*
X1615452Y1140649D03*
X1619193D03*
X1622933D03*
X1626673D03*
X1615452Y1125688D03*
X1619193D03*
X1622933D03*
X1626673D03*
Y1136909D03*
X1622933D03*
X1615452D03*
X1619193D03*
X1626673Y1129429D03*
X1622933D03*
X1619193D03*
X1615452D03*
Y1148129D03*
X1619193D03*
X1622933D03*
X1626673D03*
X1619193Y1155610D03*
X1626673D03*
X1615452Y1151869D03*
X1619193D03*
X1626673D03*
X1622933D03*
Y1144389D03*
X1615452D03*
X1619193D03*
X1626673D03*
X1622933Y1155610D03*
X1615452D03*
Y1170570D03*
X1622933D03*
X1626673Y1166830D03*
X1615452Y1159350D03*
X1619193Y1166830D03*
X1622933Y1159350D03*
X1615452Y1166830D03*
X1619193Y1170570D03*
X1626673Y1159350D03*
X1619193D03*
X1622933Y1166830D03*
X1626673Y1170570D03*
X1615452Y1181791D03*
X1619193D03*
X1622933D03*
X1626673D03*
X1615452Y1189271D03*
X1619193D03*
X1622933D03*
X1626673D03*
Y1174310D03*
X1619193D03*
Y1185531D03*
X1626673D03*
X1622933D03*
Y1178051D03*
X1615452D03*
X1619193D03*
X1626673D03*
X1615452Y1185531D03*
X1622933Y1174310D03*
X1615452D03*
X1619193Y1204232D03*
X1615452D03*
X1626673D03*
X1622933D03*
X1615452Y1196751D03*
X1619193D03*
X1622933D03*
X1626673D03*
X1622933Y1193011D03*
X1626673D03*
X1615452D03*
X1619193D03*
X1622933Y1200491D03*
X1619193D03*
X1615452D03*
X1626673D03*
X1617322Y1221062D03*
X1619193Y1207972D03*
X1622933D03*
X1626673Y1211712D03*
Y1207972D03*
X1615452Y1211712D03*
Y1207972D03*
X1621063Y1221062D03*
X1613582D03*
X1624803D03*
X1622933Y1215452D03*
X1619192Y1215451D03*
X1626673Y1215452D03*
X1615452D03*
X1613582Y1217322D03*
X1619192Y1211711D03*
X1622933D03*
X1613582Y1228543D03*
Y1224803D03*
X1621063Y1228543D03*
Y1224803D03*
X1624803Y1232283D03*
Y1236023D03*
X1617322Y1232283D03*
Y1236023D03*
X1613582Y1239763D03*
Y1243503D03*
Y1247243D03*
X1621063Y1239763D03*
Y1243503D03*
Y1247243D03*
X1624803Y1239763D03*
Y1250984D03*
Y1254724D03*
X1617322Y1239763D03*
Y1250984D03*
Y1254724D03*
X1621063Y1258465D03*
X1613582D03*
X1617038Y1348187D03*
X1621398D03*
X1617038Y1360099D03*
X1621398D03*
X1617038Y1384297D03*
Y1372385D03*
X1621398D03*
Y1384297D03*
Y1396583D03*
Y1408495D03*
X1639763Y1075196D03*
X1632283D03*
X1643503Y1071455D03*
X1636022D03*
X1628542D03*
X1636023Y1090157D03*
X1643504Y1082677D03*
X1636023D03*
Y1086417D03*
X1643504Y1090157D03*
Y1086417D03*
X1639763Y1090157D03*
Y1078936D03*
X1632283D03*
X1628543Y1082677D03*
Y1086417D03*
Y1090157D03*
X1632283D03*
Y1093897D03*
X1636023Y1101377D03*
X1643504D03*
X1628543D03*
X1632283Y1097637D03*
X1639763Y1093897D03*
Y1097637D03*
X1628543Y1105117D03*
X1636023D03*
X1643504D03*
X1641633Y1118208D03*
X1637893Y1121948D03*
X1634153D03*
X1630413D03*
X1641633D03*
X1643504Y1108858D03*
X1639763D03*
X1636023D03*
X1632283D03*
X1628543D03*
X1637893Y1118208D03*
Y1114468D03*
X1634153D03*
X1630413D03*
X1641633D03*
X1634153Y1118208D03*
X1630413D03*
X1641633Y1136909D03*
X1630413Y1133169D03*
X1634153D03*
X1637893D03*
X1641633D03*
X1634153Y1140649D03*
X1637893D03*
X1641633Y1125688D03*
Y1129429D03*
X1630413Y1125688D03*
X1634153D03*
X1637893D03*
X1641633Y1140649D03*
X1630413D03*
Y1136909D03*
X1637893D03*
X1634153D03*
X1630413Y1129429D03*
X1637893D03*
X1634153D03*
X1630413Y1148129D03*
X1634153D03*
X1637893D03*
X1641633Y1144389D03*
Y1148129D03*
Y1151869D03*
X1634153Y1155610D03*
X1641633D03*
X1630413Y1151869D03*
X1637893D03*
X1634153D03*
Y1144389D03*
X1630413D03*
X1637893D03*
Y1155610D03*
X1630413D03*
X1634153Y1166830D03*
X1630413Y1159350D03*
Y1170570D03*
X1637893D03*
X1641633D03*
X1634153D03*
X1641633Y1166830D03*
X1637893D03*
Y1159350D03*
X1641633D03*
X1634153D03*
X1630413Y1166830D03*
X1634153Y1189271D03*
X1637893D03*
X1641633Y1178051D03*
X1634153Y1174310D03*
X1641633Y1185531D03*
X1630413Y1181791D03*
X1634153D03*
X1637893D03*
X1641633Y1189271D03*
X1630413D03*
X1641633Y1174310D03*
Y1181791D03*
X1630413Y1185531D03*
X1634153D03*
X1630413Y1178051D03*
X1634153D03*
X1637893Y1185531D03*
Y1178051D03*
Y1174310D03*
X1630413D03*
X1641653Y1196732D03*
X1641633Y1204232D03*
X1630413D03*
X1634153D03*
X1637893D03*
X1641633Y1200491D03*
X1630413Y1196751D03*
X1634153D03*
X1637893D03*
X1641633Y1193011D03*
X1634153D03*
X1637893D03*
X1630413D03*
Y1200491D03*
X1637893D03*
X1634153D03*
X1641633Y1211712D03*
X1634153Y1207972D03*
X1630413D03*
X1634153Y1211712D03*
X1637893Y1207972D03*
Y1211712D03*
X1630413D03*
X1641633Y1207972D03*
X1628543Y1221062D03*
X1632283D03*
X1636023D03*
X1639763D03*
X1643504D03*
X1630413Y1215452D03*
X1637893D03*
X1634153D03*
X1628543Y1228543D03*
Y1224803D03*
X1632283Y1232283D03*
Y1236023D03*
X1636023Y1228543D03*
Y1224803D03*
X1639763Y1232283D03*
Y1236023D03*
X1643504Y1228543D03*
Y1224803D03*
X1632283Y1254724D03*
X1628543Y1247243D03*
Y1243503D03*
X1632283Y1239763D03*
Y1250984D03*
X1628543Y1239763D03*
X1636023Y1247243D03*
X1639763Y1250984D03*
Y1254724D03*
X1643504Y1247243D03*
X1636023Y1239763D03*
X1643504D03*
X1639763D03*
X1636023Y1243503D03*
X1643504D03*
Y1258465D03*
X1636023D03*
X1628543D03*
X1629278Y1348187D03*
X1641518D03*
X1633638D03*
X1629278Y1360099D03*
X1641518D03*
X1633638D03*
X1629278Y1384297D03*
Y1372385D03*
X1641518Y1384297D03*
Y1372385D03*
X1633638Y1384297D03*
Y1372385D03*
X1629278Y1396583D03*
X1641518D03*
X1633638D03*
Y1408495D03*
X1629278D03*
X1641518D03*
X1647244Y1075196D03*
X1654724D03*
X1658463Y1071455D03*
X1650983D03*
X1654724Y1078936D03*
Y1090157D03*
X1658464D03*
Y1086417D03*
Y1082677D03*
X1650984D03*
Y1086417D03*
Y1090157D03*
X1647244D03*
Y1078936D03*
Y1097637D03*
Y1093897D03*
X1654724Y1097637D03*
X1658464Y1101377D03*
X1654724Y1093897D03*
X1650984Y1101377D03*
X1658464Y1105117D03*
X1650984D03*
X1645374Y1118208D03*
X1649114D03*
Y1121948D03*
X1645374D03*
X1658464Y1108858D03*
X1654724D03*
X1650984D03*
X1647244D03*
X1656594Y1118208D03*
X1652854D03*
Y1114468D03*
X1645374D03*
X1649114D03*
X1656594D03*
X1649114Y1133169D03*
Y1140649D03*
X1652854Y1136909D03*
X1649114Y1125688D03*
X1645374D03*
X1649114Y1129429D03*
Y1136909D03*
X1652854Y1140649D03*
X1645374Y1129429D03*
Y1136909D03*
Y1140649D03*
X1656594Y1133169D03*
Y1140649D03*
Y1136909D03*
X1660334Y1140649D03*
X1645374Y1155610D03*
Y1151869D03*
Y1148129D03*
X1652854D03*
X1649114Y1144389D03*
X1652854Y1155610D03*
X1649114Y1148129D03*
X1652854Y1151869D03*
X1656594D03*
X1660334D03*
Y1155610D03*
Y1144389D03*
X1649114Y1151870D03*
Y1155610D03*
X1656594D03*
X1645374Y1144389D03*
X1660334Y1148129D03*
X1652854Y1144389D03*
X1656594Y1148129D03*
Y1144389D03*
X1645374Y1166830D03*
X1652854Y1159350D03*
X1660334Y1166830D03*
Y1170570D03*
X1645374Y1159350D03*
X1660334D03*
X1645374Y1170570D03*
X1652854D03*
Y1166830D03*
X1649114Y1159350D03*
Y1170570D03*
Y1166830D03*
X1656594Y1170570D03*
Y1166830D03*
Y1159350D03*
X1652854Y1185531D03*
X1656594Y1181791D03*
X1652854Y1178051D03*
Y1174310D03*
X1649114Y1181791D03*
X1656594Y1185531D03*
X1660334Y1174310D03*
Y1178051D03*
Y1185531D03*
X1645374Y1181791D03*
Y1174310D03*
X1649114Y1178051D03*
Y1189271D03*
X1652854D03*
X1649114Y1185531D03*
X1656594Y1189271D03*
X1649114Y1174310D03*
X1656594D03*
X1652854Y1181791D03*
X1660334Y1189271D03*
X1645374Y1185531D03*
Y1189271D03*
X1660334Y1181791D03*
X1656594Y1178051D03*
X1645374D03*
Y1204232D03*
X1656594Y1193011D03*
X1652854Y1204232D03*
X1660334D03*
Y1200491D03*
Y1193011D03*
X1652854Y1196751D03*
Y1193011D03*
X1649114D03*
X1645374Y1196751D03*
X1660334D03*
X1645374Y1200491D03*
Y1193011D03*
X1656594Y1196751D03*
Y1204232D03*
X1652854Y1200491D03*
X1649114Y1204232D03*
Y1196751D03*
Y1200491D03*
X1656594D03*
X1649114Y1211712D03*
X1645374Y1207972D03*
X1660334D03*
Y1215452D03*
Y1211712D03*
X1654724Y1221062D03*
X1658464D03*
X1650984D03*
X1647244D03*
X1645374Y1215452D03*
X1649114D03*
X1652854D03*
X1656594Y1211712D03*
X1645374D03*
X1656594Y1215452D03*
Y1207972D03*
X1649114D03*
X1652854D03*
Y1211712D03*
X1647244Y1232283D03*
Y1236023D03*
X1654724Y1232283D03*
X1658464Y1228543D03*
X1654724Y1236023D03*
X1658464Y1224803D03*
X1650984Y1228543D03*
Y1224803D03*
X1647244Y1254724D03*
Y1250984D03*
Y1239763D03*
X1654724Y1250984D03*
Y1254724D03*
X1658464Y1247243D03*
X1654724Y1239763D03*
X1658464D03*
Y1243503D03*
X1650984Y1247243D03*
Y1239763D03*
Y1243503D03*
X1658464Y1258465D03*
X1650984D03*
X1645878Y1348187D03*
X1653758D03*
X1658118D03*
X1645878Y1360099D03*
X1653758D03*
X1658118D03*
X1645878Y1384297D03*
Y1372385D03*
X1653758D03*
Y1384297D03*
X1658118D03*
Y1372385D03*
X1645878Y1396583D03*
X1653758D03*
X1658118D03*
X1645878Y1408495D03*
X1653758D03*
X1658118D03*
X1662204Y1075196D03*
X1669685D03*
X1673425Y1071455D03*
X1665944D03*
X1662204Y1078936D03*
X1662203Y1090157D03*
X1669686Y1078936D03*
X1673424Y1082677D03*
X1673425Y1086417D03*
X1669684Y1090157D03*
X1673424D03*
X1665944Y1082677D03*
X1665945Y1086417D03*
X1665944Y1090157D03*
X1662204Y1093897D03*
Y1097637D03*
X1669685Y1093897D03*
Y1097637D03*
X1673425Y1101377D03*
X1665944D03*
X1673425Y1105117D03*
X1665945D03*
X1669685Y1108858D03*
X1673425D03*
Y1116338D03*
X1669685Y1112598D03*
Y1120078D03*
X1673425Y1123818D03*
X1665944Y1112598D03*
Y1120078D03*
X1665945Y1108858D03*
X1662204Y1123818D03*
Y1120078D03*
Y1116338D03*
Y1108858D03*
X1675295Y1140649D03*
X1671555D03*
Y1136909D03*
X1669685Y1127558D03*
X1673425Y1131299D03*
X1665945Y1127558D03*
X1669685Y1135039D03*
X1665945D03*
X1662204D03*
Y1131299D03*
Y1127558D03*
Y1138779D03*
X1664075Y1140649D03*
X1667815Y1151869D03*
X1664074D03*
X1675295Y1155610D03*
Y1148129D03*
X1671555Y1155610D03*
Y1151869D03*
Y1148129D03*
Y1144389D03*
X1664074D03*
X1667815D03*
Y1155610D03*
X1664075Y1148129D03*
Y1155610D03*
X1675295Y1144389D03*
Y1151869D03*
X1664074Y1159350D03*
X1667815D03*
X1671555D03*
X1667815Y1166830D03*
X1664074D03*
X1675295Y1170570D03*
X1671555D03*
Y1166830D03*
X1675295D03*
Y1159350D03*
X1664075Y1170570D03*
X1667815D03*
X1664074Y1189271D03*
Y1174310D03*
X1671555Y1185531D03*
Y1181791D03*
Y1178051D03*
Y1174310D03*
X1667815D03*
Y1181791D03*
X1664074D03*
X1667815Y1189271D03*
X1675295Y1185531D03*
Y1178051D03*
X1671555Y1189271D03*
X1675295D03*
Y1174310D03*
Y1181791D03*
X1665945Y1194881D03*
X1669685D03*
X1664074Y1204232D03*
X1675295Y1193011D03*
X1671555D03*
X1665945Y1202362D03*
X1669685D03*
X1673425Y1198621D03*
Y1221062D03*
X1669685D03*
Y1217322D03*
X1673425Y1213582D03*
X1669685Y1209842D03*
X1665945Y1221062D03*
Y1217322D03*
Y1209842D03*
X1673425Y1206102D03*
X1662204Y1221062D03*
Y1232283D03*
Y1236023D03*
X1673425Y1224803D03*
Y1228543D03*
X1669685Y1232283D03*
Y1236023D03*
X1665945Y1224803D03*
Y1228543D03*
Y1247243D03*
Y1243503D03*
Y1239763D03*
X1662204Y1250984D03*
Y1254724D03*
Y1239763D03*
X1669685Y1250984D03*
Y1254724D03*
X1673425Y1247243D03*
Y1243503D03*
X1669685Y1239763D03*
X1673425D03*
Y1258465D03*
X1665945D03*
X1665998Y1348187D03*
X1670358D03*
X1665998Y1360099D03*
X1670358D03*
X1665998Y1384297D03*
Y1372385D03*
X1670358D03*
Y1384297D03*
X1665998Y1396583D03*
X1670358D03*
X1665998Y1408495D03*
X1670358D03*
X1677166Y1075196D03*
X1684646D03*
X1692126D03*
X1688385Y1071455D03*
X1680905D03*
X1677166Y1078936D03*
X1680904Y1082677D03*
X1680905Y1086417D03*
X1677164Y1090157D03*
X1680904D03*
X1692126Y1078936D03*
X1684646D03*
X1688385Y1082677D03*
X1692126Y1086417D03*
X1688386D03*
X1684644Y1090157D03*
X1688385D03*
X1677165Y1093897D03*
Y1097637D03*
X1680905Y1101377D03*
X1684645Y1093897D03*
Y1097637D03*
X1688385Y1101377D03*
X1692126Y1093897D03*
Y1097637D03*
X1680905Y1105117D03*
X1688386D03*
X1692126D03*
X1677164Y1108857D03*
X1680904Y1108858D03*
X1680905Y1116338D03*
X1677165D03*
X1680905Y1112598D03*
Y1123818D03*
X1677165D03*
X1680905Y1120078D03*
X1684645Y1108858D03*
X1688385D03*
X1684645Y1116338D03*
X1688385D03*
X1692126Y1112598D03*
X1684645Y1123818D03*
X1688385D03*
X1692126Y1120078D03*
X1690256Y1140649D03*
X1686515Y1136909D03*
X1690256D03*
X1682775D03*
X1679035Y1140649D03*
X1680905Y1127558D03*
Y1131299D03*
X1677165D03*
X1692126Y1127558D03*
X1688385Y1131299D03*
X1684644D03*
X1680905Y1135039D03*
X1692126D03*
X1686515Y1140649D03*
X1682775D03*
X1690256Y1144389D03*
X1682775D03*
X1679035Y1148129D03*
X1682775Y1151869D03*
X1679035Y1155610D03*
X1686515Y1144389D03*
X1690256Y1155610D03*
X1686515Y1151869D03*
X1690256D03*
Y1148129D03*
X1679035Y1151869D03*
Y1144389D03*
X1682775Y1148129D03*
X1686515Y1155610D03*
Y1148129D03*
X1682775Y1155610D03*
Y1166830D03*
X1679035Y1170570D03*
X1686515Y1159350D03*
X1690256D03*
X1682775D03*
X1679035D03*
X1686515Y1166830D03*
X1690256Y1170570D03*
Y1166830D03*
X1679035D03*
X1686515Y1170570D03*
X1682775D03*
X1690256Y1178051D03*
X1686515Y1174310D03*
X1690256D03*
X1682775D03*
X1679035Y1178051D03*
X1682775Y1181791D03*
X1679035Y1185531D03*
X1682775Y1189271D03*
X1686515Y1181791D03*
Y1189271D03*
X1690256D03*
Y1185531D03*
Y1181791D03*
X1679035D03*
Y1189271D03*
Y1174310D03*
X1686515Y1185531D03*
X1682775Y1178051D03*
X1686515D03*
X1682775Y1185531D03*
X1680905Y1194881D03*
X1690256Y1193011D03*
X1679035D03*
X1692126Y1202362D03*
X1688385Y1198621D03*
X1684645D03*
X1680905Y1202362D03*
Y1198621D03*
X1677165D03*
X1686515Y1193011D03*
X1682775D03*
X1692126Y1217322D03*
X1688385Y1221062D03*
X1684645D03*
X1692126Y1209842D03*
X1688385Y1213582D03*
X1684645D03*
X1680905Y1221062D03*
Y1217322D03*
X1677165Y1221062D03*
Y1213582D03*
X1680905D03*
Y1209842D03*
X1688385Y1206102D03*
X1684645D03*
X1680905D03*
X1677165D03*
X1692126Y1224803D03*
X1688385D03*
Y1228543D03*
X1684645Y1236023D03*
Y1232283D03*
X1692126D03*
Y1236023D03*
X1680905Y1224803D03*
Y1228543D03*
X1677165Y1232283D03*
Y1236023D03*
X1682775Y1222932D03*
X1684645Y1250984D03*
Y1254724D03*
X1692126Y1250984D03*
X1688385Y1247243D03*
Y1243503D03*
X1692126D03*
X1684645Y1239763D03*
X1688385D03*
X1692126Y1254724D03*
X1677165Y1250984D03*
Y1254724D03*
X1680905Y1247243D03*
Y1243503D03*
X1677165Y1239763D03*
X1680905D03*
X1688385Y1258465D03*
X1680905D03*
X1678238Y1348187D03*
X1690478D03*
X1682598D03*
X1678238Y1360099D03*
X1690478D03*
X1682598D03*
X1678238Y1372385D03*
Y1384297D03*
X1690478D03*
Y1372385D03*
X1682598Y1384297D03*
Y1372385D03*
X1678238Y1396583D03*
X1690478D03*
X1682598D03*
X1678238Y1408495D03*
X1690478D03*
X1682598D03*
X1695866Y1086417D03*
Y1078936D03*
X1699607Y1090158D03*
Y1082677D03*
X1695866Y1093897D03*
Y1097637D03*
Y1105117D03*
X1699607Y1101378D03*
X1695866Y1112598D03*
Y1120078D03*
X1699607Y1123819D03*
Y1116339D03*
Y1108859D03*
X1700236Y1136909D03*
X1697736Y1140649D03*
X1693996D03*
X1695866Y1127558D03*
Y1135039D03*
X1699607Y1131300D03*
X1693996Y1136909D03*
X1697736D03*
Y1148129D03*
X1693996D03*
X1697736Y1155610D03*
X1693996D03*
Y1151870D03*
X1697736D03*
X1693996Y1144389D03*
X1697736D03*
X1693996Y1170570D03*
Y1166830D03*
X1697736D03*
Y1170570D03*
Y1159350D03*
X1693996D03*
X1697736Y1178051D03*
X1693996D03*
X1697736Y1185531D03*
X1693996D03*
X1697736Y1174310D03*
X1693996Y1189271D03*
X1697736D03*
Y1181791D03*
X1693996D03*
Y1174310D03*
Y1193011D03*
X1697676D03*
X1695866Y1202362D03*
X1699607Y1198621D03*
X1695866Y1217322D03*
Y1209842D03*
X1699607Y1221062D03*
Y1213582D03*
Y1206102D03*
X1695866Y1232283D03*
Y1236023D03*
Y1224803D03*
X1699607Y1228543D03*
X1695866Y1250984D03*
Y1243503D03*
X1699607Y1247243D03*
Y1239762D03*
X1694838Y1348187D03*
X1702718D03*
X1707078D03*
X1702718Y1360099D03*
X1707078D03*
X1694838D03*
Y1384297D03*
Y1372385D03*
X1702718D03*
Y1384297D03*
X1707078D03*
Y1372385D03*
X1694838Y1396583D03*
X1702718D03*
X1707078D03*
X1694838Y1408495D03*
X1702718D03*
X1707078D03*
X1714958Y1348187D03*
X1719318D03*
X1714958Y1360099D03*
X1719318D03*
X1714958Y1384297D03*
Y1372385D03*
X1719318D03*
Y1384297D03*
X1714958Y1396583D03*
X1719318D03*
X1714958Y1408495D03*
X1719318D03*
X1727198Y1348187D03*
X1739438D03*
X1731558D03*
X1727198Y1360099D03*
X1739438D03*
X1731558D03*
X1739438Y1372385D03*
X1731558Y1384297D03*
Y1372385D03*
X1727198D03*
Y1384297D03*
X1739438D03*
X1727198Y1396583D03*
X1739438D03*
X1731558D03*
X1727198Y1408495D03*
X1739438D03*
X1731558D03*
X1796283Y441086D03*
Y433999D03*
Y437543D03*
X1793483Y441086D03*
Y433999D03*
Y437543D03*
X1796283Y444629D03*
X1793483D03*
G54D60*
X251694Y1436156D03*
X237390Y1437236D03*
X392745Y1515756D03*
G54D118*
G01X179173Y1504685D02*
Y1506175D01*
X179703Y1506705D01*
X180867D01*
X182458Y1505114D01*
Y1443855D01*
X180096Y1441493D01*
X179332D01*
X178207Y1440368D01*
Y1439604D01*
X177083Y1438480D01*
X176320D01*
X175194Y1437355D01*
Y1436591D01*
X156832Y1418229D01*
Y1344960D01*
X145092Y1333220D01*
X90902Y1295279D01*
X74820Y1279197D01*
Y1210567D01*
X92896Y1192491D01*
Y1179901D01*
X84981Y1171986D01*
Y1097980D01*
X74220Y1087219D01*
Y1058679D01*
X63220Y1032122D01*
Y982779D01*
X192499Y853500D01*
X245544D01*
X345174Y753870D01*
X373131D01*
X382001Y745000D01*
X425001D01*
X443103Y726898D01*
X488779D01*
X493801Y731920D01*
X526376D01*
X529850Y735394D01*
Y740358D01*
X529800Y740408D01*
X530985Y741593D01*
G01X179173Y1509804D02*
Y1508315D01*
X179703Y1507785D01*
X181315D01*
X183538Y1505562D01*
Y1443407D01*
X157912Y1417781D01*
Y1344512D01*
X145789Y1332389D01*
X107155Y1305339D01*
X107154Y1305340D01*
X107022Y1304588D01*
X105718Y1303675D01*
X104966Y1303807D01*
X103664Y1302896D01*
X103532Y1302144D01*
X102228Y1301231D01*
X101476Y1301363D01*
X100174Y1300452D01*
X100041Y1299700D01*
X98738Y1298787D01*
X97986Y1298920D01*
X91599Y1294448D01*
X75900Y1278749D01*
Y1211015D01*
X93976Y1192939D01*
Y1179453D01*
X86061Y1171538D01*
Y1097532D01*
X75300Y1086771D01*
Y1058464D01*
X64300Y1031907D01*
Y983227D01*
X192947Y854580D01*
X230205D01*
X230745Y855120D01*
X232335D01*
X232875Y854580D01*
X234465D01*
X235005Y855120D01*
X236595D01*
X237135Y854580D01*
X245992D01*
X345622Y754950D01*
X368219D01*
X368759Y755490D01*
X370349D01*
X370889Y754950D01*
X373579D01*
X382449Y746080D01*
X425449D01*
X443551Y727978D01*
X488331D01*
X493353Y733000D01*
X525928D01*
X528770Y735842D01*
Y740408D01*
X527585Y741593D01*
G01X187835Y1509016D02*
Y1510505D01*
X188365Y1511035D01*
X189937D01*
X192383Y1508589D01*
Y1447211D01*
X191259Y1446087D01*
X190496D01*
X189370Y1444962D01*
Y1444198D01*
X169000Y1423828D01*
Y1345440D01*
X162845Y1339286D01*
X97244Y1293348D01*
X79020Y1275123D01*
Y1212049D01*
X96606Y1194463D01*
Y1178106D01*
X88712Y1170212D01*
Y1095612D01*
X78520Y1085420D01*
Y1057887D01*
X67420Y1031088D01*
Y983881D01*
X193501Y857800D01*
X251800D01*
X351400Y758200D01*
X375373D01*
X382923Y750650D01*
X426451D01*
X446493Y730608D01*
X487197D01*
X492283Y735694D01*
X518814D01*
X519946Y736826D01*
Y739886D01*
X521131Y741071D01*
G01X187835Y1514134D02*
Y1512645D01*
X188365Y1512115D01*
X190385D01*
X193463Y1509037D01*
Y1446763D01*
X170080Y1423380D01*
Y1344992D01*
X163543Y1338455D01*
X109449Y1300575D01*
X109316Y1299823D01*
X108013Y1298910D01*
X107261Y1299043D01*
X105959Y1298131D01*
X105826Y1297379D01*
X104523Y1296466D01*
X103771Y1296599D01*
X102469Y1295687D01*
X102337Y1294935D01*
X101033Y1294022D01*
X100281Y1294155D01*
X97942Y1292517D01*
X80100Y1274675D01*
Y1212497D01*
X97686Y1194911D01*
Y1177658D01*
X89792Y1169764D01*
Y1095164D01*
X79600Y1084972D01*
Y1057672D01*
X68500Y1030873D01*
Y984329D01*
X193949Y858880D01*
X240305D01*
X240845Y859420D01*
X242435D01*
X242975Y858880D01*
X244565D01*
X245105Y859420D01*
X246695D01*
X247235Y858880D01*
X252248D01*
X351848Y759280D01*
X362265D01*
X362805Y759820D01*
X364395D01*
X364935Y759280D01*
X375821D01*
X383371Y751730D01*
X426899D01*
X446941Y731688D01*
X486749D01*
X491835Y736774D01*
X518366D01*
X518866Y737274D01*
Y739936D01*
X517731Y741071D01*
G01X179173Y1576339D02*
Y1577903D01*
X178693Y1578383D01*
X175995D01*
X174499Y1576887D01*
Y1542200D01*
X181005Y1535694D01*
X181769D01*
X182894Y1534569D01*
Y1533805D01*
X184018Y1532681D01*
X184781D01*
X185907Y1531556D01*
Y1530792D01*
X187031Y1529668D01*
X187794D01*
X188920Y1528543D01*
Y1527779D01*
X190044Y1526655D01*
X190807D01*
X191933Y1525530D01*
Y1524766D01*
X197200Y1519499D01*
Y1439500D01*
X182380Y1424680D01*
Y1346434D01*
X180215Y1342275D01*
X99843Y1285996D01*
X99840Y1285994D01*
X84600Y1270753D01*
Y1213929D01*
X101396Y1197133D01*
Y1175269D01*
X93708Y1167581D01*
Y1093580D01*
X83413Y1083285D01*
Y1056432D01*
X72400Y1029844D01*
Y985864D01*
X194584Y863680D01*
X254048D01*
X354148Y763580D01*
X379319D01*
X384419Y758480D01*
X426448D01*
X447622Y737306D01*
X487111D01*
X494945Y745138D01*
X509261D01*
X510564Y743835D01*
Y742195D01*
X511724Y741035D01*
G01X179173Y1581457D02*
Y1579893D01*
X178743Y1579463D01*
X175547D01*
X173419Y1577335D01*
Y1541752D01*
X196120Y1519051D01*
Y1439948D01*
X181300Y1425128D01*
Y1346699D01*
X179378Y1343009D01*
X99145Y1286827D01*
X83520Y1271201D01*
Y1213481D01*
X100316Y1196685D01*
Y1175717D01*
X92628Y1168029D01*
Y1094028D01*
X82333Y1083733D01*
Y1056647D01*
X71320Y1030059D01*
Y985416D01*
X194136Y862600D01*
X253600D01*
X353700Y762500D01*
X378871D01*
X383971Y757400D01*
X426000D01*
X447174Y736226D01*
X487559D01*
X495393Y744058D01*
X508813D01*
X509484Y743387D01*
Y742195D01*
X508324Y741035D01*
G01X197247Y1544069D02*
X183609Y1557707D01*
Y1562004D01*
X183659Y1562054D01*
Y1562065D01*
X182593Y1563131D01*
X181319D01*
X179173Y1560985D01*
G01Y1566103D02*
X181115Y1564161D01*
X183020D01*
X184689Y1562492D01*
Y1558154D01*
X198010Y1544833D01*
Y1544832D01*
X208035Y1534808D01*
Y1516515D01*
G01X197247Y1544069D02*
Y1544067D01*
X206955Y1534360D01*
Y1434045D01*
X212763Y1428237D01*
X216721D01*
X217906Y1427052D01*
G01X208035Y1516515D02*
Y1434493D01*
X213211Y1429317D01*
X216771D01*
X217906Y1430452D01*
G01X251694Y1436156D02*
X228517D01*
X221972Y1442701D01*
X219221D01*
X218604Y1442084D01*
Y1441427D01*
X218554Y1441377D01*
Y1441000D01*
X219525Y1440028D01*
G01X237390Y1437236D02*
X228965D01*
X222420Y1443781D01*
X218773D01*
X217524Y1442532D01*
Y1441427D01*
X216125Y1440028D01*
G01X237390Y1437236D02*
X373309D01*
X404710Y1468637D01*
X419410D01*
X426336Y1475563D01*
Y1501035D01*
X414888Y1512483D01*
Y1515751D01*
X413753Y1516886D01*
G01X251694Y1436156D02*
X373757D01*
X405158Y1467557D01*
X419858D01*
X427416Y1475115D01*
Y1501483D01*
X415968Y1512931D01*
Y1515701D01*
X417153Y1516886D01*
G01X295011Y460218D02*
X296196Y461403D01*
X298192D01*
X300984Y464195D01*
Y476860D01*
X346544Y522420D01*
X484319D01*
X487077Y525178D01*
Y573334D01*
X480319Y580092D01*
Y632939D01*
X498221Y650841D01*
X533528D01*
X536500Y653813D01*
Y660392D01*
X537664Y661556D01*
G01X295011Y463618D02*
X296146Y462483D01*
X297744D01*
X299904Y464643D01*
Y477308D01*
X346096Y523500D01*
X483871D01*
X485997Y525626D01*
Y572886D01*
X479239Y579644D01*
Y633387D01*
X497773Y651921D01*
X516040D01*
X516580Y652461D01*
X518170D01*
X518710Y651921D01*
X520300D01*
X520840Y652461D01*
X522430D01*
X522970Y651921D01*
X524560D01*
X525100Y652461D01*
X526690D01*
X527230Y651921D01*
X528820D01*
X529360Y652461D01*
X530950D01*
X531490Y651921D01*
X533080D01*
X535420Y654261D01*
Y660400D01*
X534264Y661556D01*
G01X343112Y1761624D02*
Y1757694D01*
X343642Y1757164D01*
X353312D01*
X354372Y1758224D01*
Y1761964D01*
X356064Y1763656D01*
X361380D01*
X363072Y1761964D01*
Y1751732D01*
X364132Y1750672D01*
X368552D01*
X369612Y1751732D01*
Y1761964D01*
X371304Y1763656D01*
X376620D01*
X378312Y1761964D01*
Y1751732D01*
X379372Y1750672D01*
X383792D01*
X384852Y1751732D01*
Y1761964D01*
X386544Y1763656D01*
X391860D01*
X393552Y1761964D01*
Y1751732D01*
X394612Y1750672D01*
X399032D01*
X400092Y1751732D01*
Y1761964D01*
X401784Y1763656D01*
X407100D01*
X408792Y1761964D01*
Y1751732D01*
X409852Y1750672D01*
X414272D01*
X415332Y1751732D01*
Y1761964D01*
X417024Y1763656D01*
X422340D01*
X424032Y1761964D01*
Y1751732D01*
X425092Y1750672D01*
X429512D01*
X430572Y1751732D01*
Y1761964D01*
X432264Y1763656D01*
X437580D01*
X439272Y1761964D01*
Y1751732D01*
X440332Y1750672D01*
X444752D01*
X445812Y1751732D01*
Y1761964D01*
X447504Y1763656D01*
X452820D01*
X454512Y1761964D01*
Y1751732D01*
X455572Y1750672D01*
X459992D01*
X461052Y1751732D01*
Y1761964D01*
X462744Y1763656D01*
X468060D01*
X469752Y1761964D01*
Y1751732D01*
X470812Y1750672D01*
X475232D01*
X476292Y1751732D01*
Y1761964D01*
X477984Y1763656D01*
X483300D01*
X484992Y1761964D01*
Y1751732D01*
X486052Y1750672D01*
X490472D01*
X491532Y1751732D01*
Y1761964D01*
X493224Y1763656D01*
X498540D01*
X500232Y1761964D01*
Y1751732D01*
X501292Y1750672D01*
X505712D01*
X506772Y1751732D01*
Y1761964D01*
X508464Y1763656D01*
X513780D01*
X515472Y1761964D01*
Y1751732D01*
X516532Y1750672D01*
X520952D01*
X522012Y1751732D01*
Y1761964D01*
X523704Y1763656D01*
X529020D01*
X530712Y1761964D01*
Y1751732D01*
X531772Y1750672D01*
X536192D01*
X537252Y1751732D01*
Y1761964D01*
X538944Y1763656D01*
X544260D01*
X545952Y1761964D01*
Y1751732D01*
X547012Y1750672D01*
X551432D01*
X552492Y1751732D01*
Y1761964D01*
X554184Y1763656D01*
X559500D01*
X561192Y1761964D01*
Y1751732D01*
X562252Y1750672D01*
X566672D01*
X567732Y1751732D01*
Y1761964D01*
X569424Y1763656D01*
X574740D01*
X576432Y1761964D01*
Y1751732D01*
X577492Y1750672D01*
X581912D01*
X582972Y1751732D01*
Y1755472D01*
X584664Y1757164D01*
X594782D01*
X595312Y1757694D01*
Y1761624D01*
G01X343112Y1751624D02*
Y1755554D01*
X343642Y1756084D01*
X353760D01*
X355452Y1757776D01*
Y1761516D01*
X356512Y1762576D01*
X360932D01*
X361992Y1761516D01*
Y1751284D01*
X363684Y1749592D01*
X369000D01*
X370692Y1751284D01*
Y1761516D01*
X371752Y1762576D01*
X376172D01*
X377232Y1761516D01*
Y1751284D01*
X378924Y1749592D01*
X384240D01*
X385932Y1751284D01*
Y1761516D01*
X386992Y1762576D01*
X391412D01*
X392472Y1761516D01*
Y1751284D01*
X394164Y1749592D01*
X399480D01*
X401172Y1751284D01*
Y1761516D01*
X402232Y1762576D01*
X406652D01*
X407712Y1761516D01*
Y1751284D01*
X409404Y1749592D01*
X414720D01*
X416412Y1751284D01*
Y1761516D01*
X417472Y1762576D01*
X421892D01*
X422952Y1761516D01*
Y1751284D01*
X424644Y1749592D01*
X429960D01*
X431652Y1751284D01*
Y1761516D01*
X432712Y1762576D01*
X437132D01*
X438192Y1761516D01*
Y1751284D01*
X439884Y1749592D01*
X445200D01*
X446892Y1751284D01*
Y1761516D01*
X447952Y1762576D01*
X452372D01*
X453432Y1761516D01*
Y1751284D01*
X455124Y1749592D01*
X460440D01*
X462132Y1751284D01*
Y1761516D01*
X463192Y1762576D01*
X467612D01*
X468672Y1761516D01*
Y1751284D01*
X470364Y1749592D01*
X475680D01*
X477372Y1751284D01*
Y1761516D01*
X478432Y1762576D01*
X482852D01*
X483912Y1761516D01*
Y1751284D01*
X485604Y1749592D01*
X490920D01*
X492612Y1751284D01*
Y1761516D01*
X493672Y1762576D01*
X498092D01*
X499152Y1761516D01*
Y1751284D01*
X500844Y1749592D01*
X506160D01*
X507852Y1751284D01*
Y1761516D01*
X508912Y1762576D01*
X513332D01*
X514392Y1761516D01*
Y1751284D01*
X516084Y1749592D01*
X521400D01*
X523092Y1751284D01*
Y1761516D01*
X524152Y1762576D01*
X528572D01*
X529632Y1761516D01*
Y1751284D01*
X531324Y1749592D01*
X536640D01*
X538332Y1751284D01*
Y1761516D01*
X539392Y1762576D01*
X543812D01*
X544872Y1761516D01*
Y1751284D01*
X546564Y1749592D01*
X551880D01*
X553572Y1751284D01*
Y1761516D01*
X554632Y1762576D01*
X559052D01*
X560112Y1761516D01*
Y1751284D01*
X561804Y1749592D01*
X567120D01*
X568812Y1751284D01*
Y1761516D01*
X569872Y1762576D01*
X574292D01*
X575352Y1761516D01*
Y1751284D01*
X577044Y1749592D01*
X582360D01*
X584052Y1751284D01*
Y1755024D01*
X585112Y1756084D01*
X594782D01*
X595312Y1755554D01*
Y1751624D01*
G01X372028Y1534029D02*
X362536Y1548231D01*
X356784Y1562117D01*
X354792Y1564109D01*
X352831D01*
X352401Y1564539D01*
Y1566103D01*
G01Y1560985D02*
Y1562549D01*
X352881Y1563029D01*
X354344D01*
X355868Y1561505D01*
X361579Y1547719D01*
X380323Y1519672D01*
X389778Y1515756D01*
X392745D01*
G01X372028Y1534029D02*
X381040Y1520545D01*
X389993Y1516836D01*
X396055D01*
X397266Y1518047D01*
G01Y1514647D02*
X396157Y1515756D01*
X392745D01*
G01X408159Y1349072D02*
X406999Y1350232D01*
Y1353516D01*
X408459Y1354976D01*
G01X404459D02*
X405919Y1353516D01*
Y1350232D01*
X404759Y1349072D01*
G01X404459Y1358126D02*
X405919Y1359586D01*
Y1362335D01*
X409659Y1371365D01*
Y1374539D01*
X409215Y1374983D01*
Y1375546D01*
G01X411184D02*
Y1374984D01*
X410739Y1374539D01*
Y1371150D01*
X406999Y1362120D01*
Y1359586D01*
X408459Y1358126D01*
G01X413934Y1477101D02*
X415071Y1478238D01*
Y1479501D01*
X409839Y1484733D01*
Y1496328D01*
X411844Y1498333D01*
X414017D01*
X415202Y1499518D01*
G01X417334Y1477101D02*
X416151Y1478284D01*
Y1479949D01*
X410919Y1485181D01*
Y1495880D01*
X412342Y1497303D01*
X414017D01*
X415202Y1496118D01*
G01X445331Y1305545D02*
X443886Y1304100D01*
X442189D01*
X433260Y1307800D01*
X429243D01*
X428773Y1308270D01*
X427911D01*
G01X445331Y1301545D02*
X443856Y1303020D01*
X441974D01*
X433045Y1306720D01*
X429243D01*
X429193Y1306770D01*
X429121D01*
X428652Y1306301D01*
X427911D01*
G01X454385Y1301845D02*
X453210Y1303020D01*
X449956D01*
X448481Y1301545D01*
G01X454385Y1305245D02*
X453240Y1304100D01*
X449926D01*
X448481Y1305545D01*
G01X486837Y701306D02*
X485702Y702441D01*
X482468D01*
X481016Y703893D01*
Y711620D01*
X497396Y728000D01*
X557345D01*
X560088Y725257D01*
X712742D01*
X809637Y628362D01*
Y602585D01*
X945280Y466942D01*
Y455354D01*
X966072Y434562D01*
X1016118D01*
X1036260Y454704D01*
X1057294D01*
X1074748Y437250D01*
Y370214D01*
X1089540Y355422D01*
Y335134D01*
X1083826Y329420D01*
X1081515D01*
X1080351Y328256D01*
G01X486837Y704706D02*
X485652Y703521D01*
X482916D01*
X482096Y704341D01*
Y711172D01*
X483213Y712289D01*
X483976D01*
X485095Y713407D01*
Y714171D01*
X486212Y715288D01*
X486975D01*
X488094Y716406D01*
Y717170D01*
X489211Y718287D01*
X489974D01*
X491093Y719405D01*
Y720169D01*
X492210Y721286D01*
X492973D01*
X494092Y722404D01*
Y723168D01*
X497844Y726920D01*
X499424D01*
X499964Y726380D01*
X501544D01*
X502084Y726920D01*
X503664D01*
X504204Y726380D01*
X505784D01*
X506324Y726920D01*
X556897D01*
X559640Y724177D01*
X712294D01*
X808557Y627914D01*
Y602137D01*
X944200Y466494D01*
Y454906D01*
X965624Y433482D01*
X1016566D01*
X1030710Y447626D01*
X1031474D01*
X1032592Y448745D01*
Y449508D01*
X1033709Y450625D01*
X1034473D01*
X1035591Y451744D01*
Y452507D01*
X1036708Y453624D01*
X1039886D01*
X1040426Y453084D01*
X1042006D01*
X1042546Y453624D01*
X1044126D01*
X1044666Y453084D01*
X1046246D01*
X1046786Y453624D01*
X1048366D01*
X1048906Y453084D01*
X1050486D01*
X1051026Y453624D01*
X1052606D01*
X1053146Y453084D01*
X1054726D01*
X1055266Y453624D01*
X1056846D01*
X1059744Y450726D01*
Y449962D01*
X1060862Y448844D01*
X1061626D01*
X1062896Y447574D01*
Y446810D01*
X1064015Y445692D01*
X1064778D01*
X1065895Y444575D01*
Y443811D01*
X1067014Y442693D01*
X1067777D01*
X1068894Y441576D01*
Y440812D01*
X1070012Y439694D01*
X1070776D01*
X1073668Y436802D01*
Y369766D01*
X1088460Y354974D01*
Y335582D01*
X1083378Y330500D01*
X1081507D01*
X1080351Y331656D01*
G01X752097Y460218D02*
X753257Y461378D01*
X755179D01*
X757354Y463553D01*
Y469962D01*
X750516Y476800D01*
X748129D01*
X732279Y492650D01*
X729379D01*
X707237Y514792D01*
Y600330D01*
X707187Y600380D01*
Y600757D01*
X706886Y601058D01*
Y601129D01*
X691758Y616257D01*
Y646829D01*
X679299Y659288D01*
X628503D01*
X621453Y666338D01*
Y666974D01*
X625272Y670793D01*
Y672367D01*
X622848Y674791D01*
X621274D01*
X617455Y670972D01*
X616819D01*
X615058Y672733D01*
Y673369D01*
X618877Y677188D01*
Y678762D01*
X616453Y681186D01*
X614879D01*
X611060Y677367D01*
X610424D01*
X608663Y679128D01*
Y679764D01*
X612482Y683583D01*
Y685157D01*
X610058Y687581D01*
X608484D01*
X604665Y683762D01*
X604029D01*
X602268Y685523D01*
Y686159D01*
X606037Y689928D01*
Y691663D01*
X602609Y695091D01*
X562688D01*
X561570Y696209D01*
G01X752097Y463618D02*
X753257Y462458D01*
X754731D01*
X756274Y464001D01*
Y469514D01*
X750068Y475720D01*
X747681D01*
X731831Y491570D01*
X728931D01*
X706157Y514344D01*
Y600330D01*
X690678Y615809D01*
Y646381D01*
X678851Y658208D01*
X628055D01*
X620373Y665890D01*
Y667422D01*
X624192Y671241D01*
Y671919D01*
X622400Y673711D01*
X621722D01*
X617903Y669892D01*
X616371D01*
X613978Y672285D01*
Y673817D01*
X617797Y677636D01*
Y678314D01*
X616005Y680106D01*
X615327D01*
X611508Y676287D01*
X609976D01*
X607583Y678680D01*
Y680212D01*
X611402Y684031D01*
Y684709D01*
X609610Y686501D01*
X608932D01*
X605113Y682682D01*
X603581D01*
X601188Y685075D01*
Y686607D01*
X604957Y690376D01*
Y691215D01*
X602161Y694011D01*
X594970D01*
X594430Y693471D01*
X592850D01*
X592310Y694011D01*
X590730D01*
X590190Y693471D01*
X588610D01*
X588070Y694011D01*
X586490D01*
X585950Y693471D01*
X584370D01*
X583830Y694011D01*
X582250D01*
X581710Y693471D01*
X580130D01*
X579590Y694011D01*
X578010D01*
X577470Y693471D01*
X575890D01*
X575350Y694011D01*
X573770D01*
X573230Y693471D01*
X571650D01*
X571110Y694011D01*
X569530D01*
X568990Y693471D01*
X567410D01*
X566870Y694011D01*
X562772D01*
X561570Y692809D01*
G01X949942Y-32782D02*
X949187D01*
X948743Y-32338D01*
X932403D01*
X931176Y-31308D01*
X928871Y-18236D01*
X927644Y-17377D01*
X923875Y-18042D01*
X923017Y-19267D01*
X927912Y-47031D01*
X926540Y-48992D01*
X921894Y-49811D01*
X919939Y-48440D01*
X914607Y-18224D01*
X913379Y-17365D01*
X909611Y-18031D01*
X908753Y-19254D01*
X913643Y-46986D01*
X912271Y-48946D01*
X907625Y-49765D01*
X905662Y-48393D01*
X900335Y-18166D01*
X899110Y-17307D01*
X895342Y-17973D01*
X894482Y-19201D01*
X899382Y-46994D01*
X898010Y-48956D01*
X893364Y-49775D01*
X891404Y-48401D01*
X886080Y-18210D01*
X884855Y-17351D01*
X881087Y-18016D01*
X880227Y-19244D01*
X885112Y-46956D01*
X883740Y-48919D01*
X879094Y-49738D01*
X877138Y-48367D01*
X871904Y-18701D01*
X870677Y-17842D01*
X866909Y-18507D01*
X866051Y-19733D01*
X870770Y-46500D01*
X869398Y-48461D01*
X864752Y-49280D01*
X862795Y-47909D01*
X857648Y-18734D01*
X856421Y-17875D01*
X852653Y-18540D01*
X851795Y-19766D01*
X856515Y-46539D01*
X855143Y-48500D01*
X850497Y-49319D01*
X848538Y-47948D01*
X843387Y-18744D01*
X842160Y-17885D01*
X838392Y-18550D01*
X837534Y-19776D01*
X842244Y-46493D01*
X840872Y-48454D01*
X836226Y-49273D01*
X834269Y-47902D01*
X829107Y-18641D01*
X827880Y-17782D01*
X824112Y-18447D01*
X823254Y-19673D01*
X828007Y-46634D01*
X826635Y-48595D01*
X821989Y-49414D01*
X820030Y-48043D01*
X814837Y-18600D01*
X813610Y-17741D01*
X809842Y-18406D01*
X808984Y-19632D01*
X813722Y-46508D01*
X812350Y-48470D01*
X807704Y-49289D01*
X805747Y-47918D01*
X800583Y-18645D01*
X799356Y-17786D01*
X795588Y-18451D01*
X794730Y-19677D01*
X799471Y-46570D01*
X798099Y-48531D01*
X793453Y-49350D01*
X791495Y-47980D01*
X786308Y-18570D01*
X785082Y-17711D01*
X781313Y-18376D01*
X780455Y-19601D01*
X785217Y-46615D01*
X783845Y-48576D01*
X779199Y-49395D01*
X777239Y-48024D01*
X772053Y-18614D01*
X770826Y-17755D01*
X767058Y-18420D01*
X766199Y-19646D01*
X770956Y-46616D01*
X769584Y-48575D01*
X764938Y-49394D01*
X762977Y-48023D01*
X757799Y-18660D01*
X756572Y-17801D01*
X752804Y-18466D01*
X751946Y-19692D01*
X756681Y-46551D01*
X755309Y-48512D01*
X750663Y-49331D01*
X748707Y-47962D01*
X746087Y-33114D01*
X745339Y-32366D01*
X726205D01*
X725761Y-32810D01*
X725006D01*
G01X949942Y-30814D02*
X949187D01*
X948743Y-31258D01*
X932797D01*
X932172Y-30733D01*
X929857Y-17608D01*
X927897Y-16235D01*
X923247Y-17056D01*
X921875Y-19014D01*
X926770Y-46778D01*
X925911Y-48005D01*
X922148Y-48669D01*
X920925Y-47812D01*
X915593Y-17596D01*
X913632Y-16223D01*
X908983Y-17045D01*
X907611Y-19000D01*
X912501Y-46733D01*
X911642Y-47959D01*
X907878Y-48623D01*
X906648Y-47764D01*
X901321Y-17538D01*
X899363Y-16165D01*
X894714Y-16987D01*
X893340Y-18948D01*
X898240Y-46741D01*
X897381Y-47969D01*
X893618Y-48633D01*
X892390Y-47773D01*
X887066Y-17582D01*
X885109Y-16209D01*
X880459Y-17030D01*
X879085Y-18991D01*
X883970Y-46703D01*
X883111Y-47933D01*
X879348Y-48596D01*
X878124Y-47739D01*
X872890Y-18073D01*
X870930Y-16700D01*
X870490Y-16777D01*
Y-16778D01*
X866280Y-17520D01*
X864909Y-19480D01*
X869628Y-46247D01*
X868769Y-47474D01*
X865005Y-48138D01*
X863781Y-47281D01*
X858634Y-18106D01*
X856674Y-16733D01*
X856234Y-16810D01*
Y-16811D01*
X852024Y-17553D01*
X850653Y-19513D01*
X855373Y-46286D01*
X854514Y-47513D01*
X850750Y-48177D01*
X849525Y-47319D01*
X844373Y-18116D01*
X842413Y-16743D01*
X841973Y-16820D01*
Y-16821D01*
X837763Y-17563D01*
X836392Y-19523D01*
X841102Y-46240D01*
X840243Y-47467D01*
X836479Y-48131D01*
X835255Y-47274D01*
X830093Y-18013D01*
X828133Y-16640D01*
X827693Y-16717D01*
Y-16718D01*
X823483Y-17460D01*
X822112Y-19420D01*
X826865Y-46381D01*
X826006Y-47608D01*
X822242Y-48272D01*
X821017Y-47414D01*
X815823Y-17972D01*
X813863Y-16599D01*
X813423Y-16676D01*
Y-16677D01*
X809213Y-17419D01*
X807842Y-19379D01*
X812580Y-46255D01*
X811721Y-47483D01*
X807957Y-48147D01*
X806733Y-47290D01*
X801569Y-18017D01*
X799609Y-16644D01*
X799169Y-16721D01*
Y-16722D01*
X794959Y-17464D01*
X793588Y-19424D01*
X798329Y-46317D01*
X797470Y-47544D01*
X793706Y-48208D01*
X792482Y-47351D01*
X787294Y-17942D01*
X785335Y-16569D01*
X780685Y-17390D01*
X779313Y-19348D01*
X784075Y-46362D01*
X783216Y-47589D01*
X779452Y-48253D01*
X778226Y-47395D01*
X773039Y-17986D01*
X771079Y-16613D01*
X766430Y-17434D01*
X765057Y-19393D01*
X769814Y-46363D01*
X768956Y-47589D01*
X765191Y-48252D01*
X763963Y-47394D01*
X758785Y-18032D01*
X756826Y-16659D01*
X752175Y-17479D01*
X750804Y-19439D01*
X755539Y-46298D01*
X754680Y-47525D01*
X750916Y-48189D01*
X749694Y-47333D01*
X747092Y-32591D01*
X745787Y-31286D01*
X726205D01*
X725761Y-30842D01*
X725006D01*
G01X845006Y-71990D02*
X845761D01*
X846205Y-71546D01*
X859285D01*
X863806Y-70750D01*
X864725Y-69439D01*
X862957Y-59402D01*
X863815Y-58172D01*
X867582Y-57508D01*
X868809Y-58367D01*
X873803Y-86685D01*
X875763Y-88056D01*
X880408Y-87235D01*
X881781Y-85276D01*
X877218Y-59390D01*
X878076Y-58162D01*
X881844Y-57498D01*
X883070Y-58357D01*
X888060Y-86647D01*
X890018Y-88017D01*
X894663Y-87196D01*
X896036Y-85237D01*
X891474Y-59357D01*
X892332Y-58129D01*
X896100Y-57465D01*
X897326Y-58324D01*
X902404Y-87104D01*
X904360Y-88475D01*
X909006Y-87656D01*
X910378Y-85694D01*
X905735Y-59352D01*
X906595Y-58124D01*
X910363Y-57459D01*
X911588Y-58318D01*
X916789Y-87817D01*
X918750Y-89191D01*
X923395Y-88372D01*
X924767Y-86410D01*
X919990Y-59309D01*
X920850Y-58081D01*
X924618Y-57415D01*
X925843Y-58274D01*
X930826Y-86548D01*
X932788Y-87920D01*
X937433Y-87100D01*
X938806Y-85141D01*
X934261Y-59362D01*
X935119Y-58139D01*
X938887Y-57473D01*
X940114Y-58332D01*
X945103Y-86595D01*
X947058Y-87966D01*
X951703Y-87147D01*
X953075Y-85186D01*
X948525Y-59375D01*
X949383Y-58150D01*
X953152Y-57485D01*
X954379Y-58344D01*
X956520Y-70488D01*
X957747Y-71518D01*
X973587D01*
X974031Y-71962D01*
X974786D01*
G01X845006Y-70022D02*
X845761D01*
X846205Y-70466D01*
X859190D01*
X863178Y-69763D01*
X863583Y-69185D01*
X861815Y-59150D01*
X863185Y-57185D01*
X867835Y-56366D01*
X869796Y-57738D01*
X874790Y-86056D01*
X876016Y-86914D01*
X879780Y-86249D01*
X880639Y-85022D01*
X876076Y-59137D01*
X877447Y-57176D01*
X877888Y-57098D01*
X877889D01*
X882097Y-56356D01*
X884056Y-57729D01*
X889047Y-86018D01*
X890271Y-86875D01*
X894035Y-86210D01*
X894894Y-84983D01*
X890332Y-59104D01*
X891703Y-57143D01*
X892144Y-57065D01*
X892145D01*
X896353Y-56323D01*
X898312Y-57696D01*
X903390Y-86476D01*
X904614Y-87333D01*
X908377Y-86669D01*
X909236Y-85441D01*
X904593Y-59099D01*
X905967Y-57138D01*
X910617Y-56317D01*
X912574Y-57690D01*
X917775Y-87189D01*
X919003Y-88049D01*
X922766Y-87385D01*
X923625Y-86157D01*
X918848Y-59056D01*
X920222Y-57095D01*
X924871Y-56273D01*
X926829Y-57646D01*
X931813Y-85919D01*
X933041Y-86778D01*
X936805Y-86114D01*
X937664Y-84887D01*
X933119Y-59108D01*
X934491Y-57153D01*
X939140Y-56331D01*
X941101Y-57703D01*
X946089Y-85967D01*
X947312Y-86824D01*
X951074Y-86160D01*
X951933Y-84933D01*
X947383Y-59122D01*
X948755Y-57164D01*
X953405Y-56343D01*
X955366Y-57715D01*
X957516Y-69913D01*
X958141Y-70438D01*
X973587D01*
X974031Y-69994D01*
X974786D01*
G01X909298Y302347D02*
X908146Y301195D01*
Y293945D01*
X902982Y288781D01*
Y237083D01*
X900419Y234520D01*
X894465D01*
X893284Y233339D01*
G01X905898Y302347D02*
X907066Y301177D01*
Y294393D01*
X901902Y289229D01*
Y285935D01*
X901362Y285395D01*
Y283805D01*
X901902Y283265D01*
Y281675D01*
X901362Y281135D01*
Y279545D01*
X901902Y279005D01*
Y277415D01*
X901362Y276875D01*
Y275285D01*
X901902Y274745D01*
Y237531D01*
X899971Y235600D01*
X894423D01*
X893284Y236739D01*
G01X899352Y308560D02*
X900537Y309745D01*
X906166D01*
X912482Y316061D01*
X924939D01*
X945489Y295511D01*
X950789D01*
X953872Y292428D01*
Y288105D01*
X980877Y261100D01*
X1029651D01*
X1059267Y273366D01*
X1069601Y283700D01*
X1075699D01*
X1087996Y295997D01*
X1091196D01*
X1108221Y313022D01*
X1134980D01*
X1139125Y317167D01*
X1148967D01*
X1154962Y323162D01*
X1177592D01*
X1181354Y319400D01*
X1213871D01*
X1225871Y307400D01*
X1234601D01*
X1241001Y313800D01*
X1295192D01*
X1306858Y302134D01*
X1346391D01*
X1358557Y314300D01*
X1460832D01*
X1472700Y326168D01*
Y384479D01*
X1498787Y410566D01*
Y501116D01*
X1506071Y508400D01*
X1601749D01*
X1605828Y512479D01*
Y634300D01*
X1627862Y656334D01*
Y663833D01*
X1763546Y799517D01*
Y802817D01*
G01X899352Y311960D02*
X900487Y310825D01*
X905718D01*
X912034Y317141D01*
X925387D01*
X945937Y296591D01*
X951237D01*
X954952Y292876D01*
Y288553D01*
X981325Y262180D01*
X1029436D01*
X1039250Y266245D01*
X1039542Y266951D01*
X1041012Y267559D01*
X1041718Y267267D01*
X1043186Y267875D01*
X1043479Y268581D01*
X1044949Y269190D01*
X1045654Y268898D01*
X1047123Y269506D01*
X1047415Y270212D01*
X1048885Y270821D01*
X1049590Y270528D01*
X1058655Y274282D01*
X1069153Y284780D01*
X1075251D01*
X1087548Y297077D01*
X1090748D01*
X1107773Y314102D01*
X1134532D01*
X1138677Y318247D01*
X1148519D01*
X1154514Y324242D01*
X1178040D01*
X1181802Y320480D01*
X1214319D01*
X1226319Y308480D01*
X1234153D01*
X1240553Y314880D01*
X1295640D01*
X1297316Y313204D01*
X1298079D01*
X1299204Y312079D01*
Y311316D01*
X1300328Y310192D01*
X1301091D01*
X1302217Y309067D01*
Y308303D01*
X1303341Y307179D01*
X1304104D01*
X1305230Y306054D01*
Y305290D01*
X1307306Y303214D01*
X1345943D01*
X1358109Y315380D01*
X1460384D01*
X1471620Y326616D01*
Y384927D01*
X1497707Y411014D01*
Y501564D01*
X1505623Y509480D01*
X1601301D01*
X1604748Y512927D01*
Y573205D01*
X1604208Y573745D01*
Y575335D01*
X1604748Y575875D01*
Y577465D01*
X1604208Y578005D01*
Y579595D01*
X1604748Y580135D01*
Y634748D01*
X1626782Y656782D01*
Y659526D01*
G01X1459752Y806881D02*
Y733252D01*
X1456253Y729753D01*
Y690675D01*
X1432512Y666934D01*
X1376334D01*
X1358342Y648942D01*
Y570395D01*
X1320647Y532700D01*
X1276938D01*
X1265908Y543730D01*
X1167873D01*
X1145900Y521757D01*
Y380356D01*
X1108578Y343034D01*
Y337390D01*
X1078288Y307100D01*
X1067772D01*
X1052452Y291780D01*
X1032548D01*
X1028948Y295380D01*
X1011720D01*
X1010322Y296778D01*
X975977D01*
X957800Y314955D01*
Y334800D01*
X950645Y341955D01*
X937427D01*
X935552Y340080D01*
X918442D01*
X917364Y339002D01*
Y337468D01*
X916229Y336333D01*
G01X919629D02*
X918444Y337518D01*
Y338554D01*
X918890Y339000D01*
X936000D01*
X937875Y340875D01*
X950197D01*
X956720Y334352D01*
Y314507D01*
X975529Y295698D01*
X1009874D01*
X1011272Y294300D01*
X1028500D01*
X1032100Y290700D01*
X1052900D01*
X1068220Y306020D01*
X1078736D01*
X1109658Y336942D01*
Y342586D01*
X1146980Y379908D01*
Y521309D01*
X1168321Y542650D01*
X1265460D01*
X1276490Y531620D01*
X1321095D01*
X1359422Y569947D01*
Y648494D01*
X1376782Y665854D01*
X1432960D01*
X1457333Y690227D01*
Y729305D01*
X1460832Y732804D01*
Y763285D01*
G01X1765664Y923724D02*
X1766820Y924880D01*
Y928127D01*
X1765437Y929510D01*
X1761142D01*
X1759380Y927748D01*
Y916535D01*
X1759920Y915995D01*
Y914405D01*
X1759380Y913865D01*
Y912275D01*
X1759920Y911735D01*
Y910145D01*
X1759380Y909605D01*
Y908015D01*
X1759920Y907475D01*
Y905885D01*
X1759380Y905345D01*
Y836124D01*
X1751300Y828044D01*
Y793344D01*
X1617556Y659600D01*
X1603786D01*
X1602206Y658020D01*
X1477004D01*
X1475415Y659609D01*
X1456936D01*
X1443740Y646413D01*
X1384544D01*
X1368080Y629949D01*
Y564580D01*
X1330000Y526500D01*
X1266100D01*
X1245950Y506350D01*
X1173577D01*
X1151180Y483953D01*
Y377980D01*
X1134258Y361058D01*
Y332800D01*
X1124878Y323420D01*
X1102019D01*
X1080419Y301820D01*
X1069847D01*
X1054077Y286050D01*
X1039677D01*
X1027577Y273950D01*
X977023D01*
X961520Y289453D01*
Y295452D01*
X943553Y313419D01*
X938135D01*
X937000Y312284D01*
G01Y315684D02*
X938185Y314499D01*
X944001D01*
X962600Y295900D01*
Y289901D01*
X977471Y275030D01*
X1027129D01*
X1039229Y287130D01*
X1053629D01*
X1069399Y302900D01*
X1079971D01*
X1101571Y324500D01*
X1124430D01*
X1133178Y333248D01*
Y361506D01*
X1150100Y378428D01*
Y484401D01*
X1173129Y507430D01*
X1245502D01*
X1265652Y527580D01*
X1329552D01*
X1367000Y565028D01*
Y630397D01*
X1384096Y647493D01*
X1443292D01*
X1456488Y660689D01*
X1475863D01*
X1477452Y659100D01*
X1601758D01*
X1603338Y660680D01*
X1617108D01*
X1750220Y793792D01*
Y828492D01*
X1758300Y836572D01*
Y928196D01*
X1760694Y930590D01*
X1765885D01*
X1767900Y928575D01*
Y924888D01*
X1769064Y923724D01*
G01X1008506Y-42810D02*
X1011187Y-43526D01*
G01X1008506Y-40842D02*
X1011187Y-40126D01*
G01X1078506Y-80022D02*
X1081187Y-79306D01*
G01X1078506Y-81990D02*
X1081187Y-82706D01*
G01X1228086Y-79994D02*
X1225405Y-79278D01*
G01X1228086Y-81962D02*
X1225405Y-82678D01*
G01X1233442Y-42912D02*
X1230761Y-43628D01*
G01X1233442Y-40944D02*
X1230761Y-40228D01*
G01X1295006Y-40972D02*
X1297687Y-40256D01*
G01X1295006Y-42940D02*
X1297687Y-43656D01*
G01X1335006Y-80022D02*
X1337687Y-79306D01*
G01X1335006Y-81990D02*
X1337687Y-82706D01*
G01X1460832Y763285D02*
Y823333D01*
X1479465Y841966D01*
Y870036D01*
X1479136Y870365D01*
Y881488D01*
X1478702Y882537D01*
Y888820D01*
X1493402Y903520D01*
X1511367D01*
X1512792Y904945D01*
Y907816D01*
X1513927Y908951D01*
G01X1459752Y806881D02*
Y823781D01*
X1478385Y842414D01*
Y869588D01*
X1478056Y869917D01*
Y881273D01*
X1477622Y882322D01*
Y889268D01*
X1492954Y904600D01*
X1510919D01*
X1511712Y905393D01*
Y907766D01*
X1510527Y908951D01*
G01X1484586Y-79994D02*
X1481905Y-79278D01*
G01X1484586Y-81962D02*
X1481905Y-82678D01*
G01X1519942Y-41074D02*
X1517261Y-40358D01*
G01X1519942Y-43042D02*
X1517261Y-43758D01*
G01X1589506Y-80022D02*
X1592187Y-79306D01*
G01X1589506Y-81990D02*
X1592187Y-82706D01*
G01X1579506Y-43070D02*
X1582187Y-43786D01*
G01X1579506Y-41102D02*
X1582187Y-40386D01*
G01X1626782Y659526D02*
Y664281D01*
X1762466Y799965D01*
Y820070D01*
X1760536Y822000D01*
X1756169D01*
X1754906Y820737D01*
G01X1739086Y-79994D02*
X1736405Y-79278D01*
G01X1739086Y-81962D02*
X1736405Y-82678D01*
G01X1763546Y802817D02*
Y820518D01*
X1760984Y823080D01*
X1756159D01*
X1754906Y824333D01*
G01X1804442Y-43172D02*
X1801761Y-43888D01*
G01X1804442Y-41204D02*
X1801761Y-40488D01*
G54D109*
G01X47273Y691166D02*
X39549Y683442D01*
Y682108D01*
G01X84314Y686107D02*
X79255Y691166D01*
X47273D01*
G01X49049Y842143D02*
X52574D01*
X53549Y843118D01*
G01X82648Y670679D02*
X85606Y667721D01*
Y664443D01*
G01X86528Y904833D02*
Y900545D01*
X87853Y899220D01*
G01X233722Y1260664D02*
Y1263646D01*
X238031Y1267955D01*
X280281Y1285455D01*
X319617D01*
X320624Y1284448D01*
G01X232222Y1260664D02*
Y1264268D01*
X237181Y1269227D01*
X279982Y1286955D01*
X324685D01*
X325683Y1287953D01*
G01X285334Y1178051D02*
X287263Y1179980D01*
X291089D01*
X291444Y1179625D01*
G01X289074Y1181791D02*
X291239Y1183956D01*
X291444D01*
G01X320624Y1284448D02*
X321631Y1285455D01*
X356598D01*
X385598Y1273443D01*
X394420D01*
X395670Y1272093D01*
G01X325683Y1287953D02*
X326681Y1286955D01*
X356897D01*
X385897Y1274943D01*
X394420D01*
X395670Y1276293D01*
G01X391757Y1381025D02*
X393827D01*
X396714Y1383912D01*
X398881D01*
G01Y1391786D02*
X398076Y1392591D01*
X396035D01*
G01X404324Y1271889D02*
X402913Y1273300D01*
X399927D01*
X398820Y1272093D01*
G01X404324Y1275889D02*
X403235Y1274800D01*
X400213D01*
X398820Y1276293D01*
G01X403678Y1295426D02*
X403214Y1295890D01*
Y1297965D01*
G01D02*
X403842Y1298593D01*
X405290Y1298611D01*
X407075Y1300396D01*
X409211D01*
G01Y1306301D02*
X404240D01*
X403798Y1305859D01*
G01X404583Y1316131D02*
Y1313443D01*
G01D02*
X405819Y1312207D01*
X409211D01*
G01X409215Y1394246D02*
Y1399217D01*
X408773Y1399659D01*
G01X398340Y1399779D02*
X398804Y1400243D01*
X400879D01*
G01X398881Y1389817D02*
X395770D01*
G01X400879Y1400243D02*
X400903Y1398337D01*
X403310Y1395930D01*
Y1394246D01*
G01X417574Y343005D02*
X414645D01*
X412914Y344736D01*
X410688D01*
G01X423904Y350559D02*
Y352845D01*
X426138Y355079D01*
G01X425433Y1112473D02*
X425437D01*
X428785Y1115821D01*
G01X421655Y1111226D02*
X422067Y1110814D01*
X423482D01*
X425141Y1112473D01*
X425433D01*
G01X411671Y1295967D02*
X410866Y1295162D01*
Y1293121D01*
G01X422432Y1288843D02*
Y1290913D01*
X419545Y1293800D01*
Y1295967D01*
G01X413640D02*
Y1292856D01*
G01X423482Y1314667D02*
Y1317372D01*
X425378Y1319268D01*
Y1320684D01*
G01X419545Y1314667D02*
Y1317722D01*
G01X413640Y1314667D02*
Y1315954D01*
X413538Y1316056D01*
Y1316486D01*
X413473Y1316551D01*
Y1316733D01*
X413345Y1316861D01*
Y1316953D01*
X413127Y1317171D01*
Y1318011D01*
G01X417581Y1383912D02*
X420636D01*
G01X417581Y1379975D02*
X422694D01*
X423517Y1379152D01*
G01X417305Y1368259D02*
X417255Y1368209D01*
X412779D01*
G01D02*
X413152Y1368582D01*
Y1375546D01*
G01X420925Y1390330D02*
X420085D01*
X419867Y1390112D01*
X419775D01*
X419647Y1389984D01*
X419465D01*
X419400Y1389919D01*
X418970D01*
X418868Y1389817D01*
X417581D01*
G01X416357Y1398874D02*
X415121Y1397638D01*
Y1394246D01*
G01X419045Y1398874D02*
X416357D01*
G01X439239Y342874D02*
X442340D01*
X443480Y344014D01*
G01X428118Y349696D02*
Y353276D01*
X428420Y353578D01*
G01X438127Y349675D02*
X438146Y349694D01*
Y351458D01*
X435886Y353718D01*
Y353867D01*
G01X431620Y1108898D02*
X429677Y1106955D01*
G01X428785Y1115821D02*
X431401D01*
X431476Y1115896D01*
G01X431620Y1112048D02*
X431496Y1112172D01*
X429890D01*
X427810Y1110092D01*
G01X427997Y1122742D02*
X431807D01*
X431822Y1122757D01*
G01X431476Y1118396D02*
X430087Y1118971D01*
X428785D01*
G01X431822Y1122757D02*
Y1118742D01*
X431476Y1118396D01*
G01X435248Y1309865D02*
X434875Y1310238D01*
X427911D01*
G01X435198Y1314391D02*
X435248Y1314341D01*
Y1309865D01*
G01X454591Y1010341D02*
X457376D01*
X459360Y1012325D01*
G01X450591Y1010341D02*
X454591D01*
G01X456377Y1023624D02*
X460377D01*
G01X456377Y1026774D02*
X452091Y1031060D01*
Y1039880D01*
G01X443591Y1014191D02*
X447091D01*
G01X459860Y1015825D02*
X455591D01*
G01X447091Y1014191D02*
X450591D01*
G01X455591Y1015825D02*
X453957Y1014191D01*
X450591D01*
G01X457577Y1112468D02*
X459653D01*
X460913Y1113728D01*
Y1115821D01*
G01X453676Y1111226D02*
X453689Y1111213D01*
X455840D01*
X457064Y1112437D01*
X457546D01*
X457577Y1112468D01*
G01X464385Y1026755D02*
X466219Y1028589D01*
Y1036700D01*
X464385Y1038534D01*
G01X460377Y1023624D02*
Y1019352D01*
X459885Y1018860D01*
G01X464516Y1014566D02*
X464891Y1014941D01*
Y1019069D01*
G01X464516Y1014566D02*
X462791D01*
X462185Y1015172D01*
Y1016825D01*
G01X464385Y1023605D02*
X464891Y1023099D01*
Y1019069D01*
G01X463966Y1108820D02*
Y1107418D01*
X462913Y1106365D01*
G01X463966Y1111970D02*
X461816D01*
X459938Y1110092D01*
G01X463604Y1115896D02*
X460988D01*
X460913Y1115821D01*
G01X463604Y1118396D02*
X462215Y1118971D01*
X460913D01*
G01X468297Y1197471D02*
X465785D01*
G01X458773Y1193471D02*
X461285D01*
G01X458773Y1197471D02*
X461285D01*
G01X468297Y1193471D02*
X465785D01*
G01X460846Y1254104D02*
X463156D01*
X463216Y1254164D01*
G01X460846Y1250700D02*
X463156D01*
X463216Y1250760D01*
G01X460846Y1247512D02*
Y1250700D01*
G01Y1244163D02*
Y1247512D01*
G01X465316Y1244109D02*
X463270D01*
X463216Y1244055D01*
G01X465316Y1247512D02*
Y1244109D01*
G01Y1250814D02*
X463270D01*
X463216Y1250760D01*
G01X465316Y1254104D02*
X463276D01*
X463216Y1254164D01*
G01X527136Y1288800D02*
X525935Y1290101D01*
X522972D01*
X519106Y1293967D01*
X469034D01*
X466465Y1291398D01*
X462249D01*
X460382Y1293265D01*
Y1295943D01*
X459290Y1297035D01*
G01X527136Y1293000D02*
X525837Y1291601D01*
X523594D01*
X519728Y1295467D01*
X468412D01*
X465843Y1292898D01*
X462871D01*
X461882Y1293887D01*
Y1295627D01*
X463290Y1297035D01*
G01X487127Y1111177D02*
X487310Y1110994D01*
X488725D01*
X489207Y1111476D01*
X490064D01*
X491069Y1112481D01*
G01X496372Y1108821D02*
Y1106298D01*
G01X497063Y1115896D02*
X494447D01*
X494372Y1115821D01*
G01D02*
Y1115784D01*
X491069Y1112481D01*
G01X496372Y1111971D02*
X495980Y1111579D01*
X494884D01*
X493397Y1110092D01*
G01X493532Y1122837D02*
X497332D01*
X497357Y1122862D01*
G01X497063Y1118396D02*
X495674Y1118971D01*
X494372D01*
G01X497357Y1122862D02*
Y1118690D01*
X497063Y1118396D01*
G01X523200Y1112493D02*
Y1112521D01*
X526500Y1115821D01*
G01X523200Y1112493D02*
X522137Y1111430D01*
X521646D01*
X521079Y1110863D01*
X519794D01*
X519385Y1111272D01*
G01X528500Y1108821D02*
Y1106365D01*
G01X529191Y1115896D02*
X526575D01*
X526500Y1115821D01*
G01X528500Y1111971D02*
X528089Y1111560D01*
X526993D01*
X525525Y1110092D01*
G01X529191Y1118396D02*
X527802Y1118971D01*
X526500D01*
G01X530286Y1288800D02*
X531587Y1290201D01*
X537514D01*
X538572Y1289143D01*
G01X689309Y1260832D02*
Y1262308D01*
X686966Y1264651D01*
X625283Y1290201D01*
X539630D01*
X538572Y1289143D01*
G01X530286Y1293000D02*
X531485Y1291701D01*
X542596D01*
X543621Y1292726D01*
G01X543468Y904833D02*
Y900545D01*
X544793Y899220D01*
G01X690809Y1260832D02*
Y1262930D01*
X687816Y1265923D01*
X625582Y1291701D01*
X544646D01*
X543621Y1292726D01*
G01X566103Y956232D02*
X569628D01*
X570603Y957207D01*
G01X746161Y1181791D02*
X748326Y1183956D01*
X748531D01*
G01X742421Y1178051D02*
X744340Y1179970D01*
X748186D01*
X748531Y1179625D01*
G01X780077Y1446194D02*
X780631Y1446748D01*
Y1450085D01*
G01X778428Y1455156D02*
Y1454276D01*
X775167Y1451015D01*
X774367D01*
G01X780631Y1450085D02*
X780523Y1450193D01*
X777725D01*
G01X799330Y1416760D02*
Y1405679D01*
X803095Y1401914D01*
Y1391724D01*
X799716Y1388345D01*
Y1373102D01*
X825021Y1347797D01*
X873493D01*
X879739Y1354043D01*
X989776D01*
X994179Y1358446D01*
X1022372D01*
X1041302Y1377376D01*
Y1400452D01*
X1062858Y1422008D01*
X1095808D01*
X1107200Y1433400D01*
Y1438914D01*
G01X803044Y1425152D02*
X799330Y1421438D01*
Y1416760D01*
G01X783227Y1446194D02*
Y1449439D01*
X786591Y1452803D01*
G01X794722Y1456302D02*
Y1458017D01*
X794037Y1458702D01*
X790481D01*
X786591Y1454812D01*
Y1452803D01*
G01X801354Y1478681D02*
X801998Y1478037D01*
Y1474141D01*
G01X841069Y1454159D02*
Y1454704D01*
X840547Y1455226D01*
X838894D01*
X836723Y1457397D01*
X835474D01*
G01X844219Y1454159D02*
X843650Y1453590D01*
Y1449546D01*
G01D02*
X844131D01*
X846044Y1451459D01*
G01X883669Y1456859D02*
X881244D01*
G01X889336Y1452554D02*
Y1454067D01*
X886819Y1456584D01*
Y1456859D01*
G01X912665Y353532D02*
X910040D01*
G01X900628Y918042D02*
X900458D01*
X898056Y915640D01*
Y913142D01*
X899286Y911912D01*
G01X909959Y1011750D02*
Y1008590D01*
X910013Y1008536D01*
G01X909300Y1014639D02*
Y1013281D01*
X909959Y1012622D01*
Y1011750D01*
G01X926355Y371739D02*
X929082D01*
X929943Y372600D01*
G01X931145Y865672D02*
Y864104D01*
X929161Y862120D01*
X924382D01*
X922313Y864189D01*
G01X937333Y864332D02*
X933637D01*
X929825Y860520D01*
X924915D01*
X922313Y857918D01*
Y857891D01*
G01X926693Y1379411D02*
X928594D01*
X928610Y1379427D01*
X931159D01*
G01X923570Y1383264D02*
X923543Y1383237D01*
Y1379411D01*
G01X923570Y1383264D02*
X920255D01*
G01X926720D02*
X928808D01*
X928845Y1383227D01*
X931159D01*
G01X923596Y1387039D02*
Y1390813D01*
X923624Y1390841D01*
G01X923596Y1387039D02*
X920360D01*
G01X926746D02*
X928913D01*
X928925Y1387027D01*
X931159D01*
G01X926774Y1390841D02*
X926788Y1390827D01*
X931159D01*
G01X937333Y864332D02*
X939213D01*
X939784Y864903D01*
X941768D01*
G01X945147Y868168D02*
X941883D01*
X941768Y868053D01*
G01X931145Y865672D02*
X932330Y866857D01*
X939328D01*
X940524Y868053D01*
X941768D01*
G01X945030Y864721D02*
X941950D01*
X941768Y864903D01*
G01X933970Y1375878D02*
X931137D01*
G01X937046Y1371951D02*
X938022Y1372927D01*
X940644D01*
X942742Y1375025D01*
Y1393286D01*
X944933Y1395477D01*
Y1399227D01*
X946985Y1401279D01*
Y1405012D01*
X948235Y1406262D01*
G01X931199Y1371951D02*
X933896D01*
G01X937120Y1375878D02*
X938571Y1374427D01*
X940022D01*
X941242Y1375647D01*
Y1393908D01*
X943433Y1396099D01*
Y1399849D01*
X945485Y1401901D01*
Y1405012D01*
X944235Y1406262D01*
G01X937134Y1398427D02*
Y1394627D01*
G01Y1398427D02*
X939559D01*
G01X933984Y1394627D02*
X931159D01*
G01X933984Y1398427D02*
X931159D01*
G01X933984Y1402227D02*
X931159D01*
G01X937134Y1406027D02*
Y1402227D01*
G01D02*
X939559D01*
G01X933984Y1406027D02*
X931159D01*
G01X1107200Y1438914D02*
Y1565918D01*
X1104038Y1569080D01*
X1092326D01*
X1084110Y1560864D01*
Y1544426D01*
X1064769Y1525085D01*
X1044772D01*
X1025133Y1544724D01*
X988130D01*
X986773Y1546081D01*
G01X1000554Y904833D02*
Y907003D01*
X1001229Y907678D01*
X1002430D01*
X1002930Y907178D01*
Y906785D01*
G01X1007719Y953247D02*
X1011244D01*
X1012219Y954222D01*
G01X1147895Y1261000D02*
Y1263646D01*
X1155576Y1271327D01*
X1207009Y1292631D01*
X1295376D01*
X1296787Y1291220D01*
G01X1146395Y1261000D02*
Y1264268D01*
X1154726Y1272599D01*
X1206710Y1294131D01*
X1300746D01*
X1301769Y1295154D01*
G01X1199507Y1178051D02*
X1201426Y1179970D01*
X1205272D01*
X1205617Y1179625D01*
G01X1203247Y1181791D02*
X1205412Y1183956D01*
X1205617D01*
G01X1296787Y1291220D02*
X1298198Y1292631D01*
X1308319D01*
X1309739Y1291111D01*
G01X1301769Y1295154D02*
X1302792Y1294131D01*
X1308659D01*
X1309739Y1295311D01*
G01X1315256Y336510D02*
X1316361Y337615D01*
X1320580D01*
G01X1320195Y346026D02*
X1310095D01*
X1308012Y348109D01*
G01X1315311Y840921D02*
Y841213D01*
X1316568Y842470D01*
X1316906D01*
G01X1318461Y840921D02*
X1320010Y842470D01*
X1320055D01*
G01X1314560Y867332D02*
X1316573D01*
X1316906Y867665D01*
G01X1315330Y884988D02*
Y884759D01*
X1316676Y883413D01*
X1316906D01*
G01X1310791Y1275725D02*
X1308997D01*
X1308276Y1276446D01*
G01X1318287Y1295381D02*
X1316905Y1293999D01*
X1314101D01*
X1312889Y1295311D01*
G01Y1291111D02*
X1314177Y1292499D01*
X1317169D01*
X1318287Y1291381D01*
G01X1326489Y353651D02*
Y356945D01*
G01X1330703Y352788D02*
Y356368D01*
X1331005Y356670D01*
G01X1331078Y834594D02*
X1331602D01*
X1332654Y835646D01*
Y836170D01*
G01X1331078Y837744D02*
X1332654Y839320D01*
G01X1334228Y850342D02*
X1334771D01*
X1335803Y851374D01*
Y851918D01*
G01X1321691Y863128D02*
Y862881D01*
X1323205Y861367D01*
G01X1334228Y878690D02*
X1334473D01*
X1335803Y877360D01*
Y877114D01*
G01X1334228Y894438D02*
X1334229D01*
X1335802Y896011D01*
G01X1334228Y891288D02*
X1333952D01*
X1332654Y892586D01*
Y892862D01*
G01X1341824Y345966D02*
X1344925D01*
X1346065Y347106D01*
G01X1340712Y352767D02*
X1340731Y352786D01*
Y354550D01*
X1338471Y356810D01*
Y356959D01*
G01X1349976Y840894D02*
X1351550Y839320D01*
G01X1346826Y840894D02*
X1345252Y839320D01*
G01X1338952Y855067D02*
Y855304D01*
X1340290Y856642D01*
X1340528D01*
G01X1337378Y853492D02*
X1337613D01*
X1338952Y854831D01*
Y855067D01*
G01X1342103Y855068D02*
Y855303D01*
X1343442Y856642D01*
X1343678D01*
G01X1345252Y855068D02*
Y855341D01*
X1346553Y856642D01*
X1346827D01*
G01X1351550Y855068D02*
Y855306D01*
X1350214Y856642D01*
X1349977D01*
G01X1338953Y861367D02*
Y861123D01*
G01D02*
X1337622Y859792D01*
X1337378D01*
G01X1340527Y872390D02*
X1340275D01*
X1338952Y873713D01*
Y873965D01*
G01X1335803Y877114D02*
X1337377Y875540D01*
G01D02*
X1337645D01*
X1338952Y874233D01*
Y873965D01*
G01X1337377Y878689D02*
Y878688D01*
X1335803Y877114D01*
G01X1340527Y872390D02*
Y872388D01*
X1338953Y870814D01*
G01X1337377Y869241D02*
X1338950Y870814D01*
X1338953D01*
G01X1346825Y872390D02*
X1346570D01*
X1345252Y873708D01*
Y873964D01*
G01X1343676Y872390D02*
X1343417D01*
X1342103Y873704D01*
Y873964D01*
G01X1349974Y872390D02*
X1350226D01*
X1351550Y873714D01*
Y873715D01*
G01X1353123Y872390D02*
X1352875D01*
X1351550Y873715D01*
G01X1337377Y869241D02*
X1337669D01*
X1338953Y867957D01*
G01D02*
Y867665D01*
G01X1346826Y891288D02*
X1345252Y892862D01*
G01X1349976Y891288D02*
X1351550Y892862D01*
G01X1344959Y1108821D02*
Y1107016D01*
X1344241Y1106298D01*
G01X1344959Y1111971D02*
X1344569Y1111581D01*
X1343473D01*
X1341984Y1110092D01*
G01X1345650Y1115896D02*
X1345575Y1115821D01*
X1342959D01*
G01X1339685Y1112469D02*
Y1112547D01*
X1342959Y1115821D01*
G01X1339685Y1112469D02*
X1338614Y1111398D01*
X1338146D01*
X1337537Y1110789D01*
X1336014D01*
X1335605Y1111198D01*
G01X1342218Y1122713D02*
X1342255Y1122676D01*
X1346083D01*
G01X1342959Y1118971D02*
X1343534Y1118396D01*
X1345650D01*
G01X1346083Y1122676D02*
Y1118829D01*
X1345650Y1118396D01*
G01X1362574Y837744D02*
X1364148Y836170D01*
G01X1362574Y840894D02*
X1362812D01*
X1364148Y839558D01*
Y839320D01*
G01X1359425Y856642D02*
X1359195D01*
X1357850Y855297D01*
G01X1357849Y858218D02*
X1359425Y856642D01*
G01X1354699Y855068D02*
Y855332D01*
X1353389Y856642D01*
X1353126D01*
G01X1357850Y855297D02*
Y855067D01*
G01Y855297D02*
Y855331D01*
X1356539Y856642D01*
X1356275D01*
G01X1357850Y873965D02*
Y873710D01*
X1359171Y872389D01*
X1359423D01*
G01X1362572Y875539D02*
Y875541D01*
X1360999Y877114D01*
G01D02*
Y877115D01*
X1359425Y878689D01*
G01X1354699Y873964D02*
Y873710D01*
X1356019Y872390D01*
X1356273D01*
G01D02*
X1357849Y870814D01*
G01X1354699Y867665D02*
Y867340D01*
X1355949Y866090D01*
X1356273D01*
G01X1357849Y867665D02*
Y867432D01*
X1359191Y866090D01*
X1359423D01*
G01X1351550Y873715D02*
Y873964D01*
G01X1365724Y894438D02*
X1365721D01*
X1364148Y896011D01*
G01X1365724Y891288D02*
X1365486D01*
X1364148Y892626D01*
Y892862D01*
G01X1364765Y1010341D02*
X1368765D01*
G01X1357765Y1014191D02*
X1361265D01*
G01D02*
X1364765D01*
G01D02*
X1368131D01*
X1369765Y1015825D01*
G01X1370551Y1026774D02*
X1366265Y1031060D01*
Y1039880D01*
G01X1378266Y844021D02*
X1378345D01*
X1379896Y842470D01*
G01X1372023Y869241D02*
X1371753D01*
X1370447Y867935D01*
Y867665D01*
G01X1381461Y885021D02*
Y884782D01*
X1380092Y883413D01*
X1379896D01*
G01X1368765Y1010341D02*
X1371550D01*
X1373534Y1012325D01*
G01X1369765Y1015825D02*
X1374034D01*
G01X1374551Y1023624D02*
Y1019352D01*
X1374059Y1018860D01*
G01X1370551Y1023624D02*
X1374551D01*
G01X1378559Y1026755D02*
X1380393Y1028589D01*
Y1036700D01*
X1378559Y1038534D01*
G01X1378690Y1014566D02*
X1379065Y1014941D01*
Y1019069D01*
G01X1378690Y1014566D02*
X1376965D01*
X1376359Y1015172D01*
Y1016825D01*
G01X1378559Y1023605D02*
X1379065Y1023099D01*
Y1019069D01*
G01X1377087Y1106365D02*
Y1108821D01*
G01Y1111971D02*
X1376675Y1111559D01*
X1375579D01*
X1374112Y1110092D01*
G01X1377778Y1115896D02*
X1375162D01*
X1375087Y1115821D01*
G01D02*
Y1114506D01*
X1373051Y1112470D01*
X1371792D01*
G01D02*
X1370689Y1111367D01*
X1370508D01*
X1370008Y1110867D01*
X1368316D01*
X1367985Y1111198D01*
X1367816D01*
G01X1377778Y1118396D02*
X1376389Y1118971D01*
X1375087D01*
G01X1372947Y1197471D02*
X1375459D01*
G01X1372947Y1193471D02*
X1375459D01*
G01X1382471Y1197471D02*
X1379959D01*
G01X1382471Y1193471D02*
X1379959D01*
G01X1379490Y1247512D02*
Y1244109D01*
G01D02*
X1379436Y1244055D01*
X1377390D01*
G01X1375020Y1250700D02*
X1375080Y1250760D01*
X1377390D01*
G01X1379490Y1250814D02*
X1379436Y1250760D01*
X1377390D01*
G01X1375020Y1254104D02*
X1377330D01*
X1377390Y1254164D01*
G01X1379490Y1254104D02*
X1377450D01*
X1377390Y1254164D01*
G01X1375020Y1247512D02*
Y1250700D01*
G01X1385052Y1303139D02*
X1386302Y1301889D01*
Y1299443D01*
X1387787Y1297958D01*
X1405450D01*
X1408986Y1294422D01*
X1418315D01*
X1422587Y1290150D01*
X1440059D01*
X1441309Y1288800D01*
G01X1389052Y1303139D02*
X1387802Y1301889D01*
Y1300065D01*
X1388409Y1299458D01*
X1406072D01*
X1409608Y1295922D01*
X1418937D01*
X1423209Y1291650D01*
X1440059D01*
X1441309Y1293000D01*
G01X1410546Y1108821D02*
Y1106298D01*
G01X1411237Y1115896D02*
X1408621D01*
X1408546Y1115821D01*
G01X1405189Y1112468D02*
X1405193D01*
X1408546Y1115821D01*
G01X1405189Y1112468D02*
X1404073Y1111352D01*
X1403876D01*
X1403373Y1110849D01*
X1401672D01*
X1401263Y1111258D01*
G01X1410546Y1111971D02*
X1410154Y1111579D01*
X1409058D01*
X1407571Y1110092D01*
G01X1407954Y1122887D02*
X1411806D01*
X1411829Y1122864D01*
G01X1408546Y1118971D02*
X1410662D01*
X1411237Y1118396D01*
G01X1411829Y1122864D02*
Y1118988D01*
X1411237Y1118396D01*
G01X1442674Y1108821D02*
Y1106365D01*
G01Y1111971D02*
X1442291Y1111588D01*
X1441195D01*
X1439699Y1110092D01*
G01X1440674Y1115821D02*
X1440749Y1115896D01*
X1443365D01*
G01X1440674Y1115821D02*
Y1115816D01*
X1437352Y1112494D01*
G01D02*
X1436589Y1111731D01*
X1436415D01*
X1435472Y1110788D01*
X1433915D01*
X1433506Y1111197D01*
G01X1440674Y1118971D02*
X1442790D01*
X1443365Y1118396D01*
G01X1444459Y1288800D02*
X1445760Y1290201D01*
X1451685D01*
X1452784Y1289102D01*
G01X1444459Y1293000D02*
X1445658Y1291701D01*
X1456769D01*
X1457794Y1292726D01*
G01X1457641Y904833D02*
Y901005D01*
X1459420Y899226D01*
G01X1452784Y1289102D02*
X1453883Y1290201D01*
X1538134D01*
X1602287Y1263628D01*
X1603482Y1262433D01*
Y1261000D01*
G01X1457794Y1292726D02*
X1458819Y1291701D01*
X1538433D01*
X1603137Y1264900D01*
X1604982Y1263055D01*
Y1261000D01*
G01X1523000Y961437D02*
Y967925D01*
G01X1660334Y1181791D02*
X1662499Y1183956D01*
X1662704D01*
G01X1656594Y1178051D02*
X1658513Y1179970D01*
X1662359D01*
X1662704Y1179625D01*
G01X1789399Y989590D02*
X1789151Y989342D01*
Y989126D01*
X1786863Y986838D01*
Y985060D01*
G54D16*
X15424Y1041679D03*
X28810D03*
X37157D03*
X50543D03*
X437627Y1234726D03*
X451013D03*
X476336D03*
X489722D03*
X862114Y1050682D03*
X875500D03*
X897233D03*
X883847D03*
X926091D03*
X947824D03*
X939477D03*
X961210D03*
X1351801Y1234726D03*
X1365187D03*
X1390510D03*
X1403896D03*
X1770071Y1051168D03*
X1783457D03*
X1791804D03*
X1805190D03*
G54D52*
X212460Y554847D03*
X669546D03*
X1126633D03*
X1583720D03*
G54D61*
X269682Y451628D03*
X275588Y458714D03*
X269682D03*
X275588Y451628D03*
X726768D03*
X732674Y458714D03*
X726768D03*
X732674Y451628D03*
X1183855D03*
X1189761Y458714D03*
X1183855D03*
X1189761Y451628D03*
X1640942D03*
Y458714D03*
X1646848D03*
Y451628D03*
G54D25*
X34946Y1082645D03*
X35992Y1090694D03*
X33892D03*
X35936Y1093825D03*
X33836D03*
X42947Y1073034D03*
X40847D03*
X37046Y1082645D03*
X97906Y1021028D03*
X100006D03*
X97837Y1024139D03*
X99937D03*
X181618Y562188D03*
X179518D03*
X181618Y565388D03*
X179518D03*
X181618Y568588D03*
X179518D03*
X181618Y571988D03*
X179518D03*
X181618Y575388D03*
X179518D03*
X181430Y1144389D03*
X181450Y1151870D03*
Y1155610D03*
X173949Y1153740D03*
X176049D03*
X173949Y1149999D03*
X176049D03*
X181450Y1166830D03*
X173949Y1157480D03*
X176049D03*
X181450Y1159350D03*
Y1162450D03*
Y1170570D03*
X173949Y1161220D03*
X176049D03*
X173949Y1164960D03*
X176049D03*
X173949Y1174310D03*
X176049D03*
X181450Y1181800D03*
Y1178000D03*
X173949Y1178051D03*
X176049D03*
X173949Y1181791D03*
X176049D03*
X181450Y1185200D03*
X194750Y1136909D03*
X192650D03*
X194750Y1144389D03*
X192650D03*
X182950Y1148129D03*
X185050D03*
X194750Y1151869D03*
X192650D03*
Y1148129D03*
X194750D03*
X183530Y1144389D03*
X183550Y1151870D03*
Y1155610D03*
Y1166830D03*
X192830D03*
X194930D03*
X183550Y1159350D03*
Y1162450D03*
Y1170570D03*
X194550Y1185100D03*
X192450D03*
X182950Y1174310D03*
X185050D03*
X194750Y1178250D03*
X192650D03*
Y1181791D03*
X194750D03*
X183550Y1181800D03*
Y1178000D03*
Y1185200D03*
X195570Y1193011D03*
X193470D03*
X188090D03*
X190190D03*
X200311Y1166830D03*
X202411D03*
X207791D03*
X209891D03*
X230132D03*
X222752D03*
X224852D03*
X215271D03*
X217371D03*
X239050Y1166900D03*
X236950D03*
X241950D03*
X244050D03*
X232232Y1166830D03*
X248833D03*
X250933D03*
X256313D03*
X258413D03*
X270373Y1129429D03*
X272473D03*
X277034Y1140649D03*
X274934D03*
X277034Y1136909D03*
X274934D03*
X270373Y1133169D03*
X272473D03*
X277034Y1144389D03*
X274934D03*
X269553Y1155610D03*
X267453D03*
X278674D03*
X263713Y1166830D03*
X265813D03*
X278674Y1159350D03*
X273294D03*
X271194D03*
X273294Y1166830D03*
X271194D03*
X273294Y1170570D03*
X271194D03*
X278674Y1166830D03*
Y1170570D03*
X270373Y1178051D03*
X268273D03*
X271194Y1185531D03*
X273294D03*
X277854Y1181791D03*
X273294D03*
X271194D03*
X278674Y1174310D03*
X269553D03*
X267453D03*
X271194Y1189271D03*
X273294D03*
X271194Y1193011D03*
X273294D03*
X287927Y436924D03*
X290027D03*
X287927Y433524D03*
X290027D03*
X287927Y430124D03*
X290027D03*
X287927Y440124D03*
X290027D03*
X287927Y443324D03*
X290027D03*
X280774Y1155610D03*
X288254Y1157480D03*
X286154D03*
X288254Y1161220D03*
X286154D03*
X288254Y1168700D03*
X286154D03*
X288254Y1172440D03*
X286154D03*
X288254Y1164960D03*
X286154D03*
X280774Y1159350D03*
Y1166830D03*
Y1170570D03*
X279954Y1181791D03*
X285334D03*
X283234D03*
X280774Y1174310D03*
X460846Y1250700D03*
X458746D03*
X460846Y1254104D03*
X458746D03*
X460846Y1247512D03*
X458746D03*
X460846Y1244163D03*
X458746D03*
X465316Y1247512D03*
X467416D03*
X465316Y1254104D03*
X467416D03*
X465316Y1244109D03*
X467416D03*
X465316Y1250814D03*
X467416D03*
X636604Y562188D03*
Y565388D03*
Y568588D03*
Y571988D03*
Y575388D03*
X631036Y1149999D03*
X633136D03*
X631036Y1153740D03*
X633136D03*
X631036Y1157480D03*
X633136D03*
X631036Y1172500D03*
X633136D03*
X631036Y1161220D03*
X633136D03*
X631036Y1164960D03*
X633136D03*
X631036Y1179921D03*
X633136D03*
X631036Y1176180D03*
X633136D03*
X638704Y562188D03*
Y565388D03*
Y568588D03*
Y571988D03*
Y575388D03*
X651837Y1136909D03*
X649737D03*
X651837Y1144389D03*
X649737D03*
X651837Y1151869D03*
X649737D03*
Y1148129D03*
X651837D03*
X640037D03*
X642137D03*
X638517Y1144389D03*
X640617D03*
X638500Y1151870D03*
X640600D03*
X638500Y1155610D03*
X640600D03*
X638500Y1166830D03*
X640600D03*
X649817D03*
X651917D03*
X638500Y1159350D03*
X640600D03*
X638500Y1162500D03*
X640600D03*
X638500Y1170570D03*
X640600D03*
X651837Y1178250D03*
X649737D03*
Y1181791D03*
X651837D03*
X651637Y1185100D03*
X649537D03*
X639850Y1174900D03*
X641950D03*
X638500Y1185342D03*
X640600D03*
X638537Y1181800D03*
X640637D03*
X638537Y1178000D03*
X640637D03*
X645177Y1193011D03*
X647277D03*
X652657D03*
X650557D03*
X657298Y1166830D03*
X659398D03*
X664778D03*
X666878D03*
X672258D03*
X674358D03*
X679739D03*
X681839D03*
X687219D03*
X689319D03*
X699179D03*
X701279D03*
X695899D03*
X693799D03*
X713400D03*
X715500D03*
X705920D03*
X708020D03*
X727460Y1133169D03*
X729560D03*
X727460Y1129429D03*
X729560D03*
X734121Y1136909D03*
X732021D03*
X734121Y1140649D03*
X732021D03*
X734121Y1144389D03*
X732021D03*
X726640Y1155610D03*
X724540D03*
X730381Y1159350D03*
X728281D03*
X730450Y1162800D03*
X728350D03*
X730381Y1166830D03*
X728281D03*
X720800D03*
X722900D03*
X730381Y1170570D03*
X728281D03*
Y1189271D03*
X730381D03*
X728281Y1185531D03*
X730381D03*
Y1181791D03*
X728281D03*
X726640Y1174310D03*
X724540D03*
X728281Y1193011D03*
X730381D03*
X745013Y440124D03*
X747113D03*
X745013Y430124D03*
X747113D03*
X745013Y433524D03*
X747113D03*
X745013Y436924D03*
X747113D03*
X745013Y443324D03*
X747113D03*
X737861Y1155610D03*
X735761D03*
X745341Y1164960D03*
X743241D03*
X745341Y1161220D03*
X743241D03*
X745341Y1168700D03*
X743241D03*
X745341Y1172440D03*
X743241D03*
X737861Y1159350D03*
X735761D03*
X737861Y1170570D03*
X735761D03*
X737861Y1166830D03*
X735761D03*
X745341Y1157480D03*
X743241D03*
X737861Y1174310D03*
X735761D03*
X734941Y1181791D03*
X737041D03*
X742421D03*
X740321D03*
X883265Y1100705D03*
X881165D03*
X910013Y1008536D03*
X912113D03*
X909959Y1011750D03*
X912059D03*
X921107Y1090015D03*
X923207D03*
X1088122Y1153740D03*
X1090222D03*
X1088122Y1149999D03*
X1090222D03*
X1088122Y1164960D03*
X1090222D03*
X1088122Y1161220D03*
X1090222D03*
X1088122Y1157480D03*
X1090222D03*
X1088122Y1181791D03*
X1090222D03*
X1088122Y1178051D03*
X1090222D03*
X1088122Y1174310D03*
X1090222D03*
X1095791Y568588D03*
X1093691D03*
X1095791Y565388D03*
X1093691D03*
X1095791Y562188D03*
X1093691D03*
X1095791Y571988D03*
X1093691D03*
X1095791Y575388D03*
X1093691D03*
X1106823Y1136909D03*
Y1151869D03*
Y1148129D03*
Y1144389D03*
X1095623Y1155610D03*
X1097723D03*
X1095623Y1151870D03*
X1097723D03*
X1095603Y1142579D03*
X1097703D03*
X1097123Y1148129D03*
X1099223D03*
X1107003Y1166830D03*
X1095623Y1170570D03*
X1097723D03*
X1095623Y1166830D03*
X1097723D03*
X1095623Y1162450D03*
X1097723D03*
X1095623Y1159350D03*
X1097723D03*
X1106623Y1185100D03*
X1106823Y1181791D03*
Y1178250D03*
X1095623Y1185200D03*
X1097723D03*
X1095623Y1181800D03*
X1097723D03*
X1095623Y1178000D03*
X1097723D03*
X1097123Y1174310D03*
X1099223D03*
X1107643Y1193011D03*
X1102263D03*
X1104363D03*
X1108923Y1136909D03*
Y1151869D03*
Y1148129D03*
Y1144389D03*
X1121964Y1166830D03*
X1124064D03*
X1114484D03*
X1116584D03*
X1109103D03*
X1108723Y1185100D03*
X1108923Y1181791D03*
Y1178250D03*
X1109743Y1193011D03*
X1136925Y1166830D03*
X1139025D03*
X1129444D03*
X1131544D03*
X1156123Y1166900D03*
X1153223D03*
X1151123D03*
X1144305Y1166830D03*
X1146405D03*
X1170486D03*
X1172586D03*
X1163006D03*
X1165106D03*
X1158223Y1166900D03*
X1189107Y1140649D03*
Y1136909D03*
X1184546Y1133169D03*
X1186646D03*
X1184546Y1129429D03*
X1186646D03*
X1189107Y1144389D03*
X1183726Y1155610D03*
X1181626D03*
X1187467Y1170570D03*
X1185367D03*
X1187467Y1166830D03*
X1185367D03*
X1187467Y1159350D03*
X1185367D03*
X1177886Y1166830D03*
X1179986D03*
X1185367Y1189271D03*
X1187467D03*
X1185367Y1185531D03*
X1187467D03*
Y1181791D03*
X1185367D03*
X1184546Y1178051D03*
X1182446D03*
X1183726Y1174310D03*
X1181626D03*
X1185367Y1193011D03*
X1187467D03*
X1202100Y433524D03*
X1204200D03*
X1202100Y430124D03*
X1204200D03*
X1202100Y440124D03*
X1204200D03*
X1202100Y436924D03*
X1204200D03*
X1202100Y443324D03*
X1204200D03*
X1191207Y1140649D03*
Y1136909D03*
X1194947Y1155610D03*
X1192847D03*
X1191207Y1144389D03*
X1202427Y1172440D03*
X1200327D03*
X1202427Y1168700D03*
X1200327D03*
X1202427Y1164960D03*
X1200327D03*
X1202427Y1161220D03*
X1200327D03*
X1202427Y1157480D03*
X1200327D03*
X1194947Y1170570D03*
X1192847D03*
X1194947Y1166830D03*
X1192847D03*
X1194947Y1159350D03*
X1192847D03*
X1194947Y1174310D03*
X1192847D03*
X1192027Y1181791D03*
X1194127D03*
X1199507D03*
X1197407D03*
X1375020Y1254104D03*
X1372920D03*
X1375020Y1247512D03*
X1372920D03*
X1375020Y1250700D03*
X1372920D03*
X1379490Y1254104D03*
X1381590D03*
X1379490Y1247512D03*
X1381590D03*
X1379490Y1250814D03*
X1381590D03*
X1379490Y1244109D03*
X1381590D03*
X1545209Y1149999D03*
Y1153740D03*
Y1157480D03*
Y1161220D03*
Y1164960D03*
Y1174310D03*
Y1178051D03*
Y1181791D03*
X1552878Y568588D03*
X1550778D03*
X1552878Y565388D03*
X1550778D03*
X1552878Y562188D03*
X1550778D03*
X1552878Y571988D03*
X1550778D03*
X1552878Y575388D03*
X1550778D03*
X1552690Y1144389D03*
X1554790D03*
X1554210Y1148129D03*
X1556310D03*
X1552710Y1155610D03*
X1554810D03*
X1552710Y1151870D03*
X1554810D03*
X1547309Y1149999D03*
Y1153740D03*
X1552710Y1170570D03*
X1554810D03*
X1552710Y1166830D03*
X1554810D03*
X1552710Y1162450D03*
X1554810D03*
X1552710Y1159350D03*
X1554810D03*
X1547309Y1157480D03*
Y1161220D03*
Y1164960D03*
X1552710Y1185200D03*
X1554810D03*
X1552710Y1181800D03*
X1554810D03*
X1552710Y1178000D03*
X1554810D03*
X1554210Y1174310D03*
X1556310D03*
X1547309D03*
Y1178051D03*
Y1181791D03*
X1559350Y1193011D03*
X1561450D03*
X1566010Y1136909D03*
X1563910D03*
X1566010Y1144389D03*
X1563910D03*
Y1148129D03*
X1566010D03*
Y1151869D03*
X1563910D03*
X1564090Y1166830D03*
X1566190D03*
X1571571D03*
X1573671D03*
X1579051D03*
X1566010Y1178250D03*
X1563910D03*
Y1181791D03*
X1566010D03*
X1565810Y1185100D03*
X1563710D03*
X1566830Y1193011D03*
X1564730D03*
X1586531Y1166830D03*
X1588631D03*
X1594012D03*
X1581151D03*
X1601392D03*
X1603492D03*
X1610310Y1166900D03*
X1608210D03*
X1596112Y1166830D03*
X1613210Y1166900D03*
X1615310D03*
X1620093Y1166830D03*
X1622193D03*
X1627573D03*
X1641633Y1129429D03*
X1643733D03*
X1641633Y1133169D03*
X1643733D03*
X1640813Y1155610D03*
X1638713D03*
X1634973Y1166830D03*
X1637073D03*
X1642454Y1159350D03*
Y1166830D03*
Y1170570D03*
X1629673Y1166830D03*
X1640813Y1174310D03*
X1638713D03*
X1641633Y1178051D03*
X1639533D03*
X1642454Y1181791D03*
Y1185531D03*
Y1189271D03*
Y1193011D03*
X1659187Y436924D03*
Y433524D03*
Y430124D03*
Y440124D03*
Y443324D03*
X1648294Y1136909D03*
X1646194D03*
X1648294Y1140649D03*
X1646194D03*
X1648294Y1144389D03*
X1646194D03*
X1652034Y1155610D03*
X1649934D03*
X1652034Y1159350D03*
X1649934D03*
X1652034Y1166830D03*
X1649934D03*
X1652034Y1170570D03*
X1649934D03*
X1659514Y1157480D03*
X1657414D03*
X1659514Y1161220D03*
X1657414D03*
X1659514Y1164960D03*
X1657414D03*
X1659514Y1168700D03*
X1657414D03*
X1659514Y1172440D03*
X1657414D03*
X1644554Y1159350D03*
Y1166830D03*
Y1170570D03*
X1652034Y1174310D03*
X1649934D03*
X1656594Y1181791D03*
X1654494D03*
X1649114D03*
X1651214D03*
X1644554D03*
Y1185531D03*
Y1189271D03*
Y1193011D03*
X1661287Y436924D03*
Y433524D03*
Y430124D03*
Y440124D03*
Y443324D03*
X1769937Y1073611D03*
X1772037D03*
X1769857Y1076717D03*
X1771957D03*
X1769858Y1090841D03*
X1771958D03*
X1789492Y1091246D03*
X1791592D03*
G54D34*
X44079Y1529376D03*
Y1536376D03*
X394175Y1399389D03*
Y1406389D03*
X410955Y318485D03*
Y325485D03*
X405121Y930778D03*
X397121D03*
X405121Y937778D03*
X397121D03*
X411095Y1102897D03*
Y1109897D03*
X405231Y1124747D03*
Y1117747D03*
X423750Y538080D03*
Y545080D03*
X413121Y930778D03*
X421121D03*
X413121Y937778D03*
X421121D03*
X413231Y1124747D03*
Y1117747D03*
X426934Y1198971D03*
Y1191971D03*
X413469Y1198971D03*
Y1191971D03*
X435804Y538090D03*
Y545090D03*
X443223Y1102897D03*
Y1109897D03*
X437359Y1124747D03*
Y1117747D03*
X432975Y1152039D03*
Y1159039D03*
X434266Y1378453D03*
Y1371453D03*
X459104Y537990D03*
X447614Y538080D03*
X459104Y544990D03*
X447614Y545080D03*
X445359Y1124747D03*
Y1117747D03*
X470818Y1124747D03*
Y1117747D03*
X476682Y1102897D03*
X478818Y1124747D03*
Y1117747D03*
X476682Y1109897D03*
X486671Y1198971D03*
Y1191971D03*
X508810Y1102897D03*
Y1109897D03*
X502946Y1124747D03*
Y1117747D03*
X498562Y1152039D03*
Y1159039D03*
X500136Y1198971D03*
Y1191971D03*
X510946Y1124747D03*
Y1117747D03*
X1313540Y321577D03*
Y328577D03*
X1319405Y1124747D03*
Y1117747D03*
X1325269Y1102897D03*
Y1109897D03*
X1327405Y1124747D03*
Y1117747D03*
X1327643Y1198971D03*
Y1191971D03*
X1351533Y1124747D03*
Y1117747D03*
X1347149Y1152039D03*
Y1159039D03*
X1341108Y1198971D03*
Y1191971D03*
X1357397Y1102897D03*
Y1109897D03*
X1359533Y1124747D03*
Y1117747D03*
X1384992Y1124747D03*
Y1117747D03*
X1390856Y1102897D03*
Y1109897D03*
X1392992Y1124747D03*
Y1117747D03*
X1400845Y1198971D03*
Y1191971D03*
X1417120Y1124747D03*
Y1117747D03*
X1412736Y1152039D03*
Y1159039D03*
X1414310Y1198971D03*
Y1191971D03*
X1422984Y1102897D03*
Y1109897D03*
X1425120Y1124747D03*
Y1117747D03*
G54D70*
X401341Y1375546D03*
X403310D03*
X405278D03*
X407247D03*
X409215D03*
X401341Y1394246D03*
X403310D03*
X405278D03*
X407247D03*
X409215D03*
X413640Y1295967D03*
X411671D03*
X419545D03*
X421514D03*
X423482D03*
X425451D03*
X415608D03*
X417577D03*
X425451Y1314667D03*
X413640D03*
X423482D03*
X419545D03*
X411671D03*
X421514D03*
X417577D03*
X415608D03*
X411184Y1375546D03*
X413152D03*
X415121D03*
X411184Y1394246D03*
X413152D03*
X415121D03*
G54D43*
X109882Y1453504D03*
Y1468859D03*
Y1484213D03*
Y1499567D03*
Y1514922D03*
Y1555867D03*
Y1571221D03*
Y1586575D03*
Y1601930D03*
Y1617284D03*
X127205Y1453504D03*
X118543Y1457835D03*
X127205Y1468859D03*
X118543Y1473189D03*
X127205Y1484213D03*
X118543Y1488544D03*
X127205Y1499567D03*
Y1514922D03*
X118543Y1503898D03*
Y1519252D03*
X127205Y1555867D03*
X118543Y1560197D03*
X127205Y1571221D03*
X118543Y1575552D03*
X127205Y1586575D03*
X118543Y1590906D03*
X127205Y1601930D03*
X118543Y1606260D03*
X127205Y1617284D03*
X118543Y1621615D03*
X144528Y1453504D03*
X135866Y1457835D03*
X144528Y1468859D03*
X135866Y1473189D03*
X144528Y1484213D03*
X135866Y1488544D03*
X144528Y1499567D03*
Y1514922D03*
X135866Y1503898D03*
Y1519252D03*
X144528Y1555867D03*
X135866Y1560197D03*
X144528Y1571221D03*
X135866Y1575552D03*
X144528Y1586575D03*
X135866Y1590906D03*
X144528Y1601930D03*
X135866Y1606260D03*
X144528Y1617284D03*
X135866Y1621615D03*
X161850Y1453504D03*
X153189Y1457835D03*
X161850Y1468859D03*
X153189Y1473189D03*
X161850Y1484213D03*
X153189Y1488544D03*
X161850Y1499567D03*
Y1514922D03*
X153189Y1503898D03*
Y1519252D03*
X161850Y1555867D03*
X153189Y1560197D03*
X161850Y1571221D03*
X153189Y1575552D03*
X161850Y1586575D03*
X153189Y1590906D03*
X161850Y1601930D03*
X153189Y1606260D03*
X161850Y1617284D03*
X153189Y1621615D03*
X179173Y1453504D03*
X170512Y1457835D03*
X179173Y1468859D03*
X170512Y1473189D03*
X179173Y1484213D03*
X170512Y1488544D03*
X179173Y1499567D03*
Y1514922D03*
X170512Y1503898D03*
Y1519252D03*
X179173Y1555867D03*
X170512Y1560197D03*
X179173Y1571221D03*
X170512Y1575552D03*
X179173Y1586575D03*
X170512Y1590906D03*
X179173Y1601930D03*
X170512Y1606260D03*
X179173Y1617284D03*
X170512Y1621615D03*
X187835Y1457835D03*
Y1473189D03*
Y1488544D03*
Y1503898D03*
Y1519252D03*
Y1560197D03*
Y1575552D03*
Y1590906D03*
Y1606260D03*
Y1621615D03*
X283110Y1453504D03*
X291771Y1457835D03*
X283110Y1468859D03*
X291771Y1473189D03*
X283110Y1484213D03*
X291771Y1488544D03*
X283110Y1499567D03*
X291771Y1503898D03*
X283110Y1514922D03*
X291771Y1519252D03*
X283110Y1555867D03*
X291771Y1560197D03*
X283110Y1571221D03*
X291771Y1575552D03*
X283110Y1586575D03*
X291771Y1590906D03*
X283110Y1601930D03*
X291771Y1606260D03*
X283110Y1617284D03*
X291771Y1621615D03*
X300433Y1453504D03*
X309094Y1457835D03*
X300433Y1468859D03*
X309094Y1473189D03*
X300433Y1484213D03*
X309094Y1488544D03*
X300433Y1499567D03*
X309094Y1503898D03*
X300433Y1514922D03*
X309094Y1519252D03*
X300433Y1555867D03*
X309094Y1560197D03*
X300433Y1571221D03*
X309094Y1575552D03*
X300433Y1586575D03*
X309094Y1590906D03*
X300433Y1601930D03*
X309094Y1606260D03*
X300433Y1617284D03*
X309094Y1621615D03*
X317756Y1453504D03*
X326417Y1457835D03*
X317756Y1468859D03*
X326417Y1473189D03*
X317756Y1484213D03*
X326417Y1488544D03*
X317756Y1499567D03*
X326417Y1503898D03*
X317756Y1514922D03*
X326417Y1519252D03*
X317756Y1555867D03*
X326417Y1560197D03*
X317756Y1571221D03*
X326417Y1575552D03*
X317756Y1586575D03*
X326417Y1590906D03*
X317756Y1601930D03*
X326417Y1606260D03*
X317756Y1617284D03*
X326417Y1621615D03*
X335078Y1453504D03*
X343740Y1457835D03*
X335078Y1468859D03*
X343740Y1473189D03*
X335078Y1484213D03*
X343740Y1488544D03*
X335078Y1499567D03*
X343740Y1503898D03*
X335078Y1514922D03*
X343740Y1519252D03*
X335078Y1555867D03*
X343740Y1560197D03*
X335078Y1571221D03*
X343740Y1575552D03*
X335078Y1586575D03*
X343740Y1590906D03*
X335078Y1601930D03*
X343740Y1606260D03*
X335078Y1617284D03*
X343740Y1621615D03*
X352401Y1453504D03*
X361063Y1457835D03*
X352401Y1468859D03*
X361063Y1473189D03*
X352401Y1484213D03*
X361063Y1488544D03*
X352401Y1499567D03*
X361063Y1503898D03*
X352401Y1514922D03*
X361063Y1519252D03*
X352401Y1555867D03*
X361063Y1560197D03*
X352401Y1571221D03*
X361063Y1575552D03*
X352401Y1586575D03*
X361063Y1590906D03*
X352401Y1601930D03*
X361063Y1606260D03*
X352401Y1617284D03*
X361063Y1621615D03*
X456339Y1453504D03*
Y1468859D03*
Y1484213D03*
Y1499567D03*
Y1514922D03*
Y1555867D03*
Y1571221D03*
Y1586575D03*
Y1601930D03*
Y1617284D03*
X473662Y1453504D03*
X465000Y1457835D03*
X473662Y1468859D03*
X465000Y1473189D03*
X473662Y1484213D03*
X465000Y1488544D03*
X473662Y1499567D03*
Y1514922D03*
X465000Y1503898D03*
Y1519252D03*
X473662Y1555867D03*
X465000Y1560197D03*
X473662Y1571221D03*
X465000Y1575552D03*
X473662Y1586575D03*
X465000Y1590906D03*
X473662Y1601930D03*
X465000Y1606260D03*
X473662Y1617284D03*
X465000Y1621615D03*
X490985Y1453504D03*
X482323Y1457835D03*
X490985Y1468859D03*
X482323Y1473189D03*
X490985Y1484213D03*
X482323Y1488544D03*
X490985Y1499567D03*
Y1514922D03*
X482323Y1503898D03*
Y1519252D03*
X490985Y1555867D03*
X482323Y1560197D03*
X490985Y1571221D03*
X482323Y1575552D03*
X490985Y1586575D03*
X482323Y1590906D03*
X490985Y1601930D03*
X482323Y1606260D03*
X490985Y1617284D03*
X482323Y1621615D03*
X508307Y1453504D03*
X499646Y1457835D03*
X508307Y1468859D03*
X499646Y1473189D03*
X508307Y1484213D03*
X499646Y1488544D03*
X508307Y1499567D03*
Y1514922D03*
X499646Y1503898D03*
Y1519252D03*
X508307Y1555867D03*
X499646Y1560197D03*
X508307Y1571221D03*
X499646Y1575552D03*
X508307Y1586575D03*
X499646Y1590906D03*
X508307Y1601930D03*
X499646Y1606260D03*
X508307Y1617284D03*
X499646Y1621615D03*
X516969Y1457835D03*
Y1473189D03*
Y1488544D03*
Y1503898D03*
Y1519252D03*
Y1560197D03*
Y1575552D03*
Y1590906D03*
Y1606260D03*
Y1621615D03*
X525630Y1453504D03*
X534292Y1457835D03*
X525630Y1468859D03*
X534292Y1473189D03*
X525630Y1484213D03*
X534292Y1488544D03*
X525630Y1499567D03*
X534292Y1503898D03*
X525630Y1514922D03*
X534292Y1519252D03*
X525630Y1555867D03*
X534292Y1560197D03*
X525630Y1571221D03*
X534292Y1575552D03*
X525630Y1586575D03*
X534292Y1590906D03*
X525630Y1601930D03*
X534292Y1606260D03*
X525630Y1617284D03*
X534292Y1621615D03*
X629567Y1453504D03*
X638228Y1457835D03*
X629567Y1468859D03*
X638228Y1473189D03*
X629567Y1484213D03*
X638228Y1488544D03*
X629567Y1499567D03*
X638228Y1503898D03*
X629567Y1514922D03*
X638228Y1519252D03*
X629567Y1555867D03*
X638228Y1560197D03*
X629567Y1571221D03*
X638228Y1575552D03*
X629567Y1586575D03*
X638228Y1590906D03*
X629567Y1601930D03*
X638228Y1606260D03*
X629567Y1617284D03*
X638228Y1621615D03*
X646890Y1453504D03*
Y1468859D03*
Y1484213D03*
Y1499567D03*
Y1514922D03*
Y1555867D03*
Y1571221D03*
Y1586575D03*
Y1601930D03*
Y1617284D03*
X664213Y1453504D03*
X655551Y1457835D03*
X664213Y1468859D03*
X655551Y1473189D03*
X664213Y1484213D03*
X655551Y1488544D03*
X664213Y1499567D03*
Y1514922D03*
X655551Y1503898D03*
Y1519252D03*
X664213Y1555867D03*
X655551Y1560197D03*
X664213Y1571221D03*
X655551Y1575552D03*
X664213Y1586575D03*
X655551Y1590906D03*
X664213Y1601930D03*
X655551Y1606260D03*
X664213Y1617284D03*
X655551Y1621615D03*
X681535Y1453504D03*
X672874Y1457835D03*
X681535Y1468859D03*
X672874Y1473189D03*
X681535Y1484213D03*
X672874Y1488544D03*
X681535Y1499567D03*
Y1514922D03*
X672874Y1503898D03*
Y1519252D03*
X681535Y1555867D03*
X672874Y1560197D03*
X681535Y1571221D03*
X672874Y1575552D03*
X681535Y1586575D03*
X672874Y1590906D03*
X681535Y1601930D03*
X672874Y1606260D03*
X681535Y1617284D03*
X672874Y1621615D03*
X698858Y1453504D03*
X690197Y1457835D03*
X698858Y1468859D03*
X690197Y1473189D03*
X698858Y1484213D03*
X690197Y1488544D03*
X698858Y1499567D03*
Y1514922D03*
X690197Y1503898D03*
Y1519252D03*
X698858Y1555867D03*
X690197Y1560197D03*
X698858Y1571221D03*
X690197Y1575552D03*
X698858Y1586575D03*
X690197Y1590906D03*
X698858Y1601930D03*
X690197Y1606260D03*
X698858Y1617284D03*
X690197Y1621615D03*
X707520Y1457835D03*
Y1473189D03*
Y1488544D03*
Y1503898D03*
Y1519252D03*
Y1560197D03*
Y1575552D03*
Y1590906D03*
Y1606260D03*
Y1621615D03*
X1131850Y1453504D03*
X1140511Y1457835D03*
X1131850Y1468859D03*
X1140511Y1473189D03*
X1131850Y1484213D03*
X1140511Y1488544D03*
X1131850Y1499567D03*
X1140511Y1503898D03*
X1131850Y1514922D03*
X1140511Y1519252D03*
X1131850Y1555867D03*
X1140511Y1560197D03*
X1131850Y1571221D03*
X1140511Y1575552D03*
X1131850Y1586575D03*
X1140511Y1590906D03*
X1131850Y1601930D03*
X1140511Y1606260D03*
X1131850Y1617284D03*
X1140511Y1621615D03*
X1149173Y1453504D03*
X1157834Y1457835D03*
X1149173Y1468859D03*
X1157834Y1473189D03*
X1149173Y1484213D03*
X1157834Y1488544D03*
X1149173Y1499567D03*
X1157834Y1503898D03*
X1149173Y1514922D03*
X1157834Y1519252D03*
X1149173Y1555867D03*
X1157834Y1560197D03*
X1149173Y1571221D03*
X1157834Y1575552D03*
X1149173Y1586575D03*
X1157834Y1590906D03*
X1149173Y1601930D03*
X1157834Y1606260D03*
X1149173Y1617284D03*
X1157834Y1621615D03*
X1166496Y1453504D03*
Y1468859D03*
Y1484213D03*
Y1499567D03*
Y1514922D03*
Y1555867D03*
Y1571221D03*
Y1586575D03*
Y1601930D03*
Y1617284D03*
X1183818Y1453504D03*
X1175157Y1457835D03*
X1183818Y1468859D03*
X1175157Y1473189D03*
X1183818Y1484213D03*
X1175157Y1488544D03*
X1183818Y1499567D03*
Y1514922D03*
X1175157Y1503898D03*
Y1519252D03*
X1183818Y1555867D03*
X1175157Y1560197D03*
X1183818Y1571221D03*
X1175157Y1575552D03*
X1183818Y1586575D03*
X1175157Y1590906D03*
X1183818Y1601930D03*
X1175157Y1606260D03*
X1183818Y1617284D03*
X1175157Y1621615D03*
X1201141Y1453504D03*
X1192480Y1457835D03*
X1201141Y1468859D03*
X1192480Y1473189D03*
X1201141Y1484213D03*
X1192480Y1488544D03*
X1201141Y1499567D03*
Y1514922D03*
X1192480Y1503898D03*
Y1519252D03*
X1201141Y1555867D03*
X1192480Y1560197D03*
X1201141Y1571221D03*
X1192480Y1575552D03*
X1201141Y1586575D03*
X1192480Y1590906D03*
X1201141Y1601930D03*
X1192480Y1606260D03*
X1201141Y1617284D03*
X1192480Y1621615D03*
X1209803Y1457835D03*
Y1473189D03*
Y1488544D03*
Y1503898D03*
Y1519252D03*
Y1560197D03*
Y1575552D03*
Y1590906D03*
Y1606260D03*
Y1621615D03*
X1305079Y1453504D03*
X1313740Y1457835D03*
X1305079Y1468859D03*
X1313740Y1473189D03*
X1305079Y1484213D03*
X1313740Y1488544D03*
X1305079Y1499567D03*
X1313740Y1503898D03*
X1305079Y1514922D03*
X1313740Y1519252D03*
X1305079Y1555867D03*
X1313740Y1560197D03*
X1305079Y1571221D03*
X1313740Y1575552D03*
X1305079Y1586575D03*
X1313740Y1590906D03*
X1305079Y1601930D03*
X1313740Y1606260D03*
X1305079Y1617284D03*
X1313740Y1621615D03*
X1322402Y1453504D03*
X1331063Y1457835D03*
X1322402Y1468859D03*
X1331063Y1473189D03*
X1322402Y1484213D03*
X1331063Y1488544D03*
X1322402Y1499567D03*
X1331063Y1503898D03*
X1322402Y1514922D03*
X1331063Y1519252D03*
X1322402Y1555867D03*
X1331063Y1560197D03*
X1322402Y1571221D03*
X1331063Y1575552D03*
X1322402Y1586575D03*
X1331063Y1590906D03*
X1322402Y1601930D03*
X1331063Y1606260D03*
X1322402Y1617284D03*
X1331063Y1621615D03*
X1339725Y1453504D03*
X1348386Y1457835D03*
X1339725Y1468859D03*
X1348386Y1473189D03*
X1339725Y1484213D03*
X1348386Y1488544D03*
X1339725Y1499567D03*
X1348386Y1503898D03*
X1339725Y1514922D03*
X1348386Y1519252D03*
X1339725Y1555867D03*
X1348386Y1560197D03*
X1339725Y1571221D03*
X1348386Y1575552D03*
X1339725Y1586575D03*
X1348386Y1590906D03*
X1339725Y1601930D03*
X1348386Y1606260D03*
X1339725Y1617284D03*
X1348386Y1621615D03*
X1357047Y1453504D03*
X1365709Y1457835D03*
X1357047Y1468859D03*
X1365709Y1473189D03*
X1357047Y1484213D03*
X1365709Y1488544D03*
X1357047Y1499567D03*
X1365709Y1503898D03*
X1357047Y1514922D03*
X1365709Y1519252D03*
X1357047Y1555867D03*
X1365709Y1560197D03*
X1357047Y1571221D03*
X1365709Y1575552D03*
X1357047Y1586575D03*
X1365709Y1590906D03*
X1357047Y1601930D03*
X1365709Y1606260D03*
X1357047Y1617284D03*
X1365709Y1621615D03*
X1374370Y1453504D03*
X1383032Y1457835D03*
X1374370Y1468859D03*
X1383032Y1473189D03*
X1374370Y1484213D03*
X1383032Y1488544D03*
X1374370Y1499567D03*
X1383032Y1503898D03*
X1374370Y1514922D03*
X1383032Y1519252D03*
X1374370Y1555867D03*
X1383032Y1560197D03*
X1374370Y1571221D03*
X1383032Y1575552D03*
X1374370Y1586575D03*
X1383032Y1590906D03*
X1374370Y1601930D03*
X1383032Y1606260D03*
X1374370Y1617284D03*
X1383032Y1621615D03*
X1478307Y1453504D03*
Y1468859D03*
Y1484213D03*
Y1499567D03*
Y1514922D03*
Y1555867D03*
Y1571221D03*
Y1586575D03*
Y1601930D03*
Y1617284D03*
X1495630Y1453504D03*
X1486968Y1457835D03*
X1495630Y1468859D03*
X1486968Y1473189D03*
X1495630Y1484213D03*
X1486968Y1488544D03*
X1495630Y1499567D03*
Y1514922D03*
X1486968Y1503898D03*
Y1519252D03*
X1495630Y1555867D03*
X1486968Y1560197D03*
X1495630Y1571221D03*
X1486968Y1575552D03*
X1495630Y1586575D03*
X1486968Y1590906D03*
X1495630Y1601930D03*
X1486968Y1606260D03*
X1495630Y1617284D03*
X1486968Y1621615D03*
X1512953Y1453504D03*
X1504291Y1457835D03*
X1512953Y1468859D03*
X1504291Y1473189D03*
X1512953Y1484213D03*
X1504291Y1488544D03*
X1512953Y1499567D03*
Y1514922D03*
X1504291Y1503898D03*
Y1519252D03*
X1512953Y1555867D03*
X1504291Y1560197D03*
X1512953Y1571221D03*
X1504291Y1575552D03*
X1512953Y1586575D03*
X1504291Y1590906D03*
X1512953Y1601930D03*
X1504291Y1606260D03*
X1512953Y1617284D03*
X1504291Y1621615D03*
X1530275Y1453504D03*
X1521614Y1457835D03*
X1530275Y1468859D03*
X1521614Y1473189D03*
X1530275Y1484213D03*
X1521614Y1488544D03*
X1530275Y1499567D03*
Y1514922D03*
X1521614Y1503898D03*
Y1519252D03*
X1530275Y1555867D03*
X1521614Y1560197D03*
X1530275Y1571221D03*
X1521614Y1575552D03*
X1530275Y1586575D03*
X1521614Y1590906D03*
X1530275Y1601930D03*
X1521614Y1606260D03*
X1530275Y1617284D03*
X1521614Y1621615D03*
X1547598Y1453504D03*
X1538937Y1457835D03*
X1547598Y1468859D03*
X1538937Y1473189D03*
X1547598Y1484213D03*
X1538937Y1488544D03*
X1547598Y1499567D03*
Y1514922D03*
X1538937Y1503898D03*
Y1519252D03*
X1547598Y1555867D03*
X1538937Y1560197D03*
X1547598Y1571221D03*
X1538937Y1575552D03*
X1547598Y1586575D03*
X1538937Y1590906D03*
X1547598Y1601930D03*
X1538937Y1606260D03*
X1547598Y1617284D03*
X1538937Y1621615D03*
X1556260Y1457835D03*
Y1473189D03*
Y1488544D03*
Y1503898D03*
Y1519252D03*
Y1560197D03*
Y1575552D03*
Y1590906D03*
Y1606260D03*
Y1621615D03*
X1651535Y1453504D03*
X1660196Y1457835D03*
X1651535Y1468859D03*
X1660196Y1473189D03*
X1651535Y1484213D03*
X1660196Y1488544D03*
X1651535Y1499567D03*
X1660196Y1503898D03*
X1651535Y1514922D03*
X1660196Y1519252D03*
X1651535Y1555867D03*
X1660196Y1560197D03*
X1651535Y1571221D03*
X1660196Y1575552D03*
X1651535Y1586575D03*
X1660196Y1590906D03*
X1651535Y1601930D03*
X1660196Y1606260D03*
X1651535Y1617284D03*
X1660196Y1621615D03*
X1668858Y1453504D03*
X1677519Y1457835D03*
X1668858Y1468859D03*
X1677519Y1473189D03*
X1668858Y1484213D03*
X1677519Y1488544D03*
X1668858Y1499567D03*
X1677519Y1503898D03*
X1668858Y1514922D03*
X1677519Y1519252D03*
X1668858Y1555867D03*
X1677519Y1560197D03*
X1668858Y1571221D03*
X1677519Y1575552D03*
X1668858Y1586575D03*
X1677519Y1590906D03*
X1668858Y1601930D03*
X1677519Y1606260D03*
X1668858Y1617284D03*
X1677519Y1621615D03*
X1686181Y1453504D03*
Y1468859D03*
Y1484213D03*
Y1499567D03*
Y1514922D03*
Y1555867D03*
Y1571221D03*
Y1586575D03*
Y1601930D03*
Y1617284D03*
X1703503Y1453504D03*
X1694842Y1457835D03*
X1703503Y1468859D03*
X1694842Y1473189D03*
X1703503Y1484213D03*
X1694842Y1488544D03*
X1703503Y1499567D03*
Y1514922D03*
X1694842Y1503898D03*
Y1519252D03*
X1703503Y1555867D03*
X1694842Y1560197D03*
X1703503Y1571221D03*
X1694842Y1575552D03*
X1703503Y1586575D03*
X1694842Y1590906D03*
X1703503Y1601930D03*
X1694842Y1606260D03*
X1703503Y1617284D03*
X1694842Y1621615D03*
X1720826Y1453504D03*
X1712165Y1457835D03*
X1720826Y1468859D03*
X1712165Y1473189D03*
X1720826Y1484213D03*
X1712165Y1488544D03*
X1720826Y1499567D03*
Y1514922D03*
X1712165Y1503898D03*
Y1519252D03*
X1720826Y1555867D03*
X1712165Y1560197D03*
X1720826Y1571221D03*
X1712165Y1575552D03*
X1720826Y1586575D03*
X1712165Y1590906D03*
X1720826Y1601930D03*
X1712165Y1606260D03*
X1720826Y1617284D03*
X1712165Y1621615D03*
X1729488Y1457835D03*
Y1473189D03*
Y1488544D03*
Y1503898D03*
Y1519252D03*
Y1560197D03*
Y1575552D03*
Y1590906D03*
Y1606260D03*
Y1621615D03*
G54D119*
G01X138813Y1167575D02*
X138026D01*
X129903Y1159452D01*
X123351D01*
X117794Y1153895D01*
Y1152305D01*
X118334Y1151765D01*
Y1150175D01*
X117794Y1149635D01*
Y1148045D01*
X118334Y1147505D01*
Y1145915D01*
X117794Y1145375D01*
Y1143785D01*
X118334Y1143245D01*
Y1141655D01*
X117794Y1141115D01*
Y1139525D01*
X118334Y1138985D01*
Y1137395D01*
X117794Y1136855D01*
Y1135265D01*
X118334Y1134725D01*
Y1133135D01*
X117794Y1132595D01*
Y1131005D01*
X118334Y1130465D01*
Y1128875D01*
X117794Y1128335D01*
Y1126745D01*
X118334Y1126205D01*
Y1124615D01*
X117794Y1124075D01*
Y1101843D01*
X94377Y1078426D01*
Y1052990D01*
X94267Y1052724D01*
Y1052725D01*
X82900Y1025280D01*
Y990941D01*
X198091Y875750D01*
X297421D01*
X395321Y777850D01*
X423683D01*
X455793Y791150D01*
X465060D01*
X501723Y775967D01*
X501806D01*
X501865Y775908D01*
X501988Y775857D01*
X503931Y773913D01*
Y771421D01*
X504895Y770457D01*
G01X138813Y1169025D02*
X137425D01*
X129302Y1160902D01*
X122750D01*
X116344Y1154496D01*
Y1102444D01*
X92927Y1079027D01*
Y1053279D01*
X81450Y1025569D01*
Y990340D01*
X197490Y874300D01*
X296820D01*
X394720Y776400D01*
X423972D01*
X456082Y789700D01*
X464771D01*
X501166Y774628D01*
X502481Y773312D01*
Y771443D01*
X501495Y770457D01*
G01X139113Y1181025D02*
X137875D01*
X131250Y1174400D01*
X124168D01*
X119152Y1169384D01*
X101783D01*
X97831Y1165432D01*
Y1091550D01*
X87298Y1081017D01*
Y1053709D01*
X76250Y1027037D01*
Y988016D01*
X195466Y868800D01*
X277200D01*
X373500Y772500D01*
X380300D01*
X387548Y765252D01*
X423888D01*
X426690Y762450D01*
X430279D01*
X451129Y741600D01*
X485200D01*
X492600Y749000D01*
X540759D01*
X554409Y735350D01*
X708770D01*
X819776Y624344D01*
X900905D01*
X901653Y623596D01*
Y622513D01*
X900676Y621536D01*
G01X139113Y1179575D02*
X138476D01*
X131851Y1172950D01*
X124769D01*
X119753Y1167934D01*
X118173D01*
X117633Y1167394D01*
X116053D01*
X115513Y1167934D01*
X113933D01*
X113393Y1167394D01*
X111813D01*
X111273Y1167934D01*
X102384D01*
X99281Y1164831D01*
Y1163251D01*
X99821Y1162711D01*
Y1161131D01*
X99281Y1160591D01*
Y1159011D01*
X99821Y1158471D01*
Y1156891D01*
X99281Y1156351D01*
Y1154771D01*
X99821Y1154231D01*
Y1152651D01*
X99281Y1152111D01*
Y1150531D01*
X99821Y1149991D01*
Y1148411D01*
X99281Y1147871D01*
Y1146281D01*
X99821Y1145741D01*
Y1144151D01*
X99281Y1143611D01*
Y1142021D01*
X99821Y1141481D01*
Y1139891D01*
X99281Y1139351D01*
Y1090949D01*
X88748Y1080416D01*
Y1053420D01*
X77700Y1026748D01*
Y988617D01*
X196067Y870250D01*
X277801D01*
X374101Y773950D01*
X380901D01*
X388149Y766702D01*
X424489D01*
X427291Y763900D01*
X430880D01*
X451730Y743050D01*
X484599D01*
X491999Y750450D01*
X541360D01*
X555010Y736800D01*
X709371D01*
X820377Y625794D01*
X901506D01*
X903103Y624197D01*
Y622509D01*
X904076Y621536D01*
G01X414735Y1282489D02*
X416000Y1281224D01*
Y1279768D01*
X415132Y1278900D01*
X409018D01*
X374811Y1293068D01*
X220455D01*
X145489Y1262016D01*
X102950Y1219476D01*
Y1201150D01*
X119325Y1184775D01*
X139113D01*
G01X418735Y1282489D02*
X417450Y1281204D01*
Y1279167D01*
X415733Y1277450D01*
X408729D01*
X374522Y1291618D01*
X220744D01*
X146311Y1260786D01*
X104400Y1218875D01*
Y1201751D01*
X119926Y1186225D01*
X128205D01*
X128745Y1186765D01*
X130335D01*
X130875Y1186225D01*
X132465D01*
X133005Y1186765D01*
X134595D01*
X135135Y1186225D01*
X139113D01*
G01X385403Y1388722D02*
X384081Y1387400D01*
X381835D01*
X379596Y1385161D01*
Y1330507D01*
X376150Y1327061D01*
Y1315143D01*
X374821Y1313814D01*
X371152D01*
X370202Y1314764D01*
G01X385403Y1384722D02*
X384175Y1385950D01*
X382436D01*
X381046Y1384560D01*
Y1329906D01*
X377600Y1326460D01*
Y1314542D01*
X375422Y1312364D01*
X371202D01*
X370202Y1311364D01*
G01X392736Y1299275D02*
X391460Y1300551D01*
X390751D01*
X388653Y1298453D01*
X386091D01*
X385091Y1297453D01*
G01X392736Y1303275D02*
X391462Y1302001D01*
X390150D01*
X388052Y1299903D01*
X386041D01*
X385091Y1300853D01*
G01X924650Y1327819D02*
X923700Y1326869D01*
X884548D01*
X871262Y1313583D01*
X479768D01*
X450933Y1342418D01*
X399667D01*
X381677Y1324428D01*
Y1313950D01*
X383027Y1312600D01*
X388269D01*
X389580Y1311289D01*
G01Y1315289D02*
X388341Y1314050D01*
X383628D01*
X383127Y1314551D01*
Y1317038D01*
X383777Y1317688D01*
Y1319188D01*
X383127Y1319838D01*
Y1323827D01*
X391229Y1331929D01*
X391993D01*
X393118Y1333055D01*
Y1333818D01*
X394242Y1334942D01*
X395006D01*
X396131Y1336068D01*
Y1336831D01*
X397255Y1337955D01*
X398019D01*
X399144Y1339081D01*
Y1339844D01*
X400268Y1340968D01*
X401983D01*
X402683Y1340268D01*
X404183D01*
X404883Y1340968D01*
X406383D01*
X407083Y1340268D01*
X408583D01*
X409283Y1340968D01*
X410783D01*
X411483Y1340268D01*
X412983D01*
X413683Y1340968D01*
X415183D01*
X415883Y1340268D01*
X417383D01*
X418083Y1340968D01*
X450332D01*
X451456Y1339844D01*
Y1339081D01*
X452581Y1337955D01*
X453345D01*
X479167Y1312133D01*
X871863D01*
X885149Y1325419D01*
X923650D01*
X924650Y1324419D01*
G01X392730Y1311289D02*
X393991Y1312550D01*
X394751D01*
X397137Y1310164D01*
X402529D01*
X406416Y1308554D01*
X408159D01*
X408443Y1308270D01*
X409211D01*
G01X392730Y1315289D02*
X394019Y1314000D01*
X395352D01*
X397738Y1311614D01*
X402818D01*
X406705Y1310004D01*
X408105D01*
X408339Y1310238D01*
X409211D01*
G01X388553Y1388722D02*
X389711Y1387564D01*
X397833D01*
X398118Y1387849D01*
X398881D01*
G01X388553Y1384722D02*
X389945Y1386114D01*
X397855D01*
X398089Y1385880D01*
X398881D01*
G01X395886Y1303275D02*
X397161Y1302000D01*
X403614D01*
X405662Y1304048D01*
X408137D01*
X408422Y1304333D01*
X409211D01*
G01X395886Y1299275D02*
X397161Y1300550D01*
X404215D01*
X406263Y1302598D01*
X408100D01*
X408150Y1302648D01*
X408163D01*
X408447Y1302364D01*
X409211D01*
G01X406189Y1407571D02*
X404914Y1406296D01*
Y1399893D01*
X406987Y1397820D01*
Y1395295D01*
X407247Y1395035D01*
Y1394246D01*
G01X402189Y1407571D02*
X403464Y1406296D01*
Y1399287D01*
X405537Y1397214D01*
Y1395269D01*
X405278Y1395010D01*
Y1394246D01*
G01X402189Y1410721D02*
X403500Y1412032D01*
Y1416264D01*
X402489Y1417275D01*
G01X406189Y1410721D02*
X404950Y1411960D01*
Y1416336D01*
X405889Y1417275D01*
G01X414735Y1285639D02*
X416035Y1286939D01*
Y1290464D01*
X415843Y1290656D01*
Y1294855D01*
X415893Y1294905D01*
Y1294919D01*
X415608Y1295204D01*
Y1295967D01*
G01X418735Y1285639D02*
X417485Y1286889D01*
Y1291065D01*
X417293Y1291257D01*
Y1294891D01*
X417577Y1295175D01*
Y1295967D01*
G01X414431Y1326783D02*
X415700Y1325514D01*
Y1321007D01*
X415850Y1320857D01*
Y1315612D01*
X415608Y1315370D01*
Y1314667D01*
G01X418431Y1326783D02*
X417150Y1325502D01*
Y1321608D01*
X417300Y1321458D01*
Y1315682D01*
X417577Y1315405D01*
Y1314667D01*
G01X1512196Y1184761D02*
X1504066D01*
X1502758Y1186069D01*
X1501994D01*
X1500869Y1187194D01*
Y1187958D01*
X1499745Y1189082D01*
X1498982D01*
X1497856Y1190207D01*
Y1190971D01*
X1496732Y1192095D01*
X1495969D01*
X1494843Y1193220D01*
Y1193984D01*
X1493719Y1195108D01*
X1492956D01*
X1491830Y1196233D01*
Y1196997D01*
X1490706Y1198121D01*
X1489943D01*
X1488817Y1199246D01*
Y1200010D01*
X1474834Y1213993D01*
Y1232915D01*
X1466414Y1241335D01*
Y1268639D01*
X1460792Y1274261D01*
X1460028D01*
X1458903Y1275387D01*
Y1276150D01*
X1457779Y1277274D01*
X1457015D01*
X1455890Y1278400D01*
Y1279163D01*
X1454766Y1280287D01*
X1454002D01*
X1452877Y1281413D01*
Y1282176D01*
X1451753Y1283300D01*
X1421500D01*
X1415950Y1288850D01*
X1405935D01*
X1402985Y1291800D01*
X1385699D01*
X1375699Y1301800D01*
X995261D01*
X992361Y1298900D01*
X932115D01*
X910668Y1320347D01*
X887338D01*
X873036Y1306045D01*
X476540D01*
X445685Y1336900D01*
X421132D01*
X417150Y1332918D01*
Y1331214D01*
X418431Y1329933D01*
G01X1512196Y1186211D02*
X1504667D01*
X1476284Y1214594D01*
Y1233516D01*
X1467864Y1241936D01*
Y1269240D01*
X1452354Y1284750D01*
X1422101D01*
X1416551Y1290300D01*
X1406536D01*
X1403586Y1293250D01*
X1386300D01*
X1376300Y1303250D01*
X994660D01*
X991760Y1300350D01*
X932716D01*
X911269Y1321797D01*
X886737D01*
X872435Y1307495D01*
X477120D01*
Y1307516D01*
X446286Y1338350D01*
X420531D01*
X415700Y1333519D01*
Y1331202D01*
X414431Y1329933D01*
G01X417581Y1385880D02*
X418281D01*
X418540Y1386139D01*
X428584D01*
X429697Y1385026D01*
G01X411184Y1394246D02*
Y1395014D01*
X411443Y1395273D01*
Y1396803D01*
X413028Y1400629D01*
Y1406070D01*
X415478Y1408520D01*
Y1409452D01*
X414203Y1410727D01*
G01X413152Y1394246D02*
Y1395050D01*
X412893Y1395309D01*
Y1396511D01*
X414478Y1400338D01*
Y1405468D01*
X416928Y1407918D01*
Y1409452D01*
X418203Y1410727D01*
G01X429697Y1389026D02*
X428260Y1387589D01*
X418512D01*
X418252Y1387849D01*
X417581D01*
G01X1009333Y1346693D02*
X1008333Y1345693D01*
X1003037D01*
X1000145Y1342801D01*
X886601D01*
X866800Y1323000D01*
X784380D01*
X766145Y1341235D01*
X656124D01*
X647684Y1344732D01*
X633635Y1354120D01*
Y1354119D01*
X573913Y1403122D01*
X448071D01*
X427843Y1423350D01*
X418700D01*
X415453Y1420103D01*
Y1415127D01*
X414203Y1413877D01*
G01X418203D02*
X416903Y1415177D01*
Y1419502D01*
X419301Y1421900D01*
X427242D01*
X447470Y1401672D01*
X573394D01*
X574623Y1400664D01*
X574698Y1399904D01*
X575928Y1398894D01*
X576688Y1398969D01*
X577917Y1397961D01*
X577992Y1397201D01*
X579222Y1396191D01*
X579982Y1396266D01*
X581211Y1395258D01*
X581286Y1394498D01*
X582516Y1393488D01*
X583276Y1393563D01*
X584505Y1392555D01*
X584580Y1391795D01*
X585810Y1390785D01*
X586570Y1390860D01*
X587799Y1389852D01*
X587874Y1389092D01*
X589104Y1388082D01*
X589864Y1388157D01*
X632714Y1352998D01*
X632715D01*
X632770Y1352953D01*
X646997Y1343447D01*
X655835Y1339785D01*
X765544D01*
X783779Y1321550D01*
X867401D01*
X887202Y1341351D01*
X1000746D01*
X1003638Y1344243D01*
X1008383D01*
X1009333Y1343293D01*
G01X1443660Y1310698D02*
X1442700Y1311658D01*
Y1327001D01*
X1438137Y1331564D01*
X1415232Y1341050D01*
X1408519D01*
X1393080Y1334655D01*
X1047822D01*
X1042275Y1338361D01*
X888124D01*
X868713Y1318950D01*
X781321D01*
X763118Y1337153D01*
X655073D01*
X606610Y1357228D01*
X573128Y1390710D01*
X437762D01*
X434852Y1387800D01*
X434073D01*
X432847Y1389026D01*
G01X1440260Y1310698D02*
X1441250Y1311688D01*
Y1326400D01*
X1437315Y1330334D01*
X1414943Y1339600D01*
X1408808D01*
X1393369Y1333205D01*
X1047382D01*
X1041835Y1336911D01*
X888725D01*
X869314Y1317500D01*
X780720D01*
X762517Y1335703D01*
X654784D01*
X605788Y1355998D01*
X572527Y1389260D01*
X466270D01*
X465730Y1388720D01*
X464150D01*
X463610Y1389260D01*
X462030D01*
X461490Y1388720D01*
X459910D01*
X459370Y1389260D01*
X438363D01*
X435453Y1386350D01*
X434171D01*
X432847Y1385026D01*
G01X595430Y1180704D02*
X593634D01*
X587430Y1174500D01*
X580677D01*
X571746Y1165569D01*
Y1100946D01*
X564775Y1093975D01*
X563575D01*
X532934Y1063334D01*
Y955537D01*
X563195Y925276D01*
X614324D01*
X724398Y815202D01*
Y814001D01*
X799132Y739267D01*
Y695727D01*
X859358Y635501D01*
X900148D01*
X910458Y625191D01*
Y622566D01*
X909508Y621616D01*
G01X595430Y1179254D02*
X594235D01*
X593118Y1178137D01*
Y1177374D01*
X592000Y1176255D01*
X591236D01*
X588031Y1173050D01*
X586451D01*
X585911Y1172510D01*
X584331D01*
X583791Y1173050D01*
X581278D01*
X580161Y1171933D01*
Y1171170D01*
X579043Y1170051D01*
X578279D01*
X577162Y1168934D01*
Y1168171D01*
X576044Y1167052D01*
X575280D01*
X573196Y1164968D01*
Y1163388D01*
X573736Y1162848D01*
Y1161268D01*
X573196Y1160728D01*
Y1100345D01*
X572079Y1099228D01*
Y1098465D01*
X570961Y1097346D01*
X570197D01*
X569080Y1096229D01*
Y1095466D01*
X567962Y1094347D01*
X567198D01*
X565376Y1092525D01*
X564176D01*
X534384Y1062733D01*
Y956138D01*
X563796Y926726D01*
X614925D01*
X725848Y815803D01*
Y814602D01*
X800582Y739868D01*
Y696328D01*
X859959Y636951D01*
X900749D01*
X908909Y628791D01*
X909673D01*
X910791Y627672D01*
Y626909D01*
X911908Y625792D01*
Y622616D01*
X912908Y621616D01*
G01X598013Y1168125D02*
X596625D01*
X590321Y1161821D01*
X581847D01*
X577064Y1157038D01*
Y1097764D01*
X567251Y1087951D01*
X564999D01*
X538365Y1061317D01*
Y993141D01*
X562304Y969202D01*
X583399D01*
X606733Y945868D01*
Y942137D01*
X605733Y941137D01*
G01X598013Y1166675D02*
X597226D01*
X590922Y1160371D01*
X582448D01*
X578514Y1156437D01*
Y1146475D01*
X579054Y1145935D01*
Y1144345D01*
X578514Y1143805D01*
Y1097163D01*
X567852Y1086501D01*
X565600D01*
X539815Y1060716D01*
Y993742D01*
X562905Y970652D01*
X584000D01*
X608183Y946469D01*
Y942087D01*
X609133Y941137D01*
G01X917163Y1762566D02*
Y1758700D01*
X917563Y1758300D01*
X927195D01*
X928449Y1757046D01*
Y1749602D01*
X928957Y1749094D01*
X934459D01*
X934859Y1749494D01*
Y1760395D01*
X936079Y1761615D01*
X942849D01*
X944069Y1760395D01*
Y1749494D01*
X944469Y1749094D01*
X950069D01*
X950479Y1749504D01*
Y1760395D01*
X951699Y1761615D01*
X958469D01*
X959689Y1760395D01*
Y1749494D01*
X960089Y1749094D01*
X965689D01*
X966099Y1749504D01*
Y1760395D01*
X967319Y1761615D01*
X974089D01*
X975309Y1760395D01*
Y1749494D01*
X975709Y1749094D01*
X981309D01*
X981719Y1749504D01*
Y1760395D01*
X982939Y1761615D01*
X989709D01*
X990929Y1760395D01*
Y1749622D01*
X991457Y1749094D01*
X996939D01*
X997339Y1749494D01*
Y1760395D01*
X998559Y1761615D01*
X1005329D01*
X1006549Y1760395D01*
Y1749602D01*
X1007057Y1749094D01*
X1012559D01*
X1012959Y1749494D01*
Y1760395D01*
X1014179Y1761615D01*
X1020949D01*
X1022169Y1760395D01*
Y1749494D01*
X1022569Y1749094D01*
X1028169D01*
X1028579Y1749504D01*
Y1760395D01*
X1029799Y1761615D01*
X1036569D01*
X1037789Y1760395D01*
Y1749562D01*
X1038257Y1749094D01*
X1043799D01*
X1044199Y1749494D01*
Y1760395D01*
X1045419Y1761615D01*
X1052189D01*
X1053409Y1760395D01*
Y1749642D01*
X1053957Y1749094D01*
X1059419D01*
X1059819Y1749494D01*
Y1760395D01*
X1061039Y1761615D01*
X1067809D01*
X1069029Y1760395D01*
Y1749522D01*
X1069457Y1749094D01*
X1075039D01*
X1075439Y1749494D01*
Y1760395D01*
X1076659Y1761615D01*
X1083429D01*
X1084649Y1760395D01*
Y1749494D01*
X1085049Y1749094D01*
X1090649D01*
X1091059Y1749504D01*
Y1760395D01*
X1092279Y1761615D01*
X1099049D01*
X1100269Y1760395D01*
Y1749582D01*
X1100757Y1749094D01*
X1106279D01*
X1106679Y1749494D01*
Y1760395D01*
X1107899Y1761615D01*
X1114669D01*
X1115889Y1760395D01*
Y1749494D01*
X1116289Y1749094D01*
X1121899D01*
X1122299Y1749494D01*
Y1760395D01*
X1123519Y1761615D01*
X1130289D01*
X1131509Y1760395D01*
Y1749494D01*
X1131909Y1749094D01*
X1137443D01*
X1137919Y1749570D01*
Y1760395D01*
X1139139Y1761615D01*
X1145909D01*
X1147129Y1760395D01*
Y1749565D01*
X1147550Y1749144D01*
X1152994D01*
X1153489Y1749639D01*
Y1756989D01*
X1154766Y1758266D01*
X1169019D01*
X1169263Y1758510D01*
Y1762566D01*
G01X917163Y1752566D02*
Y1756466D01*
X917547Y1756850D01*
X926594D01*
X926999Y1756445D01*
Y1749001D01*
X928356Y1747644D01*
X935060D01*
X936309Y1748893D01*
Y1759794D01*
X936680Y1760165D01*
X942248D01*
X942619Y1759794D01*
Y1748893D01*
X943868Y1747644D01*
X950680D01*
X951929Y1748893D01*
Y1759794D01*
X952300Y1760165D01*
X957868D01*
X958239Y1759794D01*
Y1748893D01*
X959488Y1747644D01*
X966300D01*
X967549Y1748893D01*
Y1759794D01*
X967920Y1760165D01*
X973488D01*
X973859Y1759794D01*
Y1748893D01*
X975108Y1747644D01*
X981920D01*
X983169Y1748893D01*
Y1759794D01*
X983540Y1760165D01*
X989108D01*
X989479Y1759794D01*
Y1749021D01*
X990856Y1747644D01*
X997540D01*
X998789Y1748893D01*
Y1759794D01*
X999160Y1760165D01*
X1004728D01*
X1005099Y1759794D01*
Y1749001D01*
X1006456Y1747644D01*
X1013160D01*
X1014409Y1748893D01*
Y1759794D01*
X1014780Y1760165D01*
X1020348D01*
X1020719Y1759794D01*
Y1748893D01*
X1021968Y1747644D01*
X1028780D01*
X1030029Y1748893D01*
Y1759794D01*
X1030400Y1760165D01*
X1035968D01*
X1036339Y1759794D01*
Y1748961D01*
X1037656Y1747644D01*
X1044400D01*
X1045649Y1748893D01*
Y1759794D01*
X1046020Y1760165D01*
X1051588D01*
X1051959Y1759794D01*
Y1749041D01*
X1053356Y1747644D01*
X1060020D01*
X1061269Y1748893D01*
Y1759794D01*
X1061640Y1760165D01*
X1067208D01*
X1067579Y1759794D01*
Y1748921D01*
X1068856Y1747644D01*
X1075640D01*
X1076889Y1748893D01*
Y1759794D01*
X1077260Y1760165D01*
X1082828D01*
X1083199Y1759794D01*
Y1748893D01*
X1084448Y1747644D01*
X1091260D01*
X1092509Y1748893D01*
Y1759794D01*
X1092880Y1760165D01*
X1098448D01*
X1098819Y1759794D01*
Y1748981D01*
X1100156Y1747644D01*
X1106880D01*
X1108129Y1748893D01*
Y1759794D01*
X1108500Y1760165D01*
X1114068D01*
X1114439Y1759794D01*
Y1748893D01*
X1115688Y1747644D01*
X1122500D01*
X1123749Y1748893D01*
Y1759794D01*
X1124120Y1760165D01*
X1129688D01*
X1130059Y1759794D01*
Y1748893D01*
X1131308Y1747644D01*
X1138044D01*
X1139369Y1748969D01*
Y1759794D01*
X1139740Y1760165D01*
X1145308D01*
X1145679Y1759794D01*
Y1748964D01*
X1146949Y1747694D01*
X1153595D01*
X1154939Y1749038D01*
Y1756388D01*
X1155367Y1756816D01*
X1168993D01*
X1169263Y1756546D01*
Y1752566D01*
G01X933725Y585936D02*
X934725Y586936D01*
X936136D01*
X941750Y592550D01*
Y615501D01*
X939353Y617898D01*
Y633310D01*
X956843Y650800D01*
X969427D01*
X1016195Y697568D01*
Y713812D01*
X1024085Y721701D01*
X1032819Y725319D01*
X1143250Y835750D01*
X1187555D01*
X1239341Y887536D01*
Y924799D01*
X1270342Y955800D01*
X1388662D01*
X1390162Y954300D01*
X1425517D01*
X1445300Y974083D01*
Y1059799D01*
X1482751Y1097250D01*
X1484250D01*
X1487350Y1100350D01*
Y1160703D01*
X1487890Y1161243D01*
Y1162823D01*
X1487350Y1163363D01*
Y1164943D01*
X1489409Y1167002D01*
X1490173D01*
X1491291Y1168121D01*
Y1168884D01*
X1492408Y1170001D01*
X1493172D01*
X1494290Y1171120D01*
Y1171883D01*
X1495407Y1173000D01*
X1502301D01*
X1508541Y1179240D01*
X1510513D01*
G01X933741Y598087D02*
X934741Y597087D01*
X935600D01*
X936100Y597587D01*
Y611203D01*
X933436Y613867D01*
Y639617D01*
X958500Y664681D01*
Y671152D01*
X995043Y707695D01*
Y742693D01*
X983002Y754734D01*
X980714D01*
X970551Y764897D01*
Y805286D01*
X968053Y811317D01*
Y819594D01*
X967079Y821946D01*
X961566Y827460D01*
Y831784D01*
X958425Y834924D01*
X957250Y837765D01*
Y842711D01*
X956149Y845370D01*
Y848368D01*
X960450Y852669D01*
Y857579D01*
X958336Y859693D01*
Y868281D01*
X956124Y873623D01*
Y909506D01*
X990750Y944132D01*
Y1040532D01*
X1007376Y1080675D01*
X1028920Y1102219D01*
Y1164671D01*
X1038258Y1174009D01*
X1044784D01*
X1051877Y1181102D01*
X1053289D01*
G01X933741Y594687D02*
X934691Y595637D01*
X936201D01*
X937550Y596986D01*
Y611804D01*
X934886Y614468D01*
Y639016D01*
X959950Y664080D01*
Y670551D01*
X996493Y707094D01*
Y743294D01*
X983603Y756184D01*
X981315D01*
X972001Y765498D01*
Y805575D01*
X969503Y811606D01*
Y819883D01*
X968309Y822768D01*
X963016Y828061D01*
Y832385D01*
X959655Y835746D01*
X958700Y838054D01*
Y843000D01*
X957599Y845659D01*
Y847767D01*
X961900Y852068D01*
Y858180D01*
X959786Y860294D01*
Y868570D01*
X957574Y873912D01*
Y908905D01*
X992200Y943531D01*
Y1040243D01*
X1008606Y1079853D01*
X1030370Y1101618D01*
Y1164070D01*
X1031487Y1165187D01*
X1032250D01*
X1033369Y1166305D01*
Y1167069D01*
X1038859Y1172559D01*
X1045385D01*
X1049479Y1176653D01*
X1050243D01*
X1051361Y1177772D01*
Y1178535D01*
X1052478Y1179652D01*
X1053289D01*
G01X933725Y589336D02*
X934675Y588386D01*
X935535D01*
X940300Y593151D01*
Y614900D01*
X937903Y617297D01*
Y633911D01*
X956242Y652250D01*
X968826D01*
X1014745Y698169D01*
Y714413D01*
X1023263Y722931D01*
X1031997Y726549D01*
X1142649Y837200D01*
X1186954D01*
X1237891Y888137D01*
Y925400D01*
X1269741Y957250D01*
X1389263D01*
X1390763Y955750D01*
X1424916D01*
X1443850Y974684D01*
Y1060400D01*
X1482150Y1098700D01*
X1483649D01*
X1485900Y1100951D01*
Y1165544D01*
X1494806Y1174450D01*
X1501700D01*
X1507940Y1180690D01*
X1510513D01*
G01X1052355Y1172254D02*
X1050524Y1170423D01*
Y1167448D01*
X1048453Y1165378D01*
X1038360Y1161197D01*
X1034792Y1157628D01*
Y1100693D01*
X1012601Y1078502D01*
X1000515Y1049323D01*
X995950Y1026371D01*
Y941294D01*
X961678Y907022D01*
Y874575D01*
X963587Y869965D01*
Y862242D01*
X966038Y859791D01*
Y847085D01*
X965250Y846297D01*
Y836950D01*
X974121Y828079D01*
Y815455D01*
X979145Y803325D01*
Y764056D01*
X982801Y760400D01*
X985838D01*
X1000250Y745988D01*
Y703070D01*
X967750Y670570D01*
Y668606D01*
X966797Y667653D01*
G01X1053381Y1171228D02*
X1051974Y1169821D01*
Y1166847D01*
X1049275Y1164148D01*
X1039182Y1159967D01*
X1036242Y1157027D01*
Y1150435D01*
X1036782Y1149895D01*
Y1148305D01*
X1036242Y1147765D01*
Y1100092D01*
X1013831Y1077680D01*
X1001910Y1048900D01*
X997400Y1026228D01*
Y940693D01*
X963128Y906421D01*
Y874864D01*
X965037Y870254D01*
Y862843D01*
X967488Y860392D01*
Y846484D01*
X966700Y845696D01*
Y837551D01*
X975571Y828680D01*
Y815744D01*
X980595Y803614D01*
Y764657D01*
X983402Y761850D01*
X986439D01*
X1001700Y746589D01*
Y702469D01*
X969200Y669969D01*
Y668650D01*
X970197Y667653D01*
G01X1510613Y1167975D02*
X1509976D01*
X1502651Y1160650D01*
X1494667D01*
X1493131Y1159114D01*
Y1098731D01*
X1484350Y1089950D01*
X1483208D01*
X1452400Y1059142D01*
Y964601D01*
X1436299Y948500D01*
X1388148D01*
X1386099Y950549D01*
X1297949D01*
X1292750Y945350D01*
X1268250D01*
X1244700Y921800D01*
Y884750D01*
X1189750Y829800D01*
X1157300D01*
X1040459Y712959D01*
Y700703D01*
X1020360Y680604D01*
X1016609D01*
X1015659Y679654D01*
G01X1510613Y1169425D02*
X1509375D01*
X1502050Y1162100D01*
X1494066D01*
X1491681Y1159715D01*
Y1099332D01*
X1483749Y1091400D01*
X1482607D01*
X1450950Y1059743D01*
Y965202D01*
X1435698Y949950D01*
X1388749D01*
X1386700Y951999D01*
X1297348D01*
X1292149Y946800D01*
X1267649D01*
X1243250Y922401D01*
Y885351D01*
X1189149Y831250D01*
X1156699D01*
X1039009Y713560D01*
Y701304D01*
X1032263Y694558D01*
X1031272D01*
X1030423Y693709D01*
Y692718D01*
X1019759Y682054D01*
X1016659D01*
X1015659Y683054D01*
G54D17*
X15023Y1070592D03*
X9223D03*
X15023Y1065299D03*
X9223D03*
X15076Y1075972D03*
X9276D03*
X14968Y1081286D03*
X9168D03*
X14970Y1086527D03*
X9170D03*
X14974Y1091945D03*
X9174D03*
X33686Y1086732D03*
X47137Y1064774D03*
X52937D03*
X39486Y1086732D03*
X166249Y1125408D03*
X172049D03*
X185369Y1189089D03*
X191169D03*
X208242Y1162291D03*
X214042D03*
X223203D03*
X229003D03*
X241904D03*
X247704D03*
X295198Y1163090D03*
X300998D03*
X311962Y1163079D03*
X306162D03*
X435198Y1314391D03*
X440998D03*
X501412Y681478D03*
X507212D03*
X501412Y687978D03*
X507212D03*
X502655Y693245D03*
X508455D03*
X521414Y717903D03*
X514383Y723583D03*
X520183D03*
X527214Y717903D03*
X532304Y797889D03*
X538104D03*
Y803389D03*
X532304D03*
X551804Y806889D03*
Y801389D03*
X557604Y806889D03*
Y801389D03*
X625146Y1126058D03*
X630946D03*
X642456Y1189089D03*
X648256D03*
X665329Y1162291D03*
X680290D03*
X686090D03*
X671129D03*
X698991D03*
X704791D03*
X752285Y1163090D03*
X758085D03*
X763249Y1163079D03*
X769049D03*
X860009Y1073297D03*
X854209D03*
X859852Y1089261D03*
X854052D03*
X859847Y1083918D03*
X854047D03*
X859989Y1078510D03*
X854189D03*
X859778Y1100734D03*
X853978D03*
X859827Y1094715D03*
X854027D03*
X868191Y827563D03*
X873991D03*
X868191Y822176D03*
X873991D03*
X868191Y833037D03*
X873991D03*
X881648Y1093445D03*
X893856Y1074510D03*
X887448Y1093445D03*
X900049Y551863D03*
X905849D03*
X912866Y832855D03*
X907066D03*
X899656Y1074510D03*
X921549Y572863D03*
X927349D03*
X927014Y1074367D03*
X921214D03*
X927095Y1085168D03*
X921295D03*
X926987Y1079821D03*
X921187D03*
X936229Y843950D03*
X942029D03*
X941933Y849373D03*
X936133D03*
X960850Y807855D03*
X955050D03*
X960850Y813342D03*
X955050D03*
X960850Y818829D03*
X955050D03*
X1009116Y316394D03*
X997020Y336954D03*
X1002820D03*
Y341954D03*
X997020D03*
X1003520Y348954D03*
X1009320D03*
Y353954D03*
X1003520D03*
X1021743Y306927D03*
X1027543D03*
X1014916Y316394D03*
X1043020Y343954D03*
X1052820Y316954D03*
X1047020D03*
X1048820Y343954D03*
X1086222Y1125408D03*
X1080422D03*
X1089700Y1521000D03*
X1105342Y1189089D03*
X1099542D03*
X1095500Y1521000D03*
X1122415Y1162291D03*
X1137376D03*
X1128215D03*
X1156077D03*
X1143176D03*
X1161877D03*
X1220335Y1163079D03*
X1215171Y1163090D03*
X1209371D03*
X1226135Y1163079D03*
X1287605Y897416D03*
X1300974Y846670D03*
X1299184Y863988D03*
X1293405Y897416D03*
X1306774Y846670D03*
X1304984Y863988D03*
X1378578Y1258399D03*
X1372778D03*
X1390449Y854121D03*
X1396249D03*
X1388924Y880908D03*
X1394724D03*
X1497063Y925240D03*
Y930740D03*
X1502863Y925240D03*
Y930740D03*
X1522363Y928740D03*
X1516563D03*
Y934240D03*
X1522363D03*
X1543309Y1125408D03*
X1537509D03*
X1562429Y1189089D03*
X1556629D03*
X1579502Y1162291D03*
X1594463D03*
X1585302D03*
X1600263D03*
X1618964D03*
X1613164D03*
X1672258Y1163090D03*
X1666458D03*
X1677422Y1163079D03*
X1683222D03*
X1773994Y1080874D03*
X1768194D03*
X1773915Y1086114D03*
X1768115D03*
X1773915Y1101159D03*
X1768115D03*
X1774017Y1095803D03*
X1768217D03*
X1788794Y1095629D03*
X1783536Y1101077D03*
X1789336D03*
X1802379Y1074480D03*
X1794594Y1095629D03*
X1808179Y1074480D03*
G54D62*
X272635Y451628D03*
X729721D03*
X1186808D03*
X1643895D03*
G54D53*
X212460Y551894D03*
Y557800D03*
X219546Y551894D03*
Y557800D03*
X669546Y551894D03*
Y557800D03*
X676632Y551894D03*
Y557800D03*
X1133719Y551894D03*
X1126633D03*
Y557800D03*
X1133719D03*
X1590806Y551894D03*
X1583720D03*
Y557800D03*
X1590806D03*
G54D35*
X46348Y1727941D03*
Y1737941D03*
X46248Y1760941D03*
Y1750941D03*
X46348Y1773941D03*
Y1783941D03*
X46248Y1806941D03*
Y1796941D03*
X318448Y1727941D03*
Y1737941D03*
Y1750941D03*
Y1760941D03*
Y1773941D03*
Y1783941D03*
X318348Y1796941D03*
Y1806941D03*
X333286Y1728583D03*
Y1738583D03*
X333112Y1751624D03*
X333212Y1774624D03*
X333112Y1761624D03*
X333212Y1784624D03*
Y1797624D03*
Y1807624D03*
X605386Y1728583D03*
Y1738583D03*
X605312Y1751624D03*
Y1774624D03*
Y1761624D03*
Y1784624D03*
Y1807624D03*
Y1797624D03*
X620083Y1728286D03*
Y1738286D03*
X619861Y1751765D03*
X619711Y1775438D03*
X619861Y1761765D03*
X619711Y1785438D03*
X619475Y1798845D03*
Y1808845D03*
X892183Y1728286D03*
Y1738286D03*
X891911Y1751765D03*
X891761Y1775438D03*
X891911Y1761765D03*
X891761Y1785438D03*
X891525Y1808845D03*
Y1798845D03*
X907279Y1738990D03*
Y1728990D03*
X907163Y1752566D03*
Y1762566D03*
X907073Y1776014D03*
Y1786014D03*
X907166Y1800435D03*
Y1810435D03*
X1179329Y1728990D03*
Y1738990D03*
X1179263Y1752566D03*
Y1762566D03*
X1179123Y1776014D03*
Y1786014D03*
X1179216Y1800435D03*
Y1810435D03*
G54D44*
X109882Y1458622D03*
Y1463741D03*
Y1473977D03*
Y1479095D03*
Y1489331D03*
Y1494449D03*
Y1504685D03*
Y1509804D03*
Y1560985D03*
Y1566103D03*
Y1576339D03*
Y1581457D03*
Y1591693D03*
Y1596811D03*
Y1607048D03*
Y1612166D03*
X127205Y1458622D03*
Y1463741D03*
X118543Y1462953D03*
X127205Y1473977D03*
Y1479095D03*
X118543Y1468071D03*
Y1478308D03*
X127205Y1489331D03*
Y1494449D03*
X118543Y1483426D03*
Y1493662D03*
Y1498780D03*
X127205Y1504685D03*
Y1509804D03*
X118543Y1509016D03*
Y1514134D03*
X127205Y1560985D03*
Y1566103D03*
Y1576339D03*
X118543Y1565315D03*
Y1570434D03*
X127205Y1581457D03*
Y1591693D03*
X118543Y1580670D03*
Y1585788D03*
Y1596024D03*
X127205Y1596811D03*
Y1607048D03*
Y1612166D03*
X118543Y1601142D03*
Y1611378D03*
Y1616496D03*
X144528Y1458622D03*
Y1463741D03*
X135866Y1462953D03*
X144528Y1473977D03*
Y1479095D03*
X135866Y1468071D03*
Y1478308D03*
X144528Y1489331D03*
Y1494449D03*
X135866Y1483426D03*
Y1493662D03*
Y1498780D03*
X144528Y1504685D03*
Y1509804D03*
X135866Y1509016D03*
Y1514134D03*
X144528Y1560985D03*
Y1566103D03*
Y1576339D03*
X135866Y1565315D03*
Y1570434D03*
X144528Y1581457D03*
Y1591693D03*
X135866Y1580670D03*
Y1585788D03*
Y1596024D03*
X144528Y1596811D03*
Y1607048D03*
Y1612166D03*
X135866Y1601142D03*
Y1611378D03*
Y1616496D03*
X161850Y1458622D03*
Y1463741D03*
X153189Y1462953D03*
X161850Y1473977D03*
Y1479095D03*
X153189Y1468071D03*
Y1478308D03*
X161850Y1489331D03*
Y1494449D03*
X153189Y1483426D03*
Y1493662D03*
Y1498780D03*
X161850Y1504685D03*
Y1509804D03*
X153189Y1509016D03*
Y1514134D03*
X161850Y1560985D03*
Y1566103D03*
Y1576339D03*
X153189Y1565315D03*
Y1570434D03*
X161850Y1581457D03*
Y1591693D03*
X153189Y1580670D03*
Y1585788D03*
Y1596024D03*
X161850Y1596811D03*
Y1607048D03*
Y1612166D03*
X153189Y1601142D03*
Y1611378D03*
Y1616496D03*
X179173Y1458622D03*
Y1463741D03*
X170512Y1462953D03*
X179173Y1473977D03*
Y1479095D03*
X170512Y1468071D03*
Y1478308D03*
Y1483426D03*
Y1493662D03*
Y1498780D03*
Y1509016D03*
Y1514134D03*
Y1565315D03*
Y1570434D03*
Y1580670D03*
Y1585788D03*
Y1596024D03*
Y1601142D03*
Y1611378D03*
Y1616496D03*
X187835Y1462953D03*
Y1468071D03*
Y1478308D03*
Y1483426D03*
Y1596024D03*
Y1601142D03*
Y1611378D03*
Y1616496D03*
X283110Y1458622D03*
X291771Y1462953D03*
X283110Y1463741D03*
X291771Y1468071D03*
X283110Y1473977D03*
X291771Y1478308D03*
X283110Y1479095D03*
X291771Y1483426D03*
X283110Y1489331D03*
X291771Y1493662D03*
X283110Y1494449D03*
X291771Y1498780D03*
X283110Y1504685D03*
X291771Y1509016D03*
X283110Y1509804D03*
X291771Y1514134D03*
X283110Y1560985D03*
X291771Y1565315D03*
X283110Y1566103D03*
X291771Y1570434D03*
X283110Y1576339D03*
X291771Y1580670D03*
X283110Y1581457D03*
X291771Y1585788D03*
X283110Y1591693D03*
X291771Y1596024D03*
X283110Y1596811D03*
X291771Y1601142D03*
X283110Y1607048D03*
X291771Y1611378D03*
X283110Y1612166D03*
X291771Y1616496D03*
X300433Y1458622D03*
X309094Y1462953D03*
X300433Y1463741D03*
X309094Y1468071D03*
X300433Y1473977D03*
X309094Y1478308D03*
X300433Y1479095D03*
X309094Y1483426D03*
X300433Y1489331D03*
X309094Y1493662D03*
X300433Y1494449D03*
X309094Y1498780D03*
X300433Y1504685D03*
X309094Y1509016D03*
X300433Y1509804D03*
X309094Y1514134D03*
X300433Y1560985D03*
X309094Y1565315D03*
X300433Y1566103D03*
X309094Y1570434D03*
X300433Y1576339D03*
X309094Y1580670D03*
X300433Y1581457D03*
X309094Y1585788D03*
X300433Y1591693D03*
X309094Y1596024D03*
X300433Y1596811D03*
X309094Y1601142D03*
X300433Y1607048D03*
X309094Y1611378D03*
X300433Y1612166D03*
X309094Y1616496D03*
X317756Y1458622D03*
X326417Y1462953D03*
X317756Y1463741D03*
X326417Y1468071D03*
X317756Y1473977D03*
X326417Y1478308D03*
X317756Y1479095D03*
X326417Y1483426D03*
X317756Y1489331D03*
X326417Y1493662D03*
X317756Y1494449D03*
X326417Y1498780D03*
X317756Y1504685D03*
X326417Y1509016D03*
X317756Y1509804D03*
X326417Y1514134D03*
X317756Y1560985D03*
X326417Y1565315D03*
X317756Y1566103D03*
X326417Y1570434D03*
X317756Y1576339D03*
X326417Y1580670D03*
X317756Y1581457D03*
X326417Y1585788D03*
X317756Y1591693D03*
X326417Y1596024D03*
X317756Y1596811D03*
X326417Y1601142D03*
X317756Y1607048D03*
X326417Y1611378D03*
X317756Y1612166D03*
X326417Y1616496D03*
X335078Y1458622D03*
X343740Y1462953D03*
X335078Y1463741D03*
X343740Y1468071D03*
X335078Y1473977D03*
X343740Y1478308D03*
X335078Y1479095D03*
X343740Y1483426D03*
X335078Y1489331D03*
X343740Y1493662D03*
X335078Y1494449D03*
X343740Y1498780D03*
X335078Y1504685D03*
X343740Y1509016D03*
X335078Y1509804D03*
X343740Y1514134D03*
X335078Y1560985D03*
X343740Y1565315D03*
X335078Y1566103D03*
X343740Y1570434D03*
X335078Y1576339D03*
X343740Y1580670D03*
X335078Y1581457D03*
X343740Y1585788D03*
X335078Y1591693D03*
X343740Y1596024D03*
X335078Y1596811D03*
X343740Y1601142D03*
X335078Y1607048D03*
X343740Y1611378D03*
X335078Y1612166D03*
X343740Y1616496D03*
X361063Y1596024D03*
Y1601142D03*
Y1611378D03*
Y1616496D03*
X456339Y1458622D03*
Y1463741D03*
Y1473977D03*
Y1479095D03*
Y1489331D03*
Y1494449D03*
Y1504685D03*
Y1509804D03*
Y1560985D03*
Y1566103D03*
Y1576339D03*
Y1581457D03*
Y1591693D03*
Y1596811D03*
Y1607048D03*
Y1612166D03*
X473662Y1458622D03*
Y1463741D03*
X465000Y1462953D03*
X473662Y1473977D03*
Y1479095D03*
X465000Y1468071D03*
Y1478308D03*
X473662Y1489331D03*
Y1494449D03*
X465000Y1483426D03*
Y1493662D03*
Y1498780D03*
X473662Y1504685D03*
Y1509804D03*
X465000Y1509016D03*
Y1514134D03*
X473662Y1560985D03*
Y1566103D03*
Y1576339D03*
X465000Y1565315D03*
Y1570434D03*
X473662Y1581457D03*
Y1591693D03*
X465000Y1580670D03*
Y1585788D03*
Y1596024D03*
X473662Y1596811D03*
Y1607048D03*
Y1612166D03*
X465000Y1601142D03*
Y1611378D03*
Y1616496D03*
X490985Y1458622D03*
Y1463741D03*
X482323Y1462953D03*
X490985Y1473977D03*
Y1479095D03*
X482323Y1468071D03*
Y1478308D03*
X490985Y1489331D03*
Y1494449D03*
X482323Y1483426D03*
Y1493662D03*
Y1498780D03*
X490985Y1504685D03*
Y1509804D03*
X482323Y1509016D03*
Y1514134D03*
X490985Y1560985D03*
Y1566103D03*
Y1576339D03*
X482323Y1565315D03*
Y1570434D03*
X490985Y1581457D03*
Y1591693D03*
X482323Y1580670D03*
Y1585788D03*
Y1596024D03*
X490985Y1596811D03*
Y1607048D03*
Y1612166D03*
X482323Y1601142D03*
Y1611378D03*
Y1616496D03*
X499646Y1462953D03*
Y1468071D03*
Y1478308D03*
Y1483426D03*
Y1493662D03*
Y1498780D03*
Y1509016D03*
Y1514134D03*
Y1565315D03*
Y1570434D03*
Y1580670D03*
Y1585788D03*
Y1596024D03*
Y1601142D03*
Y1611378D03*
Y1616496D03*
X508307Y1458622D03*
X516969Y1462953D03*
X508307Y1463741D03*
X516969Y1468071D03*
X508307Y1473977D03*
X516969Y1478308D03*
X508307Y1479095D03*
X516969Y1483426D03*
X508307Y1489331D03*
X516969Y1493662D03*
X508307Y1494449D03*
X516969Y1498780D03*
X508307Y1504685D03*
X516969Y1509016D03*
X508307Y1509804D03*
X516969Y1514134D03*
X508307Y1560985D03*
X516969Y1565315D03*
X508307Y1566103D03*
X516969Y1570434D03*
X508307Y1576339D03*
X516969Y1580670D03*
X508307Y1581457D03*
X516969Y1585788D03*
X508307Y1591693D03*
X516969Y1596024D03*
X508307Y1596811D03*
X516969Y1601142D03*
X508307Y1607048D03*
X516969Y1611378D03*
X508307Y1612166D03*
X516969Y1616496D03*
X629567Y1458622D03*
Y1463741D03*
Y1473977D03*
Y1479095D03*
Y1489331D03*
Y1494449D03*
Y1504685D03*
Y1509804D03*
Y1560985D03*
Y1566103D03*
Y1576339D03*
Y1581457D03*
Y1591693D03*
Y1596811D03*
Y1607048D03*
Y1612166D03*
X646890Y1458622D03*
Y1463741D03*
X638228Y1462953D03*
X646890Y1473977D03*
Y1479095D03*
X638228Y1468071D03*
Y1478308D03*
X646890Y1489331D03*
Y1494449D03*
X638228Y1483426D03*
Y1493662D03*
Y1498780D03*
X646890Y1504685D03*
Y1509804D03*
X638228Y1509016D03*
Y1514134D03*
X646890Y1560985D03*
Y1566103D03*
Y1576339D03*
X638228Y1565315D03*
Y1570434D03*
X646890Y1581457D03*
Y1591693D03*
X638228Y1580670D03*
Y1585788D03*
Y1596024D03*
X646890Y1596811D03*
Y1607048D03*
Y1612166D03*
X638228Y1601142D03*
Y1611378D03*
Y1616496D03*
X664213Y1458622D03*
Y1463741D03*
X655551Y1462953D03*
X664213Y1473977D03*
Y1479095D03*
X655551Y1468071D03*
Y1478308D03*
X664213Y1489331D03*
Y1494449D03*
X655551Y1483426D03*
Y1493662D03*
Y1498780D03*
X664213Y1504685D03*
Y1509804D03*
X655551Y1509016D03*
Y1514134D03*
X664213Y1560985D03*
Y1566103D03*
Y1576339D03*
X655551Y1565315D03*
Y1570434D03*
X664213Y1581457D03*
Y1591693D03*
X655551Y1580670D03*
Y1585788D03*
Y1596024D03*
X664213Y1596811D03*
Y1607048D03*
Y1612166D03*
X655551Y1601142D03*
Y1611378D03*
Y1616496D03*
X681535Y1458622D03*
Y1463741D03*
X672874Y1462953D03*
X681535Y1473977D03*
Y1479095D03*
X672874Y1468071D03*
Y1478308D03*
X681535Y1489331D03*
Y1494449D03*
X672874Y1483426D03*
Y1493662D03*
Y1498780D03*
X681535Y1504685D03*
Y1509804D03*
X672874Y1509016D03*
Y1514134D03*
X681535Y1560985D03*
Y1566103D03*
Y1576339D03*
X672874Y1565315D03*
Y1570434D03*
X681535Y1581457D03*
Y1591693D03*
X672874Y1580670D03*
Y1585788D03*
Y1596024D03*
X681535Y1596811D03*
Y1607048D03*
Y1612166D03*
X672874Y1601142D03*
Y1611378D03*
Y1616496D03*
X690197Y1462953D03*
Y1468071D03*
Y1478308D03*
Y1483426D03*
Y1493662D03*
Y1498780D03*
Y1509016D03*
Y1514134D03*
Y1565315D03*
Y1570434D03*
Y1580670D03*
Y1585788D03*
Y1596024D03*
Y1601142D03*
Y1611378D03*
Y1616496D03*
X1131850Y1458622D03*
X1140511Y1462953D03*
X1131850Y1463741D03*
X1140511Y1468071D03*
X1131850Y1473977D03*
X1140511Y1478308D03*
X1131850Y1479095D03*
X1140511Y1483426D03*
X1131850Y1489331D03*
X1140511Y1493662D03*
X1131850Y1494449D03*
X1140511Y1498780D03*
X1131850Y1504685D03*
X1140511Y1509016D03*
X1131850Y1509804D03*
X1140511Y1514134D03*
X1131850Y1560985D03*
X1140511Y1565315D03*
X1131850Y1566103D03*
X1140511Y1570434D03*
X1131850Y1576339D03*
X1140511Y1580670D03*
X1131850Y1581457D03*
X1140511Y1585788D03*
X1131850Y1591693D03*
X1140511Y1596024D03*
X1131850Y1596811D03*
X1140511Y1601142D03*
X1131850Y1607048D03*
X1140511Y1611378D03*
X1131850Y1612166D03*
X1140511Y1616496D03*
X1149173Y1458622D03*
Y1463741D03*
Y1473977D03*
Y1479095D03*
Y1489331D03*
Y1494449D03*
Y1504685D03*
Y1509804D03*
Y1560985D03*
Y1566103D03*
Y1576339D03*
Y1581457D03*
Y1591693D03*
Y1596811D03*
Y1607048D03*
Y1612166D03*
X1166496Y1458622D03*
Y1463741D03*
X1157834Y1462953D03*
X1166496Y1473977D03*
Y1479095D03*
X1157834Y1468071D03*
Y1478308D03*
X1166496Y1489331D03*
Y1494449D03*
X1157834Y1483426D03*
Y1493662D03*
Y1498780D03*
X1166496Y1504685D03*
Y1509804D03*
X1157834Y1509016D03*
Y1514134D03*
X1166496Y1560985D03*
Y1566103D03*
Y1576339D03*
X1157834Y1565315D03*
Y1570434D03*
X1166496Y1581457D03*
Y1591693D03*
X1157834Y1580670D03*
Y1585788D03*
Y1596024D03*
X1166496Y1596811D03*
Y1607048D03*
Y1612166D03*
X1157834Y1601142D03*
Y1611378D03*
Y1616496D03*
X1183818Y1458622D03*
Y1463741D03*
X1175157Y1462953D03*
X1183818Y1473977D03*
Y1479095D03*
X1175157Y1468071D03*
Y1478308D03*
X1183818Y1489331D03*
Y1494449D03*
X1175157Y1483426D03*
Y1493662D03*
Y1498780D03*
X1183818Y1504685D03*
Y1509804D03*
X1175157Y1509016D03*
Y1514134D03*
X1183818Y1560985D03*
Y1566103D03*
Y1576339D03*
X1175157Y1565315D03*
Y1570434D03*
X1183818Y1581457D03*
Y1591693D03*
X1175157Y1580670D03*
Y1585788D03*
Y1596024D03*
X1183818Y1596811D03*
Y1607048D03*
Y1612166D03*
X1175157Y1601142D03*
Y1611378D03*
Y1616496D03*
X1192480Y1462953D03*
Y1468071D03*
Y1478308D03*
Y1483426D03*
Y1493662D03*
Y1498780D03*
Y1509016D03*
Y1514134D03*
Y1565315D03*
Y1570434D03*
Y1580670D03*
Y1585788D03*
Y1596024D03*
Y1601142D03*
Y1611378D03*
Y1616496D03*
X1305079Y1458622D03*
X1313740Y1462953D03*
X1305079Y1463741D03*
X1313740Y1468071D03*
X1305079Y1473977D03*
X1313740Y1478308D03*
X1305079Y1479095D03*
X1313740Y1483426D03*
X1305079Y1489331D03*
X1313740Y1493662D03*
X1305079Y1494449D03*
X1313740Y1498780D03*
X1305079Y1504685D03*
X1313740Y1509016D03*
X1305079Y1509804D03*
X1313740Y1514134D03*
X1305079Y1560985D03*
X1313740Y1565315D03*
X1305079Y1566103D03*
X1313740Y1570434D03*
X1305079Y1576339D03*
X1313740Y1580670D03*
X1305079Y1581457D03*
X1313740Y1585788D03*
X1305079Y1591693D03*
X1313740Y1596024D03*
X1305079Y1596811D03*
X1313740Y1601142D03*
X1305079Y1607048D03*
X1313740Y1611378D03*
X1305079Y1612166D03*
X1313740Y1616496D03*
X1322402Y1458622D03*
X1331063Y1462953D03*
X1322402Y1463741D03*
X1331063Y1468071D03*
X1322402Y1473977D03*
X1331063Y1478308D03*
X1322402Y1479095D03*
X1331063Y1483426D03*
X1322402Y1489331D03*
X1331063Y1493662D03*
X1322402Y1494449D03*
X1331063Y1498780D03*
X1322402Y1504685D03*
X1331063Y1509016D03*
X1322402Y1509804D03*
X1331063Y1514134D03*
X1322402Y1560985D03*
X1331063Y1565315D03*
X1322402Y1566103D03*
X1331063Y1570434D03*
X1322402Y1576339D03*
X1331063Y1580670D03*
X1322402Y1581457D03*
X1331063Y1585788D03*
X1322402Y1591693D03*
X1331063Y1596024D03*
X1322402Y1596811D03*
X1331063Y1601142D03*
X1322402Y1607048D03*
X1331063Y1611378D03*
X1322402Y1612166D03*
X1331063Y1616496D03*
X1339725Y1458622D03*
X1348386Y1462953D03*
X1339725Y1463741D03*
X1348386Y1468071D03*
X1339725Y1473977D03*
X1348386Y1478308D03*
X1339725Y1479095D03*
X1348386Y1483426D03*
X1339725Y1489331D03*
X1348386Y1493662D03*
X1339725Y1494449D03*
X1348386Y1498780D03*
X1339725Y1504685D03*
X1348386Y1509016D03*
X1339725Y1509804D03*
X1348386Y1514134D03*
X1339725Y1560985D03*
X1348386Y1565315D03*
X1339725Y1566103D03*
X1348386Y1570434D03*
X1339725Y1576339D03*
X1348386Y1580670D03*
X1339725Y1581457D03*
X1348386Y1585788D03*
X1339725Y1591693D03*
X1348386Y1596024D03*
X1339725Y1596811D03*
X1348386Y1601142D03*
X1339725Y1607048D03*
X1348386Y1611378D03*
X1339725Y1612166D03*
X1348386Y1616496D03*
X1357047Y1458622D03*
X1365709Y1462953D03*
X1357047Y1463741D03*
X1365709Y1468071D03*
X1357047Y1473977D03*
X1365709Y1478308D03*
X1357047Y1479095D03*
X1365709Y1483426D03*
X1357047Y1489331D03*
X1365709Y1493662D03*
X1357047Y1494449D03*
X1365709Y1498780D03*
X1357047Y1504685D03*
X1365709Y1509016D03*
X1357047Y1509804D03*
X1365709Y1514134D03*
X1357047Y1560985D03*
X1365709Y1565315D03*
X1357047Y1566103D03*
X1365709Y1570434D03*
X1357047Y1576339D03*
X1365709Y1580670D03*
X1357047Y1581457D03*
X1365709Y1585788D03*
X1357047Y1591693D03*
X1365709Y1596024D03*
X1357047Y1596811D03*
X1365709Y1601142D03*
X1357047Y1607048D03*
X1365709Y1611378D03*
X1357047Y1612166D03*
X1365709Y1616496D03*
X1478307Y1458622D03*
Y1463741D03*
Y1473977D03*
Y1479095D03*
Y1489331D03*
Y1494449D03*
Y1504685D03*
Y1509804D03*
Y1560985D03*
Y1566103D03*
Y1576339D03*
Y1581457D03*
Y1591693D03*
Y1596811D03*
Y1607048D03*
Y1612166D03*
X1495630Y1458622D03*
Y1463741D03*
X1486968Y1462953D03*
X1495630Y1473977D03*
Y1479095D03*
X1486968Y1468071D03*
Y1478308D03*
X1495630Y1489331D03*
Y1494449D03*
X1486968Y1483426D03*
Y1493662D03*
Y1498780D03*
X1495630Y1504685D03*
Y1509804D03*
X1486968Y1509016D03*
Y1514134D03*
X1495630Y1560985D03*
Y1566103D03*
Y1576339D03*
X1486968Y1565315D03*
Y1570434D03*
X1495630Y1581457D03*
Y1591693D03*
X1486968Y1580670D03*
Y1585788D03*
Y1596024D03*
X1495630Y1596811D03*
Y1607048D03*
Y1612166D03*
X1486968Y1601142D03*
Y1611378D03*
Y1616496D03*
X1512953Y1458622D03*
Y1463741D03*
X1504291Y1462953D03*
X1512953Y1473977D03*
Y1479095D03*
X1504291Y1468071D03*
Y1478308D03*
X1512953Y1489331D03*
Y1494449D03*
X1504291Y1483426D03*
Y1493662D03*
Y1498780D03*
X1512953Y1504685D03*
Y1509804D03*
X1504291Y1509016D03*
Y1514134D03*
X1512953Y1560985D03*
Y1566103D03*
Y1576339D03*
X1504291Y1565315D03*
Y1570434D03*
X1512953Y1581457D03*
Y1591693D03*
X1504291Y1580670D03*
Y1585788D03*
Y1596024D03*
X1512953Y1596811D03*
Y1607048D03*
Y1612166D03*
X1504291Y1601142D03*
Y1611378D03*
Y1616496D03*
X1530275Y1458622D03*
Y1463741D03*
X1521614Y1462953D03*
X1530275Y1473977D03*
Y1479095D03*
X1521614Y1468071D03*
Y1478308D03*
X1530275Y1489331D03*
Y1494449D03*
X1521614Y1483426D03*
Y1493662D03*
Y1498780D03*
X1530275Y1504685D03*
Y1509804D03*
X1521614Y1509016D03*
Y1514134D03*
X1530275Y1560985D03*
Y1566103D03*
Y1576339D03*
X1521614Y1565315D03*
Y1570434D03*
X1530275Y1581457D03*
Y1591693D03*
X1521614Y1580670D03*
Y1585788D03*
Y1596024D03*
X1530275Y1596811D03*
Y1607048D03*
Y1612166D03*
X1521614Y1601142D03*
Y1611378D03*
Y1616496D03*
X1538937Y1462953D03*
Y1468071D03*
Y1478308D03*
Y1483426D03*
Y1493662D03*
Y1498780D03*
Y1509016D03*
Y1514134D03*
Y1565315D03*
Y1570434D03*
Y1580670D03*
Y1585788D03*
Y1596024D03*
Y1601142D03*
Y1611378D03*
Y1616496D03*
X1651535Y1458622D03*
X1660196Y1462953D03*
X1651535Y1463741D03*
X1660196Y1468071D03*
X1651535Y1473977D03*
X1660196Y1478308D03*
X1651535Y1479095D03*
X1660196Y1483426D03*
X1651535Y1489331D03*
X1660196Y1493662D03*
X1651535Y1494449D03*
X1660196Y1498780D03*
X1651535Y1504685D03*
X1660196Y1509016D03*
X1651535Y1509804D03*
X1660196Y1514134D03*
X1651535Y1560985D03*
X1660196Y1565315D03*
X1651535Y1566103D03*
X1660196Y1570434D03*
X1651535Y1576339D03*
X1660196Y1580670D03*
X1651535Y1581457D03*
X1660196Y1585788D03*
X1651535Y1591693D03*
X1660196Y1596024D03*
X1651535Y1596811D03*
X1660196Y1601142D03*
X1651535Y1607048D03*
X1660196Y1611378D03*
X1651535Y1612166D03*
X1660196Y1616496D03*
X1668858Y1458622D03*
Y1463741D03*
Y1473977D03*
Y1479095D03*
Y1489331D03*
Y1494449D03*
Y1504685D03*
Y1509804D03*
Y1560985D03*
Y1566103D03*
Y1576339D03*
Y1581457D03*
Y1591693D03*
Y1596811D03*
Y1607048D03*
Y1612166D03*
X1686181Y1458622D03*
Y1463741D03*
X1677519Y1462953D03*
X1686181Y1473977D03*
Y1479095D03*
X1677519Y1468071D03*
Y1478308D03*
X1686181Y1489331D03*
Y1494449D03*
X1677519Y1483426D03*
Y1493662D03*
Y1498780D03*
X1686181Y1504685D03*
Y1509804D03*
X1677519Y1509016D03*
Y1514134D03*
X1686181Y1560985D03*
Y1566103D03*
Y1576339D03*
X1677519Y1565315D03*
Y1570434D03*
X1686181Y1581457D03*
Y1591693D03*
X1677519Y1580670D03*
Y1585788D03*
Y1596024D03*
X1686181Y1596811D03*
Y1607048D03*
Y1612166D03*
X1677519Y1601142D03*
Y1611378D03*
Y1616496D03*
X1703503Y1458622D03*
Y1463741D03*
X1694842Y1462953D03*
X1703503Y1473977D03*
Y1479095D03*
X1694842Y1468071D03*
Y1478308D03*
X1703503Y1489331D03*
Y1494449D03*
X1694842Y1483426D03*
Y1493662D03*
Y1498780D03*
X1703503Y1504685D03*
Y1509804D03*
X1694842Y1509016D03*
Y1514134D03*
X1703503Y1560985D03*
Y1566103D03*
Y1576339D03*
X1694842Y1565315D03*
Y1570434D03*
X1703503Y1581457D03*
Y1591693D03*
X1694842Y1580670D03*
Y1585788D03*
Y1596024D03*
X1703503Y1596811D03*
Y1607048D03*
Y1612166D03*
X1694842Y1601142D03*
Y1611378D03*
Y1616496D03*
X1712165Y1462953D03*
Y1468071D03*
Y1478308D03*
Y1483426D03*
Y1493662D03*
Y1498780D03*
Y1509016D03*
Y1514134D03*
Y1565315D03*
Y1570434D03*
Y1580670D03*
Y1585788D03*
Y1596024D03*
Y1601142D03*
Y1611378D03*
Y1616496D03*
G54D80*
X721756Y-31826D03*
X841756Y-71006D03*
X1005256Y-41826D03*
X1075256Y-81006D03*
X1291756Y-41956D03*
X1331756Y-81006D03*
X1576256Y-42086D03*
X1586256Y-81006D03*
G54D71*
X420661Y1119422D03*
X423141Y1113822D03*
Y1119422D03*
X418181Y1113822D03*
Y1119422D03*
X420661Y1113822D03*
X455269Y1119422D03*
X450309Y1113822D03*
Y1119422D03*
X452789Y1113822D03*
Y1119422D03*
X455269Y1113822D03*
X488728Y1119422D03*
X483768Y1113822D03*
X486248D03*
Y1119422D03*
X483768D03*
X488728Y1113822D03*
X515484Y695757D03*
X515504Y701351D03*
X521159Y706388D03*
X515649D03*
X523929D03*
X518389D03*
X518376Y1113822D03*
Y1119422D03*
X520856Y1113822D03*
Y1119422D03*
X515896Y1113822D03*
Y1119422D03*
X529469Y706230D03*
X526699Y706388D03*
X1332355Y1113822D03*
Y1119422D03*
X1334835Y1113822D03*
Y1119422D03*
X1337315Y1113822D03*
Y1119422D03*
X1366963D03*
Y1113822D03*
X1364483Y1119422D03*
Y1113822D03*
X1369443Y1119422D03*
Y1113822D03*
X1397942Y1119422D03*
X1400422D03*
Y1113822D03*
X1397942D03*
X1402902Y1119422D03*
Y1113822D03*
X1432550Y1119422D03*
Y1113822D03*
X1430070Y1119422D03*
Y1113822D03*
X1435030Y1119422D03*
Y1113822D03*
G54D26*
X28216Y1323770D03*
X96116Y21782D03*
X105562Y825539D03*
X521365Y331801D03*
X658199Y944517D03*
X787032Y1631625D03*
X828878Y560702D03*
X906500Y61964D03*
X1244161Y960023D03*
X1308242Y547162D03*
X1349086Y176019D03*
X1680546Y34636D03*
X1779102Y1562706D03*
X1795900Y852600D03*
G54D90*
X895542Y859465D03*
X892392D03*
X895542Y856316D03*
X892392D03*
X895542Y862615D03*
X892392D03*
X895542Y868914D03*
X892392D03*
X910029Y836875D03*
X906879D03*
X920739Y846867D03*
X917589D03*
X920739Y853166D03*
X917589D03*
X945122Y860671D03*
X945030Y864721D03*
X945147Y868168D03*
X948272Y860671D03*
X948180Y864721D03*
X948297Y868168D03*
X1318541Y863128D03*
X1321691D03*
X1349976Y840894D03*
X1346826D03*
X1359425Y878689D03*
X1356275D03*
X1378266Y844021D03*
X1375116D03*
X1381461Y885021D03*
X1378311D03*
X1393970Y862829D03*
X1390820D03*
X1393947Y866620D03*
X1390797D03*
X1393001Y871018D03*
X1389851D03*
X1392988Y876204D03*
X1389838D03*
G54D63*
X372028Y1534029D03*
G54D18*
X15713Y1116633D03*
Y1125633D03*
X15767Y1134705D03*
Y1142705D03*
X17767Y1503569D03*
X22713Y1116633D03*
Y1125633D03*
X22767Y1134705D03*
Y1142705D03*
X24767Y1503569D03*
X49542Y1110100D03*
Y1119100D03*
X49701Y1129688D03*
Y1137688D03*
X56542Y1110100D03*
Y1119100D03*
X56701Y1129688D03*
Y1137688D03*
X398190Y1093068D03*
X405190D03*
X398184Y1085881D03*
X405184D03*
X397068Y1291261D03*
X404068D03*
X425725Y1331356D03*
X439744Y1093088D03*
X432725Y1331356D03*
X446744Y1093088D03*
X463777Y1093068D03*
X470777D03*
X505331Y1093088D03*
X505189Y1085890D03*
X512331Y1093088D03*
X512189Y1085890D03*
X862403Y1125636D03*
Y1134636D03*
X862580Y1152080D03*
Y1144080D03*
X869403Y1125636D03*
Y1134636D03*
X869580Y1152080D03*
Y1144080D03*
X896232Y1119103D03*
Y1128103D03*
X896701Y1141169D03*
Y1149169D03*
X903232Y1119103D03*
Y1128103D03*
X903701Y1141169D03*
Y1149169D03*
X926380Y1125636D03*
Y1134636D03*
X926558Y1143708D03*
Y1151708D03*
X933380Y1125636D03*
Y1134636D03*
X933558Y1143708D03*
Y1151708D03*
X960209Y1119103D03*
X960678Y1141169D03*
X960209Y1128103D03*
X960678Y1149169D03*
X967209Y1119103D03*
X967678Y1141169D03*
X967209Y1128103D03*
X967678Y1149169D03*
X1312364Y1093068D03*
X1319364D03*
X1312358Y1085881D03*
X1319358D03*
X1360918Y1093088D03*
X1353918D03*
X1377951Y1093068D03*
X1384951D03*
X1426363Y1085890D03*
X1419363D03*
X1426505Y1093088D03*
X1419505D03*
X1776360Y1126122D03*
X1783360D03*
X1776360Y1135122D03*
X1783360D03*
X1776360Y1151822D03*
X1783360D03*
X1776360Y1143822D03*
X1783360D03*
X1815189Y1119589D03*
X1808189D03*
X1815189Y1128589D03*
X1808189D03*
X1815189Y1140912D03*
X1808189D03*
X1815189Y1148912D03*
X1808189D03*
G54D81*
X725006Y-30842D03*
Y-32810D03*
X845006Y-70022D03*
Y-71990D03*
X949942Y-32782D03*
Y-30814D03*
X974786Y-71962D03*
Y-69994D03*
X1008506Y-40842D03*
Y-42810D03*
X1078506Y-80022D03*
Y-81990D03*
X1228086Y-81962D03*
Y-79994D03*
X1233442Y-42912D03*
Y-40944D03*
X1295006Y-40972D03*
Y-42940D03*
X1335006Y-80022D03*
Y-81990D03*
X1484586Y-81962D03*
Y-79994D03*
X1519942Y-43042D03*
Y-41074D03*
X1579506Y-41102D03*
Y-43070D03*
X1589506Y-80022D03*
Y-81990D03*
X1739086Y-81962D03*
Y-79994D03*
X1804442Y-43172D03*
Y-41204D03*
G54D36*
X65265Y822718D03*
X68869Y876608D03*
X56903Y905500D03*
Y901500D03*
X75981Y874859D03*
X85697Y664443D03*
X193616Y594400D03*
Y602400D03*
Y598400D03*
Y606400D03*
Y610400D03*
Y614400D03*
X216241Y623398D03*
X241025Y427029D03*
Y435029D03*
Y431029D03*
X274516Y388000D03*
Y384500D03*
X268879Y442606D03*
Y446606D03*
X270186Y463479D03*
X279171Y463235D03*
X281016Y388000D03*
X286987Y455152D03*
Y451152D03*
X388793Y1392591D03*
X388498Y1485778D03*
X387891Y1482239D03*
X400155Y1297965D03*
X395020Y1307238D03*
X401524Y1313443D03*
X395494Y1497835D03*
X422224Y1366972D03*
X413400Y1541221D03*
Y1547198D03*
X435850Y333907D03*
X436180Y342874D03*
X435068Y349675D03*
X429788Y1389026D03*
Y1385026D03*
X455714Y1197471D03*
X445422Y1293045D03*
X461717Y644087D03*
X468388Y1193471D03*
X488009Y791025D03*
X504157Y697405D03*
X503402Y712755D03*
Y708755D03*
X493450Y1024165D03*
X493438Y1028165D03*
X522240Y671119D03*
X514773Y831662D03*
X513843Y901500D03*
Y905500D03*
X525999Y600790D03*
X534257Y792649D03*
X525809Y876608D03*
X532921Y874859D03*
X541220Y830889D03*
Y835389D03*
X582319Y936807D03*
X650702Y594400D03*
Y602400D03*
Y598400D03*
Y606400D03*
Y610400D03*
Y614400D03*
X697035Y766471D03*
Y753471D03*
X697021Y771159D03*
Y784659D03*
X731602Y388000D03*
Y384500D03*
X727272Y463479D03*
X738102Y388000D03*
X744073Y455152D03*
Y451152D03*
X736257Y463235D03*
X780208Y1442282D03*
X780168Y1446194D03*
X796284Y1436240D03*
X813910Y869079D03*
X809983Y915705D03*
X815448Y920026D03*
X803150Y1429135D03*
X827637Y848986D03*
X827094Y880390D03*
X818513Y893885D03*
X822864Y921393D03*
X846864Y827419D03*
X840780Y847531D03*
X840253Y863413D03*
X840300Y871459D03*
X840253Y867413D03*
X841160Y1454159D03*
X853775Y863459D03*
Y859459D03*
Y871459D03*
Y879459D03*
Y867459D03*
X853766Y875468D03*
X864346Y869142D03*
X862765Y878942D03*
X853809Y892738D03*
X853806Y887707D03*
X853775Y883459D03*
X883760Y1456859D03*
X900965Y556363D03*
X911515Y578394D03*
X911465Y582863D03*
X911515Y586616D03*
X900683Y892455D03*
X900667Y884516D03*
X927712Y360129D03*
X927340Y366617D03*
X923296Y371739D03*
X914444Y817982D03*
X914344Y822083D03*
X934075Y1394627D03*
Y1398427D03*
Y1402227D03*
Y1406027D03*
X957449Y923116D03*
X971349Y901500D03*
Y905500D03*
X989975Y768775D03*
X982895Y876608D03*
X997723Y870398D03*
X1023935Y933822D03*
X1027311Y954222D03*
X1033822Y324752D03*
X1033801Y337736D03*
X1033868Y333519D03*
X1088806Y1537257D03*
X1107789Y594400D03*
Y602400D03*
Y598400D03*
Y606400D03*
Y610400D03*
Y614400D03*
X1098316Y1513398D03*
X1128691Y768859D03*
X1155198Y427029D03*
Y431029D03*
Y435029D03*
X1146001Y800642D03*
Y806642D03*
X1188689Y384500D03*
Y388000D03*
X1184359Y463479D03*
X1195189Y388000D03*
X1201160Y455152D03*
Y451152D03*
X1193344Y463235D03*
X1198235Y953789D03*
Y982789D03*
X1276233Y905173D03*
X1296516Y879800D03*
X1287980Y885651D03*
X1296516Y887800D03*
Y883800D03*
X1296970Y911478D03*
X1303016Y944000D03*
X1338435Y336999D03*
X1338765Y345966D03*
X1337653Y352767D03*
X1365716Y1422900D03*
X1382949Y561000D03*
Y607500D03*
X1382562Y1193471D03*
X1369888Y1197471D03*
X1402155Y961181D03*
X1407522Y1024254D03*
Y1028267D03*
X1428016Y905500D03*
Y901500D03*
X1442049Y601079D03*
X1439982Y876608D03*
X1447094Y874859D03*
X1440516Y931500D03*
Y936000D03*
X1479532Y959013D03*
X1491562Y327200D03*
X1492016Y318000D03*
X1485079Y880839D03*
Y870339D03*
X1492079Y880839D03*
Y870339D03*
X1499016Y920000D03*
X1505979Y958240D03*
Y962740D03*
X1564876Y602400D03*
Y598400D03*
Y594400D03*
Y606400D03*
Y610400D03*
Y614400D03*
X1612285Y427029D03*
Y431029D03*
Y435029D03*
X1640139Y442606D03*
Y446606D03*
X1641446Y463479D03*
X1652276Y388000D03*
X1645776D03*
Y384500D03*
X1658247Y455152D03*
Y451152D03*
X1650431Y463235D03*
X1789490Y989590D03*
X1798579Y964660D03*
X1801955Y985060D03*
G54D27*
X35744Y1498350D03*
X23451Y1534239D03*
X49049Y842234D03*
X43871Y1498355D03*
X51446Y1498614D03*
X59104Y871118D03*
X63745Y880158D03*
X64007Y1219595D03*
X94962Y868330D03*
X99055Y868297D03*
X95352Y897516D03*
X91387D03*
X163539Y1135425D03*
X220500Y544016D03*
X243593Y599597D03*
X291444Y1176566D03*
X302457Y448721D03*
X298507D03*
X298125Y1139165D03*
Y1146645D03*
X391757Y1377966D03*
X408459Y1355067D03*
X404459D03*
X399959D03*
X402189Y1407662D03*
X406189D03*
X404052Y1550463D03*
X423904Y347500D03*
X425433Y1109414D03*
X410866Y1285879D03*
X414431Y1326874D03*
X418431D03*
X412779Y1365150D03*
X423517Y1376093D03*
X414203Y1410818D03*
X418203D03*
X415823Y1556287D03*
X428785Y1115912D03*
X431620Y1108989D03*
X437912Y1289289D03*
X436485Y1319310D03*
X454591Y1007282D03*
X447091Y1014282D03*
X443591D03*
X457577Y1109409D03*
X460913Y1115912D03*
X463966Y1108911D03*
X478907Y1024143D03*
X484115Y1023985D03*
X491069Y1109422D03*
X494372Y1115912D03*
X496372Y1108912D03*
X515381Y685902D03*
X513775Y673471D03*
X517775D03*
X509791Y717432D03*
X520685Y880158D03*
X516044Y871118D03*
X523200Y1109434D03*
X532248Y684313D03*
X533023Y715258D03*
X525241Y793665D03*
X534241Y822665D03*
X525741Y821165D03*
X526500Y1115912D03*
X528500Y1108912D03*
X556174Y787931D03*
X548665Y844834D03*
X555995Y868297D03*
X551902Y868330D03*
X548327Y897516D03*
X552292D03*
X558241Y840665D03*
X566231Y844812D03*
X566103Y956323D03*
X583501Y811064D03*
X620866Y1135425D03*
X677586Y544016D03*
X748531Y1176566D03*
X759543Y448721D03*
X755593D03*
X755212Y1139165D03*
Y1146645D03*
X783659Y1019428D03*
X774367Y1451106D03*
X799631Y1019428D03*
X795631D03*
X800067Y961544D03*
X803673Y1019428D03*
X807673D03*
X811673D03*
X815673D03*
X825490Y886988D03*
X832258Y906565D03*
X825146Y969664D03*
X819673Y1019428D03*
X823673D03*
X827673D03*
X831673D03*
X835000Y763016D03*
X839000Y756016D03*
X835000Y781016D03*
X839000Y774016D03*
X835000Y799016D03*
X839000Y792016D03*
Y810016D03*
X835000Y817016D03*
X836258Y906601D03*
X832952Y942814D03*
X836952D03*
X880054Y761350D03*
X874851D03*
Y774074D03*
X880054Y774064D03*
X875095Y789792D03*
X894167Y590744D03*
X886610Y761349D03*
X885110Y774059D03*
X884894Y789792D03*
X894116D03*
X887916Y803406D03*
X912665Y353623D03*
X898384Y590811D03*
X907151Y590765D03*
X903766Y820506D03*
X899816D03*
X911286Y908853D03*
X903286D03*
X907286D03*
X918819Y368887D03*
X925755Y834472D03*
X916628Y922642D03*
X920628D03*
X924628D03*
X928628D03*
X937428Y205239D03*
X931124Y834472D03*
X931261Y880643D03*
X938752Y882077D03*
X932628Y922642D03*
X936628D03*
X949058Y919977D03*
X973130Y871118D03*
X977771Y880158D03*
X971672Y1228573D03*
X980081Y360398D03*
X1008988Y868330D03*
X1005413Y897516D03*
X1007719Y953338D03*
X1020345Y341217D03*
X1013081Y868297D03*
X1013897Y897212D03*
X1028830Y341160D03*
X1055521Y1435441D03*
X1077952Y1135425D03*
X1134673Y544016D03*
X1164197Y794426D03*
X1169697D03*
X1177431Y871329D03*
Y878829D03*
X1181151Y923550D03*
X1177186Y930550D03*
X1181151D03*
X1189219Y943305D03*
X1182779Y968759D03*
X1189219Y989805D03*
X1192431Y871329D03*
Y878829D03*
X1191151Y923550D03*
X1195118Y930550D03*
X1193219Y943305D03*
X1201219D03*
X1197219D03*
X1191151Y930550D03*
X1202719Y967805D03*
X1193219Y989805D03*
X1205617Y1176566D03*
X1216630Y448721D03*
X1212680D03*
X1207219Y967805D03*
X1212298Y1139165D03*
Y1146645D03*
X1269733Y864488D03*
X1289032Y863876D03*
X1315000Y816516D03*
X1319500D03*
X1326489Y350592D03*
X1324000Y816516D03*
X1328500D03*
X1333000D03*
X1342000D03*
X1346500D03*
X1351000D03*
X1337500D03*
X1342500Y918016D03*
X1346500D03*
X1350500D03*
X1342959Y1115912D03*
X1339685Y1109410D03*
X1344959Y1108912D03*
X1358500Y918016D03*
X1354500D03*
X1362500D03*
X1366500D03*
X1361265Y1014282D03*
X1357765D03*
X1373500Y816516D03*
X1382500Y918016D03*
X1370500D03*
X1378500D03*
X1368765Y1007282D03*
X1375087Y1115912D03*
X1371792Y1109411D03*
X1377087Y1108912D03*
X1386295Y918016D03*
X1393081Y1024143D03*
X1398289Y1023985D03*
X1408546Y1115912D03*
X1405189Y1109409D03*
X1410546Y1108912D03*
X1430444Y599741D03*
X1430217Y871118D03*
X1434858Y880158D03*
X1440674Y1115912D03*
X1437352Y1109435D03*
X1442674Y1108912D03*
X1462500Y897516D03*
X1470168Y868297D03*
X1466075Y868330D03*
X1466465Y897516D03*
X1491107Y884708D03*
X1487107D03*
X1490000Y921016D03*
X1490500Y948516D03*
X1499000Y950016D03*
X1513424Y972185D03*
X1525000Y893016D03*
X1529000D03*
X1520933Y915282D03*
X1523000Y968016D03*
X1533244Y971592D03*
X1535039Y1135425D03*
X1591760Y544016D03*
X1600008Y1480769D03*
X1596038D03*
X1669767Y448721D03*
X1673717D03*
X1669385Y1139165D03*
Y1146645D03*
X1662704Y1176566D03*
X1817832Y1209498D03*
G54D45*
X109882Y1622402D03*
X283110D03*
X456339D03*
X629567D03*
X1131850D03*
X1305079D03*
X1478307D03*
X1651535D03*
G54D54*
X208035Y1516515D03*
X1460832Y763285D03*
X1459752Y806881D03*
X1626782Y659526D03*
X1763546Y802817D03*
G54D72*
X419061Y1143544D03*
Y1168740D03*
X446889Y1143544D03*
Y1168740D03*
X484648Y1143544D03*
Y1168740D03*
X512476Y1143544D03*
Y1168740D03*
X1333235Y1143544D03*
Y1168740D03*
X1361063Y1143544D03*
Y1168740D03*
X1398822Y1143544D03*
Y1168740D03*
X1426650Y1143544D03*
Y1168740D03*
G54D64*
X391691Y1321645D03*
X399171D03*
X897709Y545863D03*
X905189D03*
X1042180Y350954D03*
X1046180Y310454D03*
X1053660D03*
X1049660Y350954D03*
G54D19*
X11184Y1503268D03*
Y1510748D03*
X51043Y1543839D03*
Y1536359D03*
X424559Y1404286D03*
Y1411766D03*
X880949Y599123D03*
Y606603D03*
X921449Y603123D03*
Y610603D03*
X988920Y326714D03*
Y334194D03*
G54D82*
X770472Y1490945D03*
X820079Y388583D03*
X1020866D03*
X1070472Y1490945D03*
G54D55*
X228024Y602656D03*
Y607774D03*
Y605215D03*
X236686Y602656D03*
Y607774D03*
G54D73*
X414519Y1253318D03*
Y1261804D03*
X512430Y1253318D03*
Y1261804D03*
X1328693Y1253318D03*
Y1261804D03*
X1427004Y1253810D03*
Y1262296D03*
G54D37*
X68232Y822718D03*
X59870Y905500D03*
Y901500D03*
X71836Y876608D03*
X78948Y874859D03*
X88664Y664443D03*
X196583Y594400D03*
Y602400D03*
Y598400D03*
Y606400D03*
Y610400D03*
Y614400D03*
X219208Y623398D03*
X243992Y427029D03*
Y435029D03*
Y431029D03*
X277483Y388000D03*
Y384500D03*
X271846Y442606D03*
Y446606D03*
X273153Y463479D03*
X283983Y388000D03*
X289954Y455152D03*
Y451152D03*
X282138Y463235D03*
X391760Y1392591D03*
X391465Y1485778D03*
X390858Y1482239D03*
X403122Y1297965D03*
X397987Y1307238D03*
X404491Y1313443D03*
X398461Y1497835D03*
X425191Y1366972D03*
X416367Y1541221D03*
Y1547198D03*
X438817Y333907D03*
X439147Y342874D03*
X438035Y349675D03*
X432755Y1389026D03*
Y1385026D03*
X458681Y1197471D03*
X448389Y1293045D03*
X464684Y644087D03*
X471355Y1193471D03*
X490976Y791025D03*
X507124Y697405D03*
X506369Y712755D03*
Y708755D03*
X496417Y1024165D03*
X496405Y1028165D03*
X517740Y831662D03*
X516810Y901500D03*
Y905500D03*
X528966Y600790D03*
X525207Y671119D03*
X537224Y792649D03*
X528776Y876608D03*
X535888Y874859D03*
X544187Y830889D03*
Y835389D03*
X585286Y936807D03*
X653669Y594400D03*
Y602400D03*
Y598400D03*
Y606400D03*
Y610400D03*
Y614400D03*
X700002Y766471D03*
Y753471D03*
X699988Y771159D03*
Y784659D03*
X734569Y388000D03*
Y384500D03*
X730239Y463479D03*
X741069Y388000D03*
X747040Y455152D03*
Y451152D03*
X739224Y463235D03*
X783175Y1442282D03*
X783135Y1446194D03*
X799251Y1436240D03*
X812950Y915705D03*
X806117Y1429135D03*
X830604Y848986D03*
X830061Y880390D03*
X816877Y869079D03*
X821480Y893885D03*
X825831Y921393D03*
X818415Y920026D03*
X843747Y847531D03*
X843220Y863413D03*
X843267Y871459D03*
X843220Y867413D03*
X844127Y1454159D03*
X849831Y827419D03*
X856742Y863459D03*
Y859459D03*
Y871459D03*
Y879459D03*
Y867459D03*
X856733Y875468D03*
X856776Y892738D03*
X856773Y887707D03*
X856742Y883459D03*
X867313Y869142D03*
X865732Y878942D03*
X886727Y1456859D03*
X903932Y556363D03*
X903650Y892455D03*
X903634Y884516D03*
X926263Y371739D03*
X914482Y578394D03*
X914432Y582863D03*
X914482Y586616D03*
X917411Y817982D03*
X917311Y822083D03*
X930679Y360129D03*
X930307Y366617D03*
X937042Y1394627D03*
Y1398427D03*
Y1402227D03*
Y1406027D03*
X960416Y923116D03*
X974316Y901500D03*
Y905500D03*
X992942Y768775D03*
X985862Y876608D03*
X1000690Y870398D03*
X1026902Y933822D03*
X1036789Y324752D03*
X1036768Y337736D03*
X1036835Y333519D03*
X1030278Y954222D03*
X1091773Y1537257D03*
X1101283Y1513398D03*
X1110756Y594400D03*
Y602400D03*
Y598400D03*
Y606400D03*
Y610400D03*
Y614400D03*
X1131658Y768859D03*
X1148968Y800642D03*
Y806642D03*
X1158165Y427029D03*
Y431029D03*
Y435029D03*
X1187326Y463479D03*
X1198156Y388000D03*
X1191656Y384500D03*
Y388000D03*
X1204127Y455152D03*
Y451152D03*
X1196311Y463235D03*
X1201202Y953789D03*
Y982789D03*
X1279200Y905173D03*
X1299483Y879800D03*
X1290947Y885651D03*
X1299483Y887800D03*
Y883800D03*
X1299937Y911478D03*
X1305983Y944000D03*
X1341402Y336999D03*
X1341732Y345966D03*
X1340620Y352767D03*
X1372855Y1197471D03*
X1368683Y1422900D03*
X1385916Y561000D03*
Y607500D03*
X1385529Y1193471D03*
X1405122Y961181D03*
X1410489Y1024254D03*
Y1028267D03*
X1430983Y905500D03*
Y901500D03*
X1445016Y601079D03*
X1442949Y876608D03*
X1443483Y931500D03*
Y936000D03*
X1450061Y874859D03*
X1494529Y327200D03*
X1494983Y318000D03*
X1488046Y880839D03*
Y870339D03*
X1495046Y880839D03*
Y870339D03*
X1482499Y959013D03*
X1501983Y920000D03*
X1508946Y958240D03*
Y962740D03*
X1567843Y602400D03*
Y598400D03*
Y594400D03*
Y606400D03*
Y610400D03*
Y614400D03*
X1615252Y427029D03*
Y431029D03*
Y435029D03*
X1643106Y442606D03*
Y446606D03*
X1644413Y463479D03*
X1655243Y388000D03*
X1648743D03*
Y384500D03*
X1653398Y463235D03*
X1661214Y455152D03*
Y451152D03*
X1801546Y964660D03*
X1792457Y989590D03*
X1804922Y985060D03*
G54D28*
X35744Y1501317D03*
X23451Y1537206D03*
X49049Y845201D03*
X51446Y1501581D03*
X43871Y1501322D03*
X59104Y874085D03*
X63745Y883125D03*
X64007Y1222562D03*
X94962Y871297D03*
X99055Y871264D03*
X95352Y900483D03*
X91387D03*
X163539Y1138392D03*
X220500Y546983D03*
X243593Y602564D03*
X291444Y1179533D03*
X302457Y451688D03*
X298507D03*
X298125Y1142132D03*
Y1149612D03*
X391757Y1380933D03*
X408459Y1358034D03*
X404459D03*
X399959D03*
X402189Y1410629D03*
X406189D03*
X404052Y1553430D03*
X423904Y350467D03*
X425433Y1112381D03*
X410866Y1288846D03*
X414431Y1329841D03*
X418431D03*
X412779Y1368117D03*
X423517Y1379060D03*
X414203Y1413785D03*
X418203D03*
X415823Y1559254D03*
X428785Y1118879D03*
X431620Y1111956D03*
X437912Y1292256D03*
X436485Y1322277D03*
X454591Y1010249D03*
X447091Y1017249D03*
X443591D03*
X457577Y1112376D03*
X460913Y1118879D03*
X463966Y1111878D03*
X478907Y1027110D03*
X484115Y1026952D03*
X491069Y1112389D03*
X494372Y1118879D03*
X496372Y1111879D03*
X513775Y676438D03*
X517775D03*
X515381Y688869D03*
X509791Y720399D03*
X516044Y874085D03*
X520685Y883125D03*
X523200Y1112401D03*
X532248Y687280D03*
X533023Y718225D03*
X525241Y796632D03*
X534241Y825632D03*
X525741Y824132D03*
X526500Y1118879D03*
X528500Y1111879D03*
X556174Y790898D03*
X548665Y847801D03*
X555995Y871264D03*
X551902Y871297D03*
X548327Y900483D03*
X552292D03*
X558241Y843632D03*
X566231Y847779D03*
X566103Y959290D03*
X583501Y814031D03*
X620866Y1138392D03*
X677586Y546983D03*
X748531Y1179533D03*
X759543Y451688D03*
X755593D03*
X755212Y1142132D03*
Y1149612D03*
X783659Y1022395D03*
X774367Y1454073D03*
X799631Y1022395D03*
X795631D03*
X800067Y964511D03*
X803673Y1022395D03*
X807673D03*
X811673D03*
X815673D03*
X825490Y889955D03*
X832258Y909532D03*
X825146Y972631D03*
X819673Y1022395D03*
X823673D03*
X827673D03*
X831673D03*
X835000Y765983D03*
X839000Y758983D03*
Y776983D03*
X835000Y783983D03*
X839000Y794983D03*
X835000Y801983D03*
X839000Y812983D03*
X835000Y819983D03*
X836258Y909568D03*
X832952Y945781D03*
X836952D03*
X880054Y764317D03*
X874851D03*
Y777041D03*
X880054Y777031D03*
X875095Y792759D03*
X894167Y593711D03*
X886610Y764316D03*
X885110Y777026D03*
X884894Y792759D03*
X894116D03*
X887916Y806373D03*
X912665Y356590D03*
X898384Y593778D03*
X907151Y593732D03*
X903766Y823473D03*
X899816D03*
X911286Y911820D03*
X903286D03*
X907286D03*
X918819Y371854D03*
X925755Y837439D03*
X916628Y925609D03*
X920628D03*
X924628D03*
X928628D03*
X937428Y208206D03*
X931124Y837439D03*
X938752Y885044D03*
X931261Y883610D03*
X932628Y925609D03*
X936628D03*
X949058Y922944D03*
X973130Y874085D03*
X977771Y883125D03*
X971672Y1231540D03*
X980081Y363365D03*
X1008988Y871297D03*
X1005413Y900483D03*
X1007719Y956305D03*
X1020345Y344184D03*
X1013081Y871264D03*
X1013897Y900179D03*
X1028830Y344127D03*
X1055521Y1438408D03*
X1077952Y1138392D03*
X1134673Y546983D03*
X1164197Y797393D03*
X1169697D03*
X1177431Y874296D03*
Y881796D03*
X1181151Y926517D03*
X1177186Y933517D03*
X1181151D03*
X1189219Y946272D03*
X1182779Y971726D03*
X1189219Y992772D03*
X1192431Y874296D03*
Y881796D03*
X1191151Y926517D03*
X1195118Y933517D03*
X1191151D03*
X1193219Y946272D03*
X1201219D03*
X1197219D03*
X1202719Y970772D03*
X1193219Y992772D03*
X1205617Y1179533D03*
X1216630Y451688D03*
X1212680D03*
X1207219Y970772D03*
X1212298Y1142132D03*
Y1149612D03*
X1269733Y867455D03*
X1289032Y866843D03*
X1315000Y819483D03*
X1319500D03*
X1326489Y353559D03*
X1324000Y819483D03*
X1328500D03*
X1333000D03*
X1342000D03*
X1346500D03*
X1351000D03*
X1337500D03*
X1342500Y920983D03*
X1346500D03*
X1350500D03*
X1342959Y1118879D03*
X1339685Y1112377D03*
X1344959Y1111879D03*
X1358500Y920983D03*
X1354500D03*
X1362500D03*
X1366500D03*
X1361265Y1017249D03*
X1357765D03*
X1373500Y819483D03*
X1382500Y920983D03*
X1370500D03*
X1378500D03*
X1368765Y1010249D03*
X1375087Y1118879D03*
X1371792Y1112378D03*
X1377087Y1111879D03*
X1386295Y920983D03*
X1393081Y1027110D03*
X1398289Y1026952D03*
X1408546Y1118879D03*
X1405189Y1112376D03*
X1410546Y1111879D03*
X1430444Y602708D03*
X1430217Y874085D03*
X1434858Y883125D03*
X1440674Y1118879D03*
X1437352Y1112402D03*
X1442674Y1111879D03*
X1462500Y900483D03*
X1470168Y871264D03*
X1466075Y871297D03*
X1466465Y900483D03*
X1491107Y887675D03*
X1487107D03*
X1490000Y923983D03*
X1490500Y951483D03*
X1499000Y952983D03*
X1513424Y975152D03*
X1525000Y895983D03*
X1529000D03*
X1520933Y918249D03*
X1523000Y970983D03*
X1533244Y974559D03*
X1535039Y1138392D03*
X1591760Y546983D03*
X1600008Y1483736D03*
X1596038D03*
X1669767Y451688D03*
X1673717D03*
X1669385Y1142132D03*
Y1149612D03*
X1662704Y1179533D03*
X1817832Y1212465D03*
G54D46*
X118543Y1452717D03*
X127205Y1622402D03*
X135866Y1452717D03*
X144528Y1622402D03*
X153189Y1452717D03*
X161850Y1622402D03*
X170512Y1452717D03*
X179173Y1489331D03*
Y1494449D03*
Y1504685D03*
Y1509804D03*
Y1560985D03*
Y1566103D03*
Y1576339D03*
Y1581457D03*
Y1591693D03*
Y1596811D03*
Y1607048D03*
Y1612166D03*
Y1622402D03*
X187835Y1452717D03*
Y1493662D03*
Y1498780D03*
Y1509016D03*
Y1514134D03*
Y1565315D03*
Y1570434D03*
Y1580670D03*
Y1585788D03*
X291771Y1452717D03*
X309094D03*
X300433Y1622402D03*
X326417Y1452717D03*
X317756Y1622402D03*
X343740Y1452717D03*
X335078Y1622402D03*
X361063Y1452717D03*
X352401Y1458622D03*
Y1463741D03*
X361063Y1462953D03*
Y1468071D03*
X352401Y1473977D03*
Y1479095D03*
X361063Y1478308D03*
Y1483426D03*
X352401Y1489331D03*
Y1494449D03*
X361063Y1493662D03*
Y1498780D03*
X352401Y1504685D03*
Y1509804D03*
X361063Y1509016D03*
Y1514134D03*
X352401Y1560985D03*
Y1566103D03*
X361063Y1565315D03*
Y1570434D03*
X352401Y1576339D03*
Y1581457D03*
X361063Y1580670D03*
Y1585788D03*
X352401Y1591693D03*
Y1596811D03*
Y1607048D03*
Y1612166D03*
Y1622402D03*
X465000Y1452717D03*
X473662Y1622402D03*
X482323Y1452717D03*
X490985Y1622402D03*
X499646Y1452717D03*
X516969D03*
X508307Y1622402D03*
X534292Y1452717D03*
X525630Y1458622D03*
Y1463741D03*
X534292Y1462953D03*
Y1468071D03*
X525630Y1473977D03*
Y1479095D03*
X534292Y1478308D03*
Y1483426D03*
X525630Y1489331D03*
Y1494449D03*
X534292Y1493662D03*
Y1498780D03*
X525630Y1504685D03*
Y1509804D03*
X534292Y1509016D03*
Y1514134D03*
X525630Y1560985D03*
Y1566103D03*
X534292Y1565315D03*
Y1570434D03*
X525630Y1576339D03*
Y1581457D03*
X534292Y1580670D03*
Y1585788D03*
X525630Y1591693D03*
X534292Y1596024D03*
X525630Y1596811D03*
X534292Y1601142D03*
X525630Y1607048D03*
Y1612166D03*
X534292Y1611378D03*
Y1616496D03*
X525630Y1622402D03*
X638228Y1452717D03*
X646890Y1622402D03*
X655551Y1452717D03*
X664213Y1622402D03*
X672874Y1452717D03*
X681535Y1622402D03*
X698858Y1458622D03*
Y1463741D03*
X690197Y1452717D03*
X698858Y1473977D03*
Y1479095D03*
Y1489331D03*
Y1494449D03*
Y1504685D03*
Y1509804D03*
Y1560985D03*
Y1566103D03*
Y1576339D03*
Y1581457D03*
Y1591693D03*
Y1596811D03*
Y1607048D03*
Y1612166D03*
Y1622402D03*
X707520Y1452717D03*
Y1462953D03*
Y1468071D03*
Y1478308D03*
Y1483426D03*
Y1493662D03*
Y1498780D03*
Y1509016D03*
Y1514134D03*
Y1565315D03*
Y1570434D03*
Y1580670D03*
Y1585788D03*
Y1596024D03*
Y1601142D03*
Y1611378D03*
Y1616496D03*
X1140511Y1452717D03*
X1149173Y1622402D03*
X1157834Y1452717D03*
X1166496Y1622402D03*
X1175157Y1452717D03*
X1183818Y1622402D03*
X1201141Y1458622D03*
Y1463741D03*
X1192480Y1452717D03*
X1201141Y1473977D03*
Y1479095D03*
Y1489331D03*
Y1494449D03*
Y1504685D03*
Y1509804D03*
Y1560985D03*
Y1566103D03*
Y1576339D03*
Y1581457D03*
Y1591693D03*
Y1596811D03*
Y1607048D03*
Y1612166D03*
Y1622402D03*
X1209803Y1452717D03*
Y1462953D03*
Y1468071D03*
Y1478308D03*
Y1483426D03*
Y1493662D03*
Y1498780D03*
Y1509016D03*
Y1514134D03*
Y1565315D03*
Y1570434D03*
Y1580670D03*
Y1585788D03*
Y1596024D03*
Y1601142D03*
Y1611378D03*
Y1616496D03*
X1313740Y1452717D03*
X1331063D03*
X1322402Y1622402D03*
X1348386Y1452717D03*
X1339725Y1622402D03*
X1365709Y1452717D03*
X1357047Y1622402D03*
X1383032Y1452717D03*
X1374370Y1458622D03*
Y1463741D03*
X1383032Y1462953D03*
Y1468071D03*
X1374370Y1473977D03*
Y1479095D03*
X1383032Y1478308D03*
Y1483426D03*
X1374370Y1489331D03*
Y1494449D03*
X1383032Y1493662D03*
Y1498780D03*
X1374370Y1504685D03*
Y1509804D03*
X1383032Y1509016D03*
Y1514134D03*
X1374370Y1560985D03*
Y1566103D03*
X1383032Y1565315D03*
Y1570434D03*
X1374370Y1576339D03*
Y1581457D03*
X1383032Y1580670D03*
Y1585788D03*
X1374370Y1591693D03*
X1383032Y1596024D03*
X1374370Y1596811D03*
X1383032Y1601142D03*
X1374370Y1607048D03*
Y1612166D03*
X1383032Y1611378D03*
Y1616496D03*
X1374370Y1622402D03*
X1486968Y1452717D03*
X1495630Y1622402D03*
X1504291Y1452717D03*
X1512953Y1622402D03*
X1521614Y1452717D03*
X1530275Y1622402D03*
X1538937Y1452717D03*
X1556260D03*
X1547598Y1458622D03*
Y1463741D03*
X1556260Y1462953D03*
Y1468071D03*
X1547598Y1473977D03*
Y1479095D03*
X1556260Y1478308D03*
Y1483426D03*
X1547598Y1489331D03*
Y1494449D03*
X1556260Y1493662D03*
Y1498780D03*
X1547598Y1504685D03*
Y1509804D03*
X1556260Y1509016D03*
Y1514134D03*
X1547598Y1560985D03*
Y1566103D03*
X1556260Y1565315D03*
Y1570434D03*
X1547598Y1576339D03*
Y1581457D03*
X1556260Y1580670D03*
Y1585788D03*
X1547598Y1591693D03*
X1556260Y1596024D03*
X1547598Y1596811D03*
X1556260Y1601142D03*
X1547598Y1607048D03*
Y1612166D03*
X1556260Y1611378D03*
Y1616496D03*
X1547598Y1622402D03*
X1660196Y1452717D03*
X1668858Y1622402D03*
X1677519Y1452717D03*
X1686181Y1622402D03*
X1694842Y1452717D03*
X1703503Y1622402D03*
X1720826Y1458622D03*
Y1463741D03*
X1712165Y1452717D03*
X1720826Y1473977D03*
Y1479095D03*
Y1489331D03*
Y1494449D03*
Y1504685D03*
Y1509804D03*
Y1560985D03*
Y1566103D03*
Y1576339D03*
Y1581457D03*
Y1591693D03*
Y1596811D03*
Y1607048D03*
Y1612166D03*
Y1622402D03*
X1729488Y1452717D03*
Y1462953D03*
Y1468071D03*
Y1478308D03*
Y1483426D03*
Y1493662D03*
Y1498780D03*
Y1509016D03*
Y1514134D03*
Y1565315D03*
Y1570434D03*
Y1580670D03*
Y1585788D03*
Y1596024D03*
Y1601142D03*
Y1611378D03*
Y1616496D03*
G54D91*
X909360Y230906D03*
Y274606D03*
G54D29*
X28774Y1529931D03*
Y1522774D03*
X63624Y847627D03*
X59871Y897500D03*
X61977Y1511735D03*
X63463Y1525714D03*
X63487Y1518596D03*
X63437Y1531804D03*
X90097Y681800D03*
X98773Y875194D03*
Y879194D03*
X118577Y892845D03*
Y884845D03*
Y888845D03*
X159189Y1148530D03*
X159648Y1164560D03*
X159433Y1160650D03*
X159648Y1169100D03*
X183084Y550400D03*
Y554400D03*
X193870Y544967D03*
X196584Y618400D03*
X200870Y544967D03*
X261628Y438323D03*
X251025Y427017D03*
X250993Y435029D03*
Y431029D03*
X283984Y384500D03*
X282156Y467367D03*
X306767Y377912D03*
Y389912D03*
Y381912D03*
Y385912D03*
Y393924D03*
Y397912D03*
Y401924D03*
Y405924D03*
Y409924D03*
X392639Y1311289D03*
Y1315289D03*
X388462Y1384722D03*
Y1388722D03*
X395795Y1299275D03*
Y1303275D03*
X400001Y1540700D03*
Y1535200D03*
Y1547200D03*
X420633Y343005D03*
X421054Y334523D03*
X421564Y1111226D03*
X425491Y1288843D03*
X425192Y1370972D03*
X431177Y349696D03*
X438307Y1309865D03*
X428437Y1320684D03*
X433066Y1398800D03*
X433042Y1394934D03*
X453585Y1111226D03*
X458682Y1193471D03*
X448390Y1301545D03*
Y1297045D03*
Y1305545D03*
X462369Y1007325D03*
X459269Y1002180D03*
X467575Y1014566D03*
X471356Y1197471D03*
X490977Y795025D03*
X487036Y1111177D03*
X506370Y704755D03*
X500091Y790275D03*
X509225Y796149D03*
X515420Y799973D03*
Y811973D03*
Y803973D03*
Y807973D03*
X516811Y897500D03*
X519294Y1111272D03*
X536263Y708711D03*
X526013Y713581D03*
X532188Y831027D03*
X525188D03*
X532225Y836149D03*
Y840649D03*
X525225D03*
Y836149D03*
X531868Y849830D03*
X524868D03*
X555188Y796389D03*
X555713Y879194D03*
Y875194D03*
X575517Y888845D03*
Y884845D03*
Y892845D03*
X580884Y961804D03*
X616276Y1148530D03*
X616520Y1160650D03*
X616735Y1169100D03*
Y1164560D03*
X640170Y550400D03*
Y554400D03*
X650956Y544967D03*
X653670Y618400D03*
X657956Y544967D03*
X700003Y762971D03*
Y756971D03*
X699989Y780659D03*
Y775159D03*
X718714Y438323D03*
X728933Y442606D03*
Y446606D03*
X741070Y384500D03*
X739242Y467367D03*
X763853Y377912D03*
Y389912D03*
Y381912D03*
Y385912D03*
Y393924D03*
Y397912D03*
Y401924D03*
Y405924D03*
Y409924D03*
X806103Y1425152D03*
X806328Y1436240D03*
X802328Y1460979D03*
X831208Y859484D03*
X816878Y872812D03*
Y876605D03*
X845793Y835459D03*
Y839459D03*
X843748Y843490D03*
X843345Y855397D03*
X845793Y851459D03*
X845707Y875476D03*
X842942Y879459D03*
Y883459D03*
X842848Y891503D03*
X842849Y887490D03*
X834371Y1463690D03*
X864875Y388245D03*
X856743Y847459D03*
Y835459D03*
Y839459D03*
Y843459D03*
Y855459D03*
X856790Y851924D03*
X889535Y571532D03*
X890686Y577288D03*
X890743Y585773D03*
X886715Y1460847D03*
X903630Y888478D03*
X919957Y312228D03*
X915134Y360583D03*
X915365Y365893D03*
X926602Y1379411D03*
X926629Y1383264D03*
X926655Y1387039D03*
X926683Y1390841D03*
X936955Y1371951D03*
X937029Y1375878D03*
X941997Y1443901D03*
X974317Y897500D03*
X968042Y1444474D03*
X993684Y1369200D03*
Y1373400D03*
Y1385200D03*
Y1394200D03*
Y1389200D03*
X993655Y1398271D03*
X990227Y1444240D03*
X1010742Y327510D03*
Y323386D03*
Y333088D03*
Y339880D03*
X1005485Y801475D03*
X1009489Y816957D03*
X1012799Y875194D03*
Y879194D03*
X1014338Y1444512D03*
X1032603Y892845D03*
Y884845D03*
Y888845D03*
X1040004Y1444596D03*
X1046904Y337454D03*
X1073362Y1148530D03*
X1073821Y1164560D03*
Y1169100D03*
X1073606Y1160650D03*
X1091774Y1533457D03*
X1097257Y550400D03*
Y554400D03*
X1108043Y544967D03*
X1115043D03*
X1110757Y618400D03*
X1155501Y788431D03*
X1148969Y797142D03*
Y810142D03*
X1165198Y427017D03*
X1165166Y431029D03*
Y435029D03*
X1175801Y438323D03*
X1186020Y442606D03*
Y446606D03*
X1179636Y888899D03*
X1198157Y384500D03*
X1196329Y467367D03*
X1220940Y377912D03*
Y389912D03*
Y381912D03*
Y385912D03*
Y393924D03*
Y397912D03*
Y401924D03*
Y405924D03*
Y409924D03*
X1263714Y327257D03*
X1270621D03*
X1279484Y330500D03*
Y334500D03*
X1299484Y871800D03*
Y875800D03*
Y891800D03*
X1290948Y881802D03*
X1323639Y337615D03*
X1323254Y346026D03*
X1333762Y352788D03*
X1335514Y1111198D03*
X1367725D03*
X1376543Y1007325D03*
X1373443Y1002180D03*
X1381749Y1014566D03*
X1372856Y1193471D03*
X1385917Y569000D03*
Y565000D03*
Y615500D03*
Y611500D03*
X1397501Y984037D03*
X1385530Y1197471D03*
X1411799Y992861D03*
X1401172Y1111258D03*
X1410884Y1423700D03*
X1430984Y897500D03*
X1433415Y1111197D03*
X1443484Y927000D03*
X1469886Y879194D03*
Y875194D03*
X1473984Y923500D03*
X1480179Y927324D03*
Y931324D03*
Y939324D03*
Y935324D03*
X1490320Y891615D03*
X1496947Y958378D03*
X1489947D03*
X1496984Y963500D03*
X1489984D03*
X1496984Y968000D03*
X1489984D03*
X1489627Y977181D03*
X1496627D03*
X1500547Y876339D03*
X1519947Y923740D03*
X1525984Y943000D03*
X1518984D03*
X1530449Y1148530D03*
X1530693Y1160650D03*
X1530908Y1169100D03*
Y1164560D03*
X1554344Y550400D03*
Y554400D03*
X1551207Y1418847D03*
X1560206Y1418806D03*
X1565130Y544967D03*
X1572130D03*
X1567844Y618400D03*
X1588494Y341787D03*
Y337787D03*
X1622285Y427017D03*
X1622253Y431029D03*
Y435029D03*
X1632888Y438323D03*
X1655244Y384500D03*
X1653416Y467367D03*
X1678027Y377912D03*
Y389912D03*
Y381912D03*
Y385912D03*
Y393924D03*
Y397912D03*
Y401924D03*
Y405924D03*
Y409924D03*
G54D74*
X414519Y1250868D03*
Y1264254D03*
X512430Y1250868D03*
Y1264254D03*
X1328693Y1250868D03*
Y1264254D03*
X1427004Y1251360D03*
Y1264746D03*
G54D83*
X798484Y980041D03*
Y1002089D03*
X801043Y980041D03*
X803602D03*
X806161D03*
X808720D03*
X811279D03*
X813839D03*
Y1002089D03*
X811279D03*
X808720D03*
X806161D03*
X803602D03*
X801043D03*
X816398Y980041D03*
X818957D03*
X821516D03*
X824075D03*
X826634D03*
Y1002089D03*
X824075D03*
X821516D03*
X818957D03*
X816398D03*
G54D56*
X227803Y616063D03*
Y623543D03*
X237449Y616063D03*
Y619803D03*
Y623543D03*
G54D92*
X904991Y843717D03*
Y846867D03*
X908140Y843717D03*
Y846867D03*
X901841Y843717D03*
Y846867D03*
Y872063D03*
Y875213D03*
X904991Y872063D03*
Y875213D03*
X908140Y872063D03*
Y875213D03*
X898692Y872063D03*
Y875213D03*
X941768Y864903D03*
Y868053D03*
X1331078Y834594D03*
Y837744D03*
X1334228Y850342D03*
Y853492D03*
X1337378Y859792D03*
Y862942D03*
Y853492D03*
Y856642D03*
X1349974Y866090D03*
Y869240D03*
X1346825Y866090D03*
Y869240D03*
X1340527Y866090D03*
Y869240D03*
X1343676Y866090D03*
Y869240D03*
X1340527Y872390D03*
Y875540D03*
X1343676Y872390D03*
Y875540D03*
X1346825Y872390D03*
Y875540D03*
X1349974Y872390D03*
Y875540D03*
X1362574Y837744D03*
Y840894D03*
Y853492D03*
Y856642D03*
X1356273Y866090D03*
Y869240D03*
X1359423Y866090D03*
Y869240D03*
Y872389D03*
Y875539D03*
X1356273Y872390D03*
Y875540D03*
X1353123Y866090D03*
Y869240D03*
Y872390D03*
Y875540D03*
G54D38*
X56348Y1727941D03*
Y1737941D03*
X56248Y1750941D03*
X56348Y1773941D03*
X56248Y1760941D03*
X56348Y1783941D03*
X56248Y1806941D03*
Y1796941D03*
X308448Y1737941D03*
Y1727941D03*
Y1750941D03*
Y1760941D03*
Y1773941D03*
Y1783941D03*
X308348Y1796941D03*
Y1806941D03*
X343286Y1738583D03*
Y1728583D03*
X343112Y1751624D03*
X343212Y1774624D03*
X343112Y1761624D03*
X343212Y1784624D03*
Y1797624D03*
Y1807624D03*
X595386Y1728583D03*
Y1738583D03*
X595312Y1751624D03*
Y1774624D03*
Y1761624D03*
Y1784624D03*
Y1807624D03*
Y1797624D03*
X630083Y1738286D03*
Y1728286D03*
X629861Y1751765D03*
X629711Y1775438D03*
X629861Y1761765D03*
X629711Y1785438D03*
X629475Y1798845D03*
Y1808845D03*
X882183Y1728286D03*
Y1738286D03*
X881911Y1751765D03*
X881761Y1775438D03*
X881911Y1761765D03*
X881761Y1785438D03*
X881525Y1798845D03*
Y1808845D03*
X917279Y1738990D03*
Y1728990D03*
X917163Y1752566D03*
Y1762566D03*
X917073Y1786014D03*
Y1776014D03*
X917166Y1800435D03*
Y1810435D03*
X1169329Y1728990D03*
Y1738990D03*
X1169263Y1752566D03*
Y1762566D03*
X1169123Y1776014D03*
Y1786014D03*
X1169216Y1800435D03*
Y1810435D03*
G54D47*
X146948Y1136909D03*
X143208D03*
X145078Y1198621D03*
Y1191141D03*
X148818D03*
Y1198621D03*
X145078Y1221062D03*
X148818D03*
Y1213582D03*
X145078D03*
Y1206102D03*
X148818D03*
X145078Y1228543D03*
X148818D03*
Y1247243D03*
X145078D03*
X148818Y1239763D03*
X145078D03*
X150689Y1133169D03*
X165649D03*
X161909D03*
X154429D03*
X156299Y1187401D03*
X163779D03*
X152559D03*
X156299Y1202362D03*
Y1194881D03*
X152559Y1202362D03*
Y1194881D03*
X163779D03*
Y1202362D03*
X156299Y1217322D03*
Y1209842D03*
X152559D03*
X163779D03*
Y1217322D03*
X152559D03*
X160039Y1236023D03*
X163779Y1224803D03*
X156299D03*
Y1228543D03*
X163779D03*
X160039Y1232283D03*
X152559Y1236023D03*
Y1232283D03*
Y1250984D03*
Y1254724D03*
X160039D03*
X156299Y1243503D03*
Y1247243D03*
X163779Y1243503D03*
X160039Y1250984D03*
X163779Y1247243D03*
X174999Y1075196D03*
X182480D03*
X174999Y1078936D03*
X182480D03*
X178740Y1082677D03*
Y1086417D03*
X174999Y1093897D03*
X182480D03*
Y1097637D03*
X174999D03*
X178740Y1101376D03*
Y1105117D03*
X173129Y1136909D03*
X169389D03*
X167519Y1187401D03*
X174999Y1198621D03*
Y1191141D03*
X167519Y1194881D03*
X171259Y1198621D03*
Y1191141D03*
X167519Y1202362D03*
Y1209842D03*
X171259Y1213582D03*
Y1206102D03*
X174999D03*
X167519Y1217322D03*
X174999Y1213582D03*
X178740Y1228543D03*
X171259Y1224803D03*
X182480Y1236023D03*
Y1232283D03*
X174999D03*
X171259Y1228543D03*
X178740Y1224803D03*
X174999Y1236023D03*
X167519Y1232283D03*
Y1236023D03*
Y1254724D03*
Y1250984D03*
X178740Y1247243D03*
X182480Y1254724D03*
Y1250984D03*
X171259Y1247243D03*
X174999Y1250984D03*
X171259Y1243503D03*
X174999Y1254724D03*
X178740Y1243503D03*
X189960Y1075196D03*
X197440D03*
X186220Y1082677D03*
Y1086417D03*
X189960Y1078936D03*
X193700Y1086417D03*
Y1082677D03*
X197440Y1078936D03*
X193700Y1105117D03*
X197440Y1093897D03*
X189960Y1097637D03*
X186220Y1105117D03*
X197440Y1097637D03*
X193700Y1101376D03*
X186220D03*
X189960Y1093897D03*
X197440Y1236023D03*
X186220Y1224803D03*
X193700Y1228543D03*
X197440Y1232283D03*
X189960Y1236023D03*
X186220Y1228543D03*
X193700Y1224803D03*
X189960Y1232283D03*
X197440Y1254724D03*
Y1250984D03*
X193700Y1247243D03*
Y1243503D03*
X189960Y1254724D03*
Y1250984D03*
X186220Y1247243D03*
Y1243503D03*
X204921Y1075196D03*
X212401D03*
Y1078936D03*
X208661Y1082677D03*
X201181D03*
Y1086417D03*
X208661D03*
X204921Y1078936D03*
Y1097637D03*
X208661Y1101376D03*
X212401Y1097637D03*
X208661Y1105117D03*
X212401Y1093897D03*
X201181Y1101376D03*
X204921Y1093897D03*
X201181Y1105117D03*
X204921Y1232283D03*
X201181Y1224803D03*
X212401Y1232283D03*
X208661Y1228543D03*
X212401Y1236023D03*
X208661Y1224803D03*
X201181Y1228543D03*
X204921Y1236023D03*
X208661Y1243503D03*
X204921Y1250984D03*
X208661Y1247243D03*
X212401Y1254724D03*
X201181Y1243503D03*
X212401Y1250984D03*
X201181Y1247243D03*
X204921Y1254724D03*
X227362Y1075196D03*
X219881D03*
Y1078936D03*
X216141Y1086417D03*
X231102Y1082677D03*
Y1086417D03*
X223622Y1082677D03*
X227362Y1078936D03*
X216141Y1082677D03*
X223622Y1086417D03*
X216141Y1101376D03*
X231102D03*
X227362Y1093897D03*
X219881Y1097637D03*
X223621Y1101376D03*
Y1105117D03*
X216141D03*
X219881Y1093897D03*
X227362Y1097637D03*
X231102Y1105117D03*
Y1228543D03*
Y1224803D03*
X219881Y1232283D03*
Y1236023D03*
X216141Y1224803D03*
X223622D03*
X227362Y1232283D03*
X223622Y1228543D03*
X216141D03*
X227362Y1236023D03*
X231102Y1243503D03*
Y1247243D03*
X223622Y1243503D03*
X216141Y1247243D03*
X223622D03*
X216141Y1243503D03*
X219881Y1250984D03*
Y1254724D03*
X227362D03*
Y1250984D03*
X234841Y1075195D03*
X242321Y1075196D03*
Y1078936D03*
X246061Y1082677D03*
X238581Y1082676D03*
X234841Y1078935D03*
X246061Y1086417D03*
X238581Y1086416D03*
X234841Y1093897D03*
X246062Y1105117D03*
X242321Y1097637D03*
X234841D03*
X238582Y1101376D03*
X246062D03*
X238582Y1105117D03*
X242321Y1093897D03*
X238582Y1224803D03*
Y1228543D03*
X242322Y1236023D03*
Y1232283D03*
X246062Y1228543D03*
X234842Y1232283D03*
X246062Y1224803D03*
X234842Y1236023D03*
X238582Y1247243D03*
X246062Y1243503D03*
X242322Y1250984D03*
X234842D03*
X246062Y1247243D03*
X234842Y1254724D03*
X238582Y1243503D03*
X242322Y1254724D03*
X249802Y1075196D03*
X257282D03*
X249802Y1078936D03*
X261022Y1086417D03*
X253542Y1082676D03*
X257282Y1078936D03*
X253542Y1086416D03*
X261022Y1082677D03*
X249802Y1097637D03*
X257282D03*
X249802Y1093897D03*
X253543Y1105117D03*
Y1101376D03*
X257282Y1093897D03*
X261023Y1105117D03*
Y1101376D03*
Y1224803D03*
X253543Y1228543D03*
X249803Y1232283D03*
X257283D03*
Y1236023D03*
X261023Y1228543D03*
X253543Y1224803D03*
X249803Y1236023D03*
X261023Y1243503D03*
X249803Y1250984D03*
X261023Y1247243D03*
X257283Y1250984D03*
X253543Y1247243D03*
X257283Y1254724D03*
X249803D03*
X253543Y1243503D03*
X279723Y1075196D03*
X264762D03*
X272243D03*
X275982Y1082677D03*
Y1086417D03*
X268502Y1082676D03*
X272243Y1078936D03*
X268502Y1086416D03*
X279723Y1078936D03*
X264762D03*
Y1097637D03*
X268503Y1105117D03*
X272243Y1097637D03*
X275984Y1105117D03*
X279723Y1093897D03*
X272243D03*
X279723Y1097637D03*
X268503Y1101376D03*
X275984D03*
X264762Y1093897D03*
X264763Y1232283D03*
X268503Y1224803D03*
X275984D03*
X272244Y1236023D03*
X279724Y1232283D03*
Y1236023D03*
X275984Y1228543D03*
X272244Y1232283D03*
X268503Y1228543D03*
X264763Y1236023D03*
Y1254724D03*
Y1250984D03*
X268503Y1243503D03*
Y1247243D03*
X272244Y1254724D03*
Y1250984D03*
X275984Y1243503D03*
Y1247243D03*
X279724Y1250984D03*
Y1254724D03*
X287203Y1075196D03*
X294684D03*
X290943Y1086417D03*
X287203Y1078936D03*
X290943Y1082677D03*
X283463Y1082676D03*
Y1086416D03*
X294684Y1078936D03*
X283464Y1101376D03*
X294684Y1093897D03*
X287203D03*
X294684Y1097637D03*
X283464Y1105117D03*
X290944Y1101376D03*
Y1105117D03*
X287203Y1097637D03*
X294684Y1123818D03*
Y1116338D03*
Y1131299D03*
X294685Y1198621D03*
Y1213582D03*
Y1206102D03*
X287204Y1232283D03*
X283464Y1224803D03*
Y1228543D03*
X287204Y1236023D03*
X294685D03*
X290944Y1224803D03*
X294685Y1232283D03*
X290944Y1228543D03*
X287204Y1254724D03*
X283464Y1243503D03*
Y1247243D03*
X287204Y1250984D03*
X294685Y1254724D03*
Y1250984D03*
X290944Y1247243D03*
Y1243503D03*
X302164Y1075196D03*
X309644D03*
X305904Y1082677D03*
X302164Y1078936D03*
X305904Y1086417D03*
X309644Y1078936D03*
X298424Y1086416D03*
Y1082676D03*
X298425Y1105117D03*
Y1101376D03*
X309644Y1097637D03*
X302164D03*
X305905Y1105117D03*
X309644Y1093897D03*
X305905Y1101376D03*
X302164Y1093897D03*
X302165Y1120078D03*
X305905Y1112598D03*
X298425Y1116338D03*
X305905Y1120078D03*
X302165Y1112598D03*
X298425Y1123818D03*
X305905Y1127559D03*
Y1135039D03*
X302165D03*
Y1127559D03*
X298425Y1131299D03*
Y1198621D03*
X305905Y1202362D03*
X302165D03*
X298425Y1213582D03*
X305905Y1209842D03*
Y1217322D03*
X302165Y1209842D03*
X298425Y1206102D03*
X302165Y1217322D03*
Y1232283D03*
X309645D03*
X298425Y1224803D03*
Y1228543D03*
X309645Y1236023D03*
X305905Y1228543D03*
Y1224803D03*
X302165Y1236023D03*
X309645Y1254724D03*
X298425Y1247243D03*
X309645Y1250984D03*
X298425Y1243503D03*
X305905D03*
Y1247243D03*
X302165Y1254724D03*
Y1250984D03*
X317124Y1075196D03*
X320866Y1090157D03*
X324606D03*
Y1082676D03*
X317124Y1078936D03*
X313384Y1082677D03*
Y1086417D03*
X320866Y1082676D03*
X313385Y1101377D03*
X317125Y1093897D03*
X320866Y1101377D03*
X313385Y1105117D03*
X324606Y1101377D03*
X317125Y1097637D03*
X313385Y1120078D03*
X324606Y1123818D03*
Y1108858D03*
X320866D03*
X317125Y1112598D03*
X324606Y1116338D03*
X313385Y1112598D03*
X317125Y1120078D03*
X320866Y1116338D03*
Y1123818D03*
X313385Y1127558D03*
X317125Y1135039D03*
X313385D03*
X324606Y1131299D03*
X317125Y1127558D03*
X320866Y1131299D03*
Y1198621D03*
X313385Y1202362D03*
X324606Y1198621D03*
X317125Y1202362D03*
Y1217322D03*
Y1209842D03*
X324606Y1213582D03*
X320866Y1221062D03*
X313385Y1209842D03*
X320866Y1206102D03*
Y1213582D03*
X324606Y1221062D03*
Y1206102D03*
X313385Y1217322D03*
X317125Y1236023D03*
X313385Y1224803D03*
X324606Y1228543D03*
X317125Y1232283D03*
X313385Y1228543D03*
X320866D03*
X317125Y1254724D03*
X324606Y1239763D03*
X313385Y1247243D03*
X320866D03*
X317125Y1250984D03*
X320866Y1239763D03*
X313385Y1243503D03*
X324606Y1247243D03*
X602165Y1191141D03*
Y1198621D03*
Y1221062D03*
Y1206102D03*
Y1213582D03*
Y1228543D03*
Y1247243D03*
Y1239763D03*
X613386Y1187401D03*
X609646D03*
X620866D03*
X605905Y1191141D03*
X613386Y1194881D03*
X605905Y1198621D03*
X609646Y1194881D03*
Y1202362D03*
X613386D03*
X620866D03*
Y1194881D03*
X613386Y1217322D03*
X605905Y1221062D03*
X609646Y1217322D03*
Y1209842D03*
X605905Y1206102D03*
Y1213582D03*
X620866Y1209842D03*
X613386D03*
X620866Y1217322D03*
X605905Y1228543D03*
X620866D03*
Y1224803D03*
X609646Y1232283D03*
X617126Y1236023D03*
X613386Y1228543D03*
X617126Y1232283D03*
X609646Y1236023D03*
X613386Y1224803D03*
X605905Y1247243D03*
X617126Y1250984D03*
X620866Y1243503D03*
Y1247243D03*
X609646Y1254724D03*
X613386Y1247243D03*
X617126Y1254724D03*
X613386Y1243503D03*
X609646Y1250984D03*
X605905Y1239763D03*
X632086Y1075196D03*
Y1078936D03*
X635827Y1086417D03*
Y1082677D03*
X632086Y1097637D03*
X635827Y1105117D03*
X632086Y1093897D03*
X635827Y1101376D03*
X624606Y1187401D03*
X628346Y1191141D03*
X624606Y1194881D03*
X632086Y1191141D03*
X628346Y1198621D03*
X624606Y1202362D03*
X632086Y1198621D03*
X628346Y1206102D03*
X632086D03*
X624606Y1217322D03*
X628346Y1213582D03*
X632086D03*
X624606Y1209842D03*
X628346Y1224803D03*
Y1228543D03*
X635827D03*
X632086Y1232283D03*
Y1236023D03*
X624606Y1232283D03*
Y1236023D03*
X635827Y1224803D03*
X624606Y1254724D03*
Y1250984D03*
X632086Y1254724D03*
X635827Y1243503D03*
X632086Y1250984D03*
X635827Y1247243D03*
X628346Y1243503D03*
Y1247243D03*
X639567Y1075196D03*
X647047D03*
X643307Y1086417D03*
Y1082677D03*
X647047Y1078936D03*
X639567D03*
X650787Y1082677D03*
Y1086417D03*
Y1105117D03*
X647047Y1093897D03*
X639567Y1097637D03*
X643307Y1105117D03*
X647047Y1097637D03*
X639567Y1093897D03*
X643307Y1101376D03*
X650787D03*
X639567Y1236023D03*
X647047D03*
X639567Y1232283D03*
X643307Y1224803D03*
X647047Y1232283D03*
X643307Y1228543D03*
X650787D03*
Y1224803D03*
X639567Y1250984D03*
Y1254724D03*
X650787Y1247243D03*
Y1243503D03*
X647047Y1254724D03*
Y1250984D03*
X643307Y1247243D03*
Y1243503D03*
X662008Y1075196D03*
X654527D03*
X669488D03*
X662008Y1078936D03*
X665748Y1082677D03*
X658268D03*
X654527Y1078936D03*
X665748Y1086417D03*
X658268D03*
X669488Y1078936D03*
X662008Y1097637D03*
X654527Y1093897D03*
X669488D03*
X665748Y1105117D03*
X654527Y1097637D03*
X662008Y1093897D03*
X669488Y1097637D03*
X665748Y1101376D03*
X658268Y1105117D03*
Y1101376D03*
X669488Y1232283D03*
X654527Y1236023D03*
X662008Y1232283D03*
X665748Y1224803D03*
X662008Y1236023D03*
X658268Y1224803D03*
X665748Y1228543D03*
X658268D03*
X669488Y1236023D03*
X654527Y1232283D03*
X662008Y1254724D03*
X665748Y1247243D03*
X669488Y1250984D03*
X658268Y1247243D03*
X662008Y1250984D03*
X665748Y1243503D03*
X669488Y1254724D03*
X658268Y1243503D03*
X654527Y1254724D03*
Y1250984D03*
X676968Y1075196D03*
X684449D03*
X676968Y1078936D03*
X680709Y1086417D03*
X684449Y1078936D03*
X673228Y1086417D03*
Y1082677D03*
X680709D03*
X673228Y1105117D03*
X684449Y1093897D03*
X676968D03*
X684449Y1097637D03*
X676968D03*
X680708Y1105117D03*
X673228Y1101376D03*
X680708D03*
X676968Y1236023D03*
X684449Y1232283D03*
X673228Y1228543D03*
X680709Y1224803D03*
X684449Y1236023D03*
X676968Y1232283D03*
X673228Y1224803D03*
X680709Y1228543D03*
X673228Y1243503D03*
X680709Y1247243D03*
X673228D03*
X684449Y1254724D03*
Y1250984D03*
X676968Y1254724D03*
Y1250984D03*
X680709Y1243503D03*
X699408Y1075196D03*
X691928Y1075195D03*
X688189Y1086417D03*
Y1082677D03*
X691928Y1078935D03*
X699408Y1078936D03*
X695668Y1086416D03*
Y1082676D03*
X688189Y1105117D03*
X695669Y1101376D03*
X699408Y1097637D03*
X695669Y1105117D03*
X691928Y1093897D03*
Y1097637D03*
X699408Y1093897D03*
X688189Y1101376D03*
Y1228543D03*
X691929Y1236023D03*
X699409Y1232283D03*
X688189Y1224803D03*
X699409Y1236023D03*
X691929Y1232283D03*
X695669Y1228543D03*
Y1224803D03*
X699409Y1254724D03*
X691929Y1250984D03*
X688189Y1247243D03*
Y1243503D03*
X691929Y1254724D03*
X695669Y1247243D03*
X699409Y1250984D03*
X695669Y1243503D03*
X706889Y1075196D03*
X714369D03*
X706889Y1078936D03*
X718109Y1086417D03*
X714369Y1078936D03*
X703148Y1082677D03*
X710629Y1086416D03*
X703148Y1086417D03*
X718109Y1082677D03*
X710629Y1082676D03*
X714369Y1097637D03*
X706889Y1093897D03*
X703149Y1105117D03*
X718110D03*
Y1101376D03*
X710630Y1105117D03*
X714369Y1093897D03*
X706889Y1097637D03*
X703149Y1101376D03*
X710630D03*
X706890Y1236023D03*
X718110Y1228543D03*
X714370Y1236023D03*
X710630Y1228543D03*
X703149D03*
X714370Y1232283D03*
X703149Y1224803D03*
X718110D03*
X710630D03*
X706890Y1232283D03*
X718110Y1243503D03*
Y1247243D03*
X706890Y1250984D03*
X703149Y1243503D03*
X714370Y1254724D03*
Y1250984D03*
X710630Y1247243D03*
X706890Y1254724D03*
X710630Y1243503D03*
X703149Y1247243D03*
X721849Y1075196D03*
X729330D03*
X725589Y1086416D03*
X733069Y1086417D03*
X721849Y1078936D03*
X729330D03*
X733069Y1082677D03*
X725589Y1082676D03*
X725590Y1101376D03*
X733071Y1105117D03*
X725590D03*
X721849Y1097637D03*
Y1093897D03*
X729330Y1097637D03*
X733071Y1101376D03*
X729330Y1093897D03*
X725590Y1228543D03*
X733071D03*
X721850Y1236023D03*
X733071Y1224803D03*
X721850Y1232283D03*
X725590Y1224803D03*
X729331Y1236023D03*
Y1232283D03*
Y1250984D03*
X733071Y1247243D03*
X721850Y1250984D03*
Y1254724D03*
X725590Y1243503D03*
X729331Y1254724D03*
X733071Y1243503D03*
X725590Y1247243D03*
X736810Y1075196D03*
X744290D03*
Y1078936D03*
X748030Y1086417D03*
X740550Y1086416D03*
Y1082676D03*
X736810Y1078936D03*
X748030Y1082677D03*
X736810Y1097637D03*
X748031Y1105117D03*
X744290Y1093897D03*
X740551Y1105117D03*
X744290Y1097637D03*
X736810Y1093897D03*
X740551Y1101376D03*
X748031D03*
X744291Y1236023D03*
X736811Y1232283D03*
X744291D03*
X736811Y1236023D03*
X740551Y1224803D03*
Y1228543D03*
X748031Y1224803D03*
Y1228543D03*
X744291Y1254724D03*
X740551Y1243503D03*
Y1247243D03*
X744291Y1250984D03*
X736811Y1254724D03*
Y1250984D03*
X748031Y1247243D03*
Y1243503D03*
X751771Y1075196D03*
X766731D03*
X759251D03*
X762991Y1086417D03*
X766731Y1078936D03*
X755511Y1086416D03*
X759251Y1078936D03*
X755511Y1082676D03*
X762991Y1082677D03*
X751771Y1078936D03*
Y1097637D03*
X762992Y1101376D03*
Y1105117D03*
X755512D03*
X759251Y1097637D03*
Y1093897D03*
X766731Y1097637D03*
X755512Y1101376D03*
X766731Y1093897D03*
X751771D03*
X755512Y1123818D03*
X759252Y1112598D03*
X751771Y1123818D03*
X762992Y1112598D03*
X755512Y1116338D03*
X751771D03*
X759252Y1120078D03*
X762992D03*
X751771Y1131299D03*
X762992Y1135039D03*
X755512Y1131299D03*
X762992Y1127559D03*
X759252Y1135039D03*
Y1127559D03*
X762992Y1202362D03*
X755512Y1198621D03*
X759252Y1202362D03*
X751772Y1198621D03*
X762992Y1217322D03*
X751772Y1213582D03*
X762992Y1209842D03*
X755512Y1213582D03*
X751772Y1206102D03*
X759252Y1217322D03*
Y1209842D03*
X755512Y1206102D03*
Y1228543D03*
X751772Y1236023D03*
X762992Y1228543D03*
X751772Y1232283D03*
X766732D03*
Y1236023D03*
X759252Y1232283D03*
X762992Y1224803D03*
X759252Y1236023D03*
X755512Y1224803D03*
X766732Y1250984D03*
X755512Y1243503D03*
X762992D03*
Y1247243D03*
X751772Y1250984D03*
Y1254724D03*
X759252D03*
X766732D03*
X759252Y1250984D03*
X755512Y1247243D03*
X774211Y1075196D03*
X781693Y1090157D03*
X777953D03*
X781693Y1082676D03*
X774211Y1078936D03*
X770471Y1086417D03*
Y1082677D03*
X777953Y1082676D03*
X770472Y1101377D03*
X781693D03*
X777953D03*
X774212Y1097637D03*
X770472Y1105117D03*
X774212Y1093897D03*
Y1112598D03*
X770472D03*
X781693Y1123818D03*
X777953D03*
X781693Y1116338D03*
X777953Y1108858D03*
X770472Y1120078D03*
X781693Y1108858D03*
X777953Y1116338D03*
X774212Y1120078D03*
X770472Y1127558D03*
Y1135039D03*
X781693Y1131299D03*
X774212Y1127558D03*
Y1135039D03*
X777953Y1131299D03*
X781693Y1198621D03*
X774212Y1202362D03*
X770472D03*
X777953Y1198621D03*
Y1206102D03*
X770472Y1209842D03*
X781693Y1213582D03*
X774212Y1209842D03*
X777953Y1221062D03*
X781693D03*
Y1206102D03*
X770472Y1217322D03*
X774212D03*
X777953Y1213582D03*
X770472Y1228543D03*
X781693D03*
X770472Y1224803D03*
X777953Y1228543D03*
X774212Y1232283D03*
Y1236023D03*
X777953Y1239763D03*
X781693D03*
X777953Y1247243D03*
X770472Y1243503D03*
X781693Y1247243D03*
X770472D03*
X774212Y1250984D03*
Y1254724D03*
X1059251Y1198621D03*
Y1191141D03*
Y1221062D03*
Y1206102D03*
Y1213582D03*
Y1228543D03*
Y1247243D03*
Y1239763D03*
X1070472Y1187401D03*
X1066732D03*
X1062991Y1198621D03*
X1066732Y1194881D03*
X1062991Y1191141D03*
X1070472Y1194881D03*
Y1202362D03*
X1066732D03*
X1070472Y1217322D03*
X1066732D03*
X1062991Y1221062D03*
Y1206102D03*
X1070472Y1209842D03*
X1062991Y1213582D03*
X1066732Y1209842D03*
X1070472Y1228543D03*
X1066732Y1236023D03*
Y1232283D03*
X1074212Y1236023D03*
Y1232283D03*
X1070472Y1224803D03*
X1062991Y1228543D03*
X1074212Y1250984D03*
X1066732Y1254724D03*
X1070472Y1247243D03*
X1074212Y1254724D03*
X1062991Y1247243D03*
X1070472Y1243503D03*
X1062991Y1239763D03*
X1066732Y1250984D03*
X1089172Y1075196D03*
Y1078936D03*
Y1097637D03*
Y1093897D03*
X1077952Y1187401D03*
X1081692D03*
X1077952Y1194881D03*
Y1202362D03*
X1089172Y1191141D03*
Y1198621D03*
X1081692Y1202362D03*
X1085432Y1198621D03*
X1081692Y1194881D03*
X1085432Y1191141D03*
X1089172Y1206102D03*
X1077952Y1209842D03*
X1081692D03*
Y1217322D03*
X1089172Y1213582D03*
X1077952Y1217322D03*
X1085432Y1206102D03*
Y1213582D03*
X1089172Y1232283D03*
X1081692D03*
Y1236023D03*
X1089172D03*
X1077952Y1224803D03*
Y1228543D03*
X1085432Y1224803D03*
Y1228543D03*
X1077952Y1243503D03*
X1081692Y1250984D03*
X1077952Y1247243D03*
X1081692Y1254724D03*
X1085432Y1243503D03*
X1089172Y1254724D03*
Y1250984D03*
X1085432Y1247243D03*
X1096653Y1075196D03*
X1104133D03*
X1100393Y1082677D03*
X1104133Y1078936D03*
X1107873Y1082677D03*
Y1086417D03*
X1092913Y1082677D03*
X1100393Y1086417D03*
X1092913D03*
X1096653Y1078936D03*
X1092913Y1105117D03*
X1104133Y1097637D03*
X1096653D03*
X1100393Y1105117D03*
X1104133Y1093897D03*
X1100393Y1101376D03*
X1096653Y1093897D03*
X1092913Y1101376D03*
X1107873Y1105117D03*
Y1101376D03*
X1100393Y1228543D03*
X1104133Y1236023D03*
X1092913Y1224803D03*
X1104133Y1232283D03*
X1107873Y1224803D03*
X1096653Y1236023D03*
X1100393Y1224803D03*
X1107873Y1228543D03*
X1096653Y1232283D03*
X1092913Y1228543D03*
X1096653Y1254724D03*
X1104133D03*
X1092913Y1247243D03*
X1096653Y1250984D03*
X1092913Y1243503D03*
X1107873D03*
X1100393D03*
X1107873Y1247243D03*
X1100393D03*
X1104133Y1250984D03*
X1111613Y1075196D03*
X1119094D03*
X1122834Y1086417D03*
X1119094Y1078936D03*
X1115354Y1082677D03*
X1111613Y1078936D03*
X1115354Y1086417D03*
X1122834Y1082677D03*
X1119094Y1097637D03*
X1115354Y1101376D03*
X1111613Y1093897D03*
Y1097637D03*
X1122834Y1105117D03*
X1119094Y1093897D03*
X1122834Y1101376D03*
X1115354Y1105117D03*
X1122834Y1224803D03*
X1119094Y1232283D03*
X1115354Y1228543D03*
X1111613Y1232283D03*
X1119094Y1236023D03*
X1115354Y1224803D03*
X1111613Y1236023D03*
X1122834Y1228543D03*
Y1243503D03*
X1119094Y1250984D03*
X1111613Y1254724D03*
X1119094D03*
X1122834Y1247243D03*
X1115354Y1243503D03*
Y1247243D03*
X1111613Y1250984D03*
X1126574Y1075196D03*
X1134054D03*
Y1078936D03*
X1126574D03*
X1130314Y1086417D03*
Y1082677D03*
X1137795Y1086417D03*
Y1082677D03*
X1126574Y1093897D03*
X1130314Y1105117D03*
X1134054Y1093897D03*
X1130314Y1101376D03*
X1134054Y1097637D03*
X1137794Y1105117D03*
X1126574Y1097637D03*
X1137794Y1101376D03*
X1134054Y1236023D03*
X1137795Y1228543D03*
X1134054Y1232283D03*
X1126574D03*
Y1236023D03*
X1137795Y1224803D03*
X1130314Y1228543D03*
Y1224803D03*
X1126574Y1254724D03*
X1137795Y1243503D03*
X1130314Y1247243D03*
X1126574Y1250984D03*
X1137795Y1247243D03*
X1130314Y1243503D03*
X1134054Y1250984D03*
Y1254724D03*
X1141535Y1075196D03*
X1156494D03*
X1149014Y1075195D03*
X1145275Y1086417D03*
Y1082677D03*
X1141535Y1078936D03*
X1149014Y1078935D03*
X1156494Y1078936D03*
X1152754Y1086416D03*
Y1082676D03*
X1145275Y1105117D03*
X1141535Y1093897D03*
X1145275Y1101376D03*
X1141535Y1097637D03*
X1149014D03*
X1156494Y1093897D03*
X1152755Y1101376D03*
X1156494Y1097637D03*
X1149014Y1093897D03*
X1152755Y1105117D03*
X1149015Y1236023D03*
Y1232283D03*
X1152755Y1228543D03*
X1145275Y1224803D03*
X1156495Y1232283D03*
Y1236023D03*
X1141535D03*
X1145275Y1228543D03*
X1152755Y1224803D03*
X1141535Y1232283D03*
Y1254724D03*
Y1250984D03*
X1149015Y1254724D03*
X1145275Y1247243D03*
X1152755Y1243503D03*
X1156495Y1254724D03*
X1145275Y1243503D03*
X1152755Y1247243D03*
X1149015Y1250984D03*
X1156495D03*
X1163975Y1075196D03*
X1171455D03*
X1160234Y1086417D03*
X1167715Y1086416D03*
X1163975Y1078936D03*
X1160234Y1082677D03*
X1171455Y1078936D03*
X1167715Y1082676D03*
X1160235Y1105117D03*
Y1101376D03*
X1171455Y1093897D03*
X1167716Y1105117D03*
X1171455Y1097637D03*
X1163975Y1093897D03*
Y1097637D03*
X1167716Y1101376D03*
X1160235Y1224803D03*
X1163976Y1232283D03*
X1167716Y1224803D03*
X1160235Y1228543D03*
X1171456Y1232283D03*
X1163976Y1236023D03*
X1171456D03*
X1167716Y1228543D03*
X1171456Y1250984D03*
X1167716Y1247243D03*
X1163976Y1250984D03*
X1160235Y1247243D03*
Y1243503D03*
X1167716D03*
X1171456Y1254724D03*
X1163976D03*
X1178935Y1075196D03*
X1186416D03*
X1175195Y1086417D03*
X1182675Y1086416D03*
X1175195Y1082677D03*
X1178935Y1078936D03*
X1182675Y1082676D03*
X1186416Y1078936D03*
X1178935Y1097637D03*
X1186416Y1093897D03*
X1182676Y1105117D03*
X1175196D03*
X1178935Y1093897D03*
X1182676Y1101376D03*
X1175196D03*
X1186416Y1097637D03*
X1182676Y1228543D03*
X1186417Y1236023D03*
X1178936D03*
X1186417Y1232283D03*
X1175196Y1228543D03*
X1178936Y1232283D03*
X1182676Y1224803D03*
X1175196D03*
X1178936Y1254724D03*
X1175196Y1243503D03*
X1182676Y1247243D03*
X1178936Y1250984D03*
X1186417D03*
X1182676Y1243503D03*
X1186417Y1254724D03*
X1175196Y1247243D03*
X1193896Y1075196D03*
X1201376D03*
X1190155Y1086417D03*
X1205116Y1082677D03*
X1190155D03*
X1197636Y1082676D03*
X1193896Y1078936D03*
X1205116Y1086417D03*
X1201376Y1078936D03*
X1197636Y1086416D03*
X1201376Y1093897D03*
X1193896Y1097637D03*
X1197637Y1105117D03*
X1205117D03*
X1197637Y1101376D03*
X1205117D03*
X1190157D03*
X1193896Y1093897D03*
X1201376Y1097637D03*
X1190157Y1105117D03*
X1197637Y1224803D03*
X1193897Y1236023D03*
X1190157Y1228543D03*
X1201377Y1236023D03*
X1190157Y1224803D03*
X1193897Y1232283D03*
X1197637Y1228543D03*
X1201377Y1232283D03*
X1205117Y1228543D03*
Y1224803D03*
X1190157Y1243503D03*
X1201377Y1250984D03*
X1197637Y1247243D03*
X1193897Y1250984D03*
X1201377Y1254724D03*
X1197637Y1243503D03*
X1193897Y1254724D03*
X1190157Y1247243D03*
X1205117Y1243503D03*
Y1247243D03*
X1216337Y1075196D03*
X1208857D03*
X1212597Y1082676D03*
Y1086416D03*
X1220077Y1086417D03*
X1208857Y1078936D03*
X1216337D03*
X1220077Y1082677D03*
X1220078Y1105117D03*
X1216337Y1093897D03*
X1212598Y1101376D03*
Y1105117D03*
X1208857Y1093897D03*
X1216337Y1097637D03*
X1220078Y1101376D03*
X1208857Y1097637D03*
X1212598Y1123818D03*
X1208857Y1116338D03*
X1212598D03*
X1216338Y1120078D03*
Y1112598D03*
X1208857Y1123818D03*
X1220078Y1112598D03*
Y1120078D03*
X1216338Y1127559D03*
Y1135039D03*
X1212598Y1131299D03*
X1208857D03*
X1220078Y1135039D03*
Y1127559D03*
X1212598Y1198621D03*
X1208858D03*
X1216338Y1202362D03*
X1220078D03*
Y1217322D03*
Y1209842D03*
X1212598Y1206102D03*
X1216338Y1217322D03*
X1212598Y1213582D03*
X1208858Y1206102D03*
Y1213582D03*
X1216338Y1209842D03*
X1220078Y1224803D03*
X1212598Y1228543D03*
X1208858Y1232283D03*
X1216338Y1236023D03*
Y1232283D03*
X1212598Y1224803D03*
X1220078Y1228543D03*
X1208858Y1236023D03*
X1212598Y1243503D03*
X1220078Y1247243D03*
Y1243503D03*
X1212598Y1247243D03*
X1208858Y1254724D03*
Y1250984D03*
X1216338Y1254724D03*
Y1250984D03*
X1231297Y1075196D03*
X1223817D03*
X1235039Y1090157D03*
X1231297Y1078936D03*
X1235039Y1082676D03*
X1227557Y1086417D03*
X1223817Y1078936D03*
X1227557Y1082677D03*
X1227558Y1101377D03*
X1231298Y1093897D03*
X1235039Y1101377D03*
X1227558Y1105117D03*
X1223817Y1093897D03*
Y1097637D03*
X1231298D03*
X1227558Y1112598D03*
X1235039Y1123818D03*
X1231298Y1120078D03*
Y1112598D03*
X1235039Y1108858D03*
Y1116338D03*
X1227558Y1120078D03*
X1231298Y1135039D03*
X1227558Y1127558D03*
X1235039Y1131299D03*
X1231298Y1127558D03*
X1227558Y1135039D03*
X1231298Y1202362D03*
X1235039Y1198621D03*
X1227558Y1202362D03*
X1235039Y1213582D03*
X1231298Y1209842D03*
X1227558D03*
X1235039Y1221062D03*
X1231298Y1217322D03*
X1235039Y1206102D03*
X1227558Y1217322D03*
X1231298Y1232283D03*
X1227558Y1228543D03*
Y1224803D03*
X1223818Y1236023D03*
X1231298D03*
X1235039Y1228543D03*
X1223818Y1232283D03*
X1227558Y1247243D03*
X1231298Y1254724D03*
X1223818D03*
Y1250984D03*
X1235039Y1239763D03*
X1227558Y1243503D03*
X1231298Y1250984D03*
X1235039Y1247243D03*
X1238779Y1090157D03*
Y1082676D03*
Y1101377D03*
Y1108858D03*
Y1116338D03*
Y1123818D03*
Y1131299D03*
Y1198621D03*
Y1221062D03*
Y1206102D03*
Y1213582D03*
Y1228543D03*
Y1247243D03*
Y1239763D03*
X1523819Y1187401D03*
X1527559D03*
X1516338Y1198621D03*
X1523819Y1194881D03*
X1520078Y1198621D03*
X1523819Y1202362D03*
X1516338Y1191141D03*
X1527559Y1202362D03*
Y1194881D03*
X1520078Y1191141D03*
Y1221062D03*
X1516338Y1213582D03*
Y1206102D03*
X1520078D03*
X1527559Y1217322D03*
X1523819Y1209842D03*
X1516338Y1221062D03*
X1527559Y1209842D03*
X1523819Y1217322D03*
X1520078Y1213582D03*
X1527559Y1228543D03*
X1516338D03*
X1523819Y1232283D03*
X1520078Y1228543D03*
X1523819Y1236023D03*
X1527559Y1224803D03*
X1516338Y1239763D03*
X1520078D03*
Y1247243D03*
X1516338D03*
X1527559Y1243503D03*
Y1247243D03*
X1523819Y1250984D03*
Y1254724D03*
X1546259Y1075196D03*
Y1078936D03*
Y1097637D03*
Y1093897D03*
X1535039Y1187401D03*
X1538779D03*
X1542519Y1191141D03*
X1538779Y1202362D03*
X1535039Y1194881D03*
X1542519Y1198621D03*
X1546259D03*
Y1191141D03*
X1535039Y1202362D03*
X1538779Y1194881D03*
X1542519Y1213582D03*
Y1206102D03*
X1546259Y1213582D03*
X1535039Y1209842D03*
Y1217322D03*
X1546259Y1206102D03*
X1538779Y1209842D03*
Y1217322D03*
X1546259Y1232283D03*
X1535039Y1224803D03*
X1538779Y1236023D03*
X1531299Y1232283D03*
X1542519Y1228543D03*
X1535039D03*
X1546259Y1236023D03*
X1542519Y1224803D03*
X1531299Y1236023D03*
X1538779Y1232283D03*
X1546259Y1250984D03*
X1542519Y1243503D03*
X1546259Y1254724D03*
X1542519Y1247243D03*
X1538779Y1250984D03*
Y1254724D03*
X1535039Y1243503D03*
X1531299Y1250984D03*
X1535039Y1247243D03*
X1531299Y1254724D03*
X1553740Y1075196D03*
X1561220D03*
X1557480Y1082677D03*
X1553740Y1078936D03*
X1561220D03*
X1550000Y1086417D03*
Y1082677D03*
X1557480Y1086417D03*
Y1101376D03*
X1561220Y1093897D03*
X1557480Y1105117D03*
X1561220Y1097637D03*
X1550000Y1101376D03*
Y1105117D03*
X1553740Y1093897D03*
Y1097637D03*
Y1232283D03*
X1550000Y1228543D03*
X1553740Y1236023D03*
X1550000Y1224803D03*
X1557480Y1228543D03*
X1561220Y1236023D03*
Y1232283D03*
X1557480Y1224803D03*
X1561220Y1250984D03*
Y1254724D03*
X1550000Y1243503D03*
X1557480Y1247243D03*
X1550000D03*
X1557480Y1243503D03*
X1553740Y1250984D03*
Y1254724D03*
X1576181Y1075196D03*
X1568700D03*
Y1078936D03*
X1572441Y1086417D03*
X1564960Y1082677D03*
Y1086417D03*
X1572441Y1082677D03*
X1576181Y1078936D03*
X1564960Y1105117D03*
X1576181Y1097637D03*
X1568700D03*
X1576181Y1093897D03*
X1568700D03*
X1572441Y1101376D03*
Y1105117D03*
X1564960Y1101376D03*
X1572441Y1228543D03*
X1568700Y1236023D03*
X1564960Y1224803D03*
X1576181Y1236023D03*
X1572441Y1224803D03*
X1564960Y1228543D03*
X1576181Y1232283D03*
X1568700D03*
Y1254724D03*
X1572441Y1247243D03*
X1576181Y1254724D03*
X1564960Y1243503D03*
Y1247243D03*
X1576181Y1250984D03*
X1572441Y1243503D03*
X1568700Y1250984D03*
X1583661Y1075196D03*
X1591141D03*
X1594882Y1082677D03*
X1579921D03*
X1583661Y1078936D03*
X1594882Y1086417D03*
X1587401Y1082677D03*
X1579921Y1086417D03*
X1587401D03*
X1591141Y1078936D03*
X1594881Y1105117D03*
X1591141Y1097637D03*
X1583661Y1093897D03*
X1594881Y1101376D03*
X1583661Y1097637D03*
X1587401Y1105117D03*
X1579921Y1101376D03*
X1591141Y1093897D03*
X1587401Y1101376D03*
X1579921Y1105117D03*
X1594882Y1224803D03*
X1591141Y1232283D03*
X1583661Y1236023D03*
X1579921Y1228543D03*
X1583661Y1232283D03*
X1594882Y1228543D03*
X1579921Y1224803D03*
X1587401Y1228543D03*
Y1224803D03*
X1591141Y1236023D03*
X1583661Y1254724D03*
X1579921Y1247243D03*
X1591141Y1254724D03*
X1587401Y1247243D03*
Y1243503D03*
X1594882D03*
X1579921D03*
X1594882Y1247243D03*
X1583661Y1250984D03*
X1591141D03*
X1606101Y1075195D03*
X1598622Y1075196D03*
X1609841Y1086416D03*
X1606101Y1078935D03*
X1609841Y1082676D03*
X1602362Y1082677D03*
Y1086417D03*
X1598622Y1078936D03*
X1606101Y1093897D03*
X1602362Y1101376D03*
X1598622Y1097637D03*
Y1093897D03*
X1602362Y1105117D03*
X1609842Y1101376D03*
Y1105117D03*
X1606101Y1097637D03*
X1598622Y1236023D03*
X1606102D03*
X1609842Y1228543D03*
X1606102Y1232283D03*
X1602362Y1224803D03*
X1609842D03*
X1602362Y1228543D03*
X1598622Y1232283D03*
Y1254724D03*
Y1250984D03*
X1609842Y1247243D03*
X1606102Y1250984D03*
Y1254724D03*
X1609842Y1243503D03*
X1602362Y1247243D03*
Y1243503D03*
X1613581Y1075196D03*
X1621062D03*
X1613581Y1078936D03*
X1624802Y1082676D03*
X1617321Y1082677D03*
X1621062Y1078936D03*
X1617321Y1086417D03*
X1624802Y1086416D03*
X1621062Y1093897D03*
X1617322Y1105117D03*
Y1101376D03*
X1613581Y1093897D03*
Y1097637D03*
X1624803Y1101376D03*
Y1105117D03*
X1621062Y1097637D03*
X1617322Y1228543D03*
X1624803Y1224803D03*
X1617322D03*
X1621063Y1236023D03*
X1613582D03*
X1621063Y1232283D03*
X1624803Y1228543D03*
X1613582Y1232283D03*
X1624803Y1247243D03*
Y1243503D03*
X1621063Y1254724D03*
X1613582Y1250984D03*
X1617322Y1243503D03*
Y1247243D03*
X1613582Y1254724D03*
X1621063Y1250984D03*
X1636022Y1075196D03*
X1643503D03*
X1628542D03*
X1632282Y1082677D03*
X1643503Y1078936D03*
X1628542D03*
X1639762Y1086416D03*
X1632282Y1086417D03*
X1636022Y1078936D03*
X1639762Y1082676D03*
X1639763Y1101376D03*
X1628542Y1093897D03*
X1636022D03*
X1639763Y1105117D03*
X1632283D03*
Y1101376D03*
X1636022Y1097637D03*
X1643503D03*
Y1093897D03*
X1628542Y1097637D03*
X1632283Y1228543D03*
X1628543Y1236023D03*
Y1232283D03*
X1639763Y1224803D03*
X1636023Y1236023D03*
X1643504Y1232283D03*
X1632283Y1224803D03*
X1643504Y1236023D03*
X1636023Y1232283D03*
X1639763Y1228543D03*
X1632283Y1243503D03*
X1636023Y1254724D03*
X1639763Y1243503D03*
X1636023Y1250984D03*
X1632283Y1247243D03*
X1643504Y1250984D03*
X1628543D03*
X1639763Y1247243D03*
X1628543Y1254724D03*
X1643504D03*
X1650983Y1075196D03*
X1658463D03*
X1654723Y1086416D03*
Y1082676D03*
X1650983Y1078936D03*
X1647242Y1082677D03*
Y1086417D03*
X1658463Y1078936D03*
Y1097637D03*
X1647244Y1101376D03*
X1658463Y1093897D03*
X1654724Y1105117D03*
X1650983Y1093897D03*
X1647244Y1105117D03*
X1654724Y1101376D03*
X1650983Y1097637D03*
X1654724Y1228543D03*
X1647244D03*
X1658464Y1232283D03*
X1654724Y1224803D03*
X1658464Y1236023D03*
X1650984D03*
X1647244Y1224803D03*
X1650984Y1232283D03*
X1654724Y1243503D03*
X1650984Y1250984D03*
X1647244Y1247243D03*
X1654724D03*
X1647244Y1243503D03*
X1650984Y1254724D03*
X1658464D03*
Y1250984D03*
X1673424Y1075196D03*
X1665944D03*
X1662203Y1086417D03*
Y1082677D03*
X1669684Y1086416D03*
X1665944Y1078936D03*
X1673424D03*
X1669684Y1082676D03*
X1665944Y1093897D03*
X1662204Y1105117D03*
X1669685D03*
X1673424Y1097637D03*
X1669685Y1101376D03*
X1673424Y1093897D03*
X1665944Y1097637D03*
X1662204Y1101376D03*
X1673425Y1112598D03*
X1665944Y1123818D03*
X1673425Y1120078D03*
X1669685Y1123818D03*
X1665944Y1116338D03*
X1669685D03*
X1665944Y1131299D03*
X1669685D03*
X1673425Y1127559D03*
Y1135039D03*
Y1202362D03*
X1665945Y1198621D03*
X1669685D03*
X1665945Y1206102D03*
X1669685Y1213582D03*
X1673425Y1209842D03*
X1669685Y1206102D03*
X1665945Y1213582D03*
X1673425Y1217322D03*
Y1236023D03*
X1662204Y1228543D03*
X1669685D03*
X1673425Y1232283D03*
X1665945D03*
Y1236023D03*
X1662204Y1224803D03*
X1669685D03*
X1673425Y1250984D03*
X1662204Y1247243D03*
X1665945Y1254724D03*
X1673425D03*
X1662204Y1243503D03*
X1665945Y1250984D03*
X1669685Y1247243D03*
Y1243503D03*
X1680904Y1075196D03*
X1688384D03*
X1692126Y1090157D03*
Y1082676D03*
X1684644Y1082677D03*
Y1086417D03*
X1680904Y1078936D03*
X1688384D03*
X1677164Y1086417D03*
Y1082677D03*
X1692126Y1101377D03*
X1684645D03*
X1677165Y1105117D03*
X1680904Y1097637D03*
X1677165Y1101376D03*
X1688385Y1097637D03*
X1684645Y1105117D03*
X1680904Y1093897D03*
X1688385D03*
X1677165Y1120078D03*
Y1112598D03*
X1692126Y1116338D03*
Y1108858D03*
X1684645Y1120078D03*
X1688385D03*
X1684645Y1112598D03*
X1692126Y1123818D03*
X1688385Y1112598D03*
X1677165Y1135039D03*
Y1127559D03*
X1684645Y1135039D03*
Y1127558D03*
X1692126Y1131299D03*
X1688385Y1127558D03*
Y1135039D03*
X1684645Y1202362D03*
X1692126Y1198621D03*
X1688385Y1202362D03*
X1677165D03*
X1692126Y1213582D03*
X1684645Y1217322D03*
Y1209842D03*
X1692126Y1206102D03*
X1677165Y1209842D03*
X1692126Y1221062D03*
X1688385Y1209842D03*
X1677165Y1217322D03*
X1688385D03*
X1677165Y1228543D03*
X1680905Y1236023D03*
Y1232283D03*
X1692126Y1228543D03*
X1684645Y1224803D03*
Y1228543D03*
X1677165Y1224803D03*
X1688385Y1232283D03*
Y1236023D03*
X1684645Y1243503D03*
X1677165D03*
X1692126Y1247243D03*
X1684645D03*
X1677165D03*
X1688385Y1254724D03*
Y1250984D03*
X1692126Y1239763D03*
X1680905Y1254724D03*
Y1250984D03*
X1695866Y1090157D03*
Y1082676D03*
Y1101377D03*
Y1123818D03*
Y1116338D03*
Y1108858D03*
Y1131299D03*
Y1198621D03*
Y1221062D03*
Y1213582D03*
Y1206102D03*
Y1228543D03*
Y1239763D03*
Y1247243D03*
G54D65*
X414519Y1251852D03*
Y1264254D03*
X512830Y1251852D03*
Y1264254D03*
X1328693Y1251852D03*
Y1264254D03*
X1427004Y1251852D03*
Y1264254D03*
G54D84*
X849441Y1367717D03*
G54D57*
X230754Y633125D03*
Y635684D03*
Y638243D03*
X238234Y635684D03*
Y633125D03*
Y638243D03*
G54D75*
X490050Y804497D03*
Y800757D03*
Y808237D03*
X501074Y800757D03*
Y804497D03*
Y808237D03*
X1465833Y928108D03*
X1454809D03*
Y931848D03*
Y935588D03*
X1465833Y931848D03*
Y935588D03*
G54D39*
X79028Y883233D03*
X69028D03*
X71528D03*
X76528D03*
X74028D03*
X84028D03*
X81528D03*
X84028Y904833D03*
X76528D03*
X69028D03*
X81528D03*
X79028D03*
X74028D03*
X71528D03*
X86528Y883233D03*
Y904833D03*
X535968Y883233D03*
X525968D03*
X528468D03*
X533468D03*
X530968D03*
X538468D03*
X533468Y904833D03*
X525968D03*
X538468D03*
X535968D03*
X530968D03*
X528468D03*
X543468Y883233D03*
X540968D03*
Y904833D03*
X543468D03*
X993054Y883233D03*
X983054D03*
X985554D03*
X990554D03*
X988054D03*
X990554Y904833D03*
X983054D03*
X993054D03*
X988054D03*
X985554D03*
X1000554Y883233D03*
X998054D03*
X995554D03*
X998054Y904833D03*
X1000554D03*
X995554D03*
X1440141Y883233D03*
X1442641D03*
X1447641D03*
X1445141D03*
X1447641Y904833D03*
X1440141D03*
X1445141D03*
X1442641D03*
X1450141Y883233D03*
X1457641D03*
X1455141D03*
X1452641D03*
X1455141Y904833D03*
X1457641D03*
X1452641D03*
X1450141D03*
G54D66*
X398820Y1272093D03*
Y1276293D03*
X527136Y1288800D03*
Y1293000D03*
X1312889Y1291111D03*
Y1295311D03*
X1441309Y1288800D03*
Y1293000D03*
G54D93*
X911290Y846867D03*
Y853166D03*
Y859465D03*
Y865764D03*
Y868914D03*
X914440Y846867D03*
Y853166D03*
Y859465D03*
Y865764D03*
Y868914D03*
X1302770Y854824D03*
X1302776Y851193D03*
X1302883Y859088D03*
X1315311Y840921D03*
X1318461D03*
X1303195Y832247D03*
X1306345D03*
X1303183Y835985D03*
X1306333D03*
X1305920Y854824D03*
X1305926Y851193D03*
X1306033Y859088D03*
X1315330Y884988D03*
X1318480D03*
X1337377Y878689D03*
X1340527D03*
X1346826Y891288D03*
X1349976D03*
G54D48*
X173829Y455492D03*
Y583957D03*
X202844Y455492D03*
Y583957D03*
X266841Y421555D03*
Y550020D03*
X295856Y421555D03*
Y550020D03*
X630915Y455492D03*
Y583957D03*
X659930Y455492D03*
Y583957D03*
X723927Y421555D03*
Y550020D03*
X752942Y421555D03*
Y550020D03*
X1088002Y455492D03*
Y583957D03*
X1117017Y455492D03*
Y583957D03*
X1181014Y421555D03*
Y550020D03*
X1210029Y421555D03*
Y550020D03*
X1545089Y455492D03*
Y583957D03*
X1574104Y455492D03*
Y583957D03*
X1638101Y421555D03*
Y550020D03*
X1667116Y421555D03*
Y550020D03*
G54D94*
X901841Y856316D03*
Y853166D03*
X927438Y856316D03*
Y853166D03*
X923888Y856316D03*
Y853166D03*
X920739Y862615D03*
Y859465D03*
X930768Y856316D03*
Y853166D03*
X934268Y856316D03*
Y853166D03*
X1314560Y864182D03*
Y867332D03*
X1306387Y896580D03*
Y893430D03*
X1310482Y896580D03*
Y893430D03*
X1334228Y878690D03*
Y875540D03*
Y894438D03*
Y891288D03*
X1346827Y856642D03*
Y853492D03*
X1349977Y856642D03*
Y853492D03*
X1343678Y856642D03*
Y853492D03*
X1340528Y856642D03*
Y853492D03*
X1349977Y862942D03*
Y859792D03*
X1340528Y862942D03*
Y859792D03*
X1346826Y862942D03*
Y859792D03*
X1343677Y862942D03*
Y859792D03*
X1337377Y869241D03*
Y866091D03*
Y875540D03*
Y872390D03*
X1356275Y862942D03*
Y859792D03*
X1359425Y862942D03*
Y859792D03*
X1356275Y856642D03*
Y853492D03*
X1359425Y856642D03*
Y853492D03*
X1353126Y856642D03*
Y853492D03*
Y862942D03*
Y859792D03*
X1362572Y875539D03*
Y872389D03*
X1365724Y894438D03*
Y891288D03*
X1372023Y869241D03*
Y866091D03*
G36*
G01X248233Y1606137D02*
G02X235433Y1618942I-12800J5D01*
G02X248233Y1606147I0J-12800D01*
G01X243683D01*
G03X235433Y1597891I-8250J-5D01*
G03X243683Y1606137I0J8251D01*
G01X248233D01*
G37*
G36*
G01X594690D02*
G02X581890Y1618942I-12800J5D01*
G02X594690Y1606147I0J-12800D01*
G01X590140D01*
G03X581890Y1597891I-8250J-5D01*
G03X590140Y1606137I0J8251D01*
G01X594690D01*
G37*
G36*
G01X1271855D02*
G02X1259055Y1618942I-12800J5D01*
G02X1271855Y1606147I0J-12800D01*
G01X1267305D01*
G03X1259055Y1597891I-8250J-5D01*
G03X1267305Y1606137I0J8251D01*
G01X1271855D01*
G37*
G36*
G01X1618312D02*
G02X1605512Y1618942I-12800J5D01*
G02X1618312Y1606147I0J-12800D01*
G01X1613762D01*
G03X1605512Y1597891I-8250J-5D01*
G03X1613762Y1606137I0J8251D01*
G01X1618312D01*
G37*
G54D67*
X396770Y1272093D03*
Y1276293D03*
X1310839Y1291111D03*
Y1295311D03*
G54D76*
X501267Y830468D03*
Y833027D03*
Y835586D03*
X507821Y846830D03*
X499947D03*
X507821Y844271D03*
X499947D03*
X507821Y849389D03*
X499947D03*
X509141Y830468D03*
Y833027D03*
Y835586D03*
X1466026Y960378D03*
Y957819D03*
Y962937D03*
X1464706Y974181D03*
Y976740D03*
Y971622D03*
X1473900Y960378D03*
Y957819D03*
Y962937D03*
X1472580Y974181D03*
Y976740D03*
Y971622D03*
X1506626Y876339D03*
X1514500D03*
X1506626Y873780D03*
X1514500D03*
X1506626Y878898D03*
X1514500D03*
G54D85*
X843012Y1592787D03*
Y1602787D03*
Y1612787D03*
Y1622787D03*
X853012Y1592787D03*
Y1602787D03*
Y1612787D03*
Y1622787D03*
X878012Y1592787D03*
Y1602787D03*
Y1612787D03*
Y1622787D03*
X888012Y1592787D03*
Y1602787D03*
Y1612787D03*
Y1622787D03*
X913012Y1592787D03*
Y1602787D03*
Y1612787D03*
Y1622787D03*
X923012Y1592787D03*
Y1602787D03*
Y1612787D03*
Y1622787D03*
X948012Y1592787D03*
Y1602787D03*
Y1612787D03*
Y1622787D03*
X958012Y1592787D03*
Y1602787D03*
Y1612787D03*
Y1622787D03*
X983012Y1592787D03*
X993012D03*
X983012Y1602787D03*
Y1612787D03*
X993012Y1602787D03*
Y1612787D03*
X983012Y1622787D03*
X993012D03*
X1018012Y1592787D03*
X1028012D03*
X1018012Y1602787D03*
Y1612787D03*
X1028012Y1602787D03*
Y1612787D03*
X1018012Y1622787D03*
G54D49*
X190325Y368760D03*
X279360Y636752D03*
X647411Y368760D03*
X736446Y636752D03*
X1104498Y368760D03*
X1193533Y636752D03*
X1561585Y368760D03*
X1650620Y636752D03*
G54D95*
X953192Y-31798D03*
X978036Y-70978D03*
X1231336Y-80978D03*
X1236692Y-41928D03*
X1487836Y-80978D03*
X1523192Y-42058D03*
X1742336Y-80978D03*
X1807692Y-42188D03*
G54D59*
X232944Y1123810D03*
Y1129610D03*
X232916Y1205884D03*
Y1200084D03*
X404934Y324379D03*
Y318579D03*
X417325Y1217782D03*
Y1211982D03*
X424563Y1217782D03*
Y1211982D03*
X411816Y1217782D03*
Y1211982D03*
X425874Y1277211D03*
Y1283011D03*
X417305Y1362459D03*
Y1368259D03*
X439934Y1198371D03*
Y1192571D03*
X430101Y1217782D03*
Y1211982D03*
X438005Y1217782D03*
Y1211982D03*
X441044Y1277232D03*
Y1283032D03*
X436291Y1277232D03*
Y1283032D03*
X431114Y1277510D03*
Y1283310D03*
X450470Y1211982D03*
Y1217782D03*
X455811Y1211982D03*
Y1217782D03*
X443840D03*
Y1211982D03*
X456438Y1277339D03*
Y1283139D03*
X451343Y1277319D03*
Y1283119D03*
X446212Y1277264D03*
Y1283064D03*
X471348Y1211982D03*
Y1217782D03*
X466241Y1211982D03*
Y1217782D03*
X461014Y1211982D03*
Y1217782D03*
X461643Y1277361D03*
Y1283161D03*
X466973Y1277361D03*
Y1283161D03*
X472590Y1277361D03*
Y1283161D03*
X476577Y1211982D03*
Y1217782D03*
X482888Y1211982D03*
Y1217782D03*
X489047D03*
Y1211982D03*
X489119Y1277361D03*
Y1283161D03*
X478099Y1277361D03*
Y1283161D03*
X483501Y1277361D03*
Y1283161D03*
X496768Y1217782D03*
Y1211982D03*
X502202Y1217782D03*
Y1211982D03*
X494899Y1279035D03*
Y1284835D03*
X506026Y1279035D03*
Y1284835D03*
X500300Y1279035D03*
Y1284835D03*
X523741Y816549D03*
Y810749D03*
X513136Y1198371D03*
Y1192571D03*
X515463Y1217782D03*
Y1211982D03*
X510190Y1217782D03*
Y1211982D03*
X523694Y1217782D03*
Y1211982D03*
X522765Y1277845D03*
Y1283645D03*
X517332Y1277845D03*
Y1283645D03*
X511876Y1277845D03*
Y1283645D03*
X528136Y1277845D03*
Y1283645D03*
X547039Y681536D03*
X542084Y681459D03*
X547039Y687336D03*
X542084Y687259D03*
X690031Y1123810D03*
Y1129610D03*
X690003Y1205884D03*
Y1200084D03*
X877949Y566263D03*
Y560463D03*
X894949Y553963D03*
X889949D03*
X882949Y560463D03*
Y566263D03*
X894949Y559763D03*
X889949D03*
X887949Y599963D03*
Y605763D03*
X915949Y566463D03*
Y572263D03*
X914949Y603963D03*
Y609763D03*
X925114Y1095109D03*
Y1100909D03*
X930167Y1095126D03*
Y1100926D03*
X939435Y825288D03*
Y819488D03*
X942796Y872268D03*
Y878068D03*
X945889Y1095016D03*
Y1100816D03*
X940701Y1095023D03*
Y1100823D03*
X935430Y1095120D03*
Y1100920D03*
X994920Y326054D03*
Y331854D03*
X1147117Y1123810D03*
Y1129610D03*
X1147089Y1200084D03*
Y1205884D03*
X1307519Y327471D03*
Y321671D03*
X1307691Y828067D03*
Y822267D03*
X1317009Y1217914D03*
Y1212114D03*
X1311699Y1251496D03*
Y1245696D03*
X1320072Y1280152D03*
Y1285952D03*
X1314618Y1280207D03*
Y1286007D03*
X1329350Y1217914D03*
Y1212114D03*
X1323915Y1217914D03*
Y1212114D03*
X1335873Y1284287D03*
X1325444D03*
X1330594D03*
X1335873Y1290087D03*
X1325444D03*
X1330594D03*
X1352163Y1212114D03*
Y1217914D03*
X1344332D03*
Y1212114D03*
X1341137Y1284287D03*
X1346371D03*
X1351668D03*
X1341137Y1290087D03*
X1346371D03*
X1351668D03*
X1364623Y1212114D03*
Y1217914D03*
X1357630D03*
Y1212114D03*
X1356871Y1284287D03*
X1367681D03*
X1362269D03*
X1356871Y1290087D03*
X1367681D03*
X1362269D03*
X1380372Y1212114D03*
Y1217914D03*
X1375161Y1212114D03*
Y1217914D03*
X1369945Y1212114D03*
Y1217914D03*
X1373032Y1284243D03*
X1380311Y1276377D03*
Y1282177D03*
X1373032Y1290043D03*
X1396780Y896111D03*
Y901911D03*
X1397096Y1212114D03*
Y1217914D03*
X1390655Y1212114D03*
Y1217914D03*
X1385539Y1212114D03*
Y1217914D03*
X1385497Y1276433D03*
Y1282233D03*
X1400803Y1277849D03*
Y1283649D03*
X1390647Y1276399D03*
Y1282199D03*
X1395671Y1276397D03*
Y1282197D03*
X1411434Y1217914D03*
Y1212114D03*
X1416583Y1217914D03*
Y1212114D03*
X1403080Y1217914D03*
Y1212114D03*
X1412392Y1277962D03*
Y1283762D03*
X1407232Y1277952D03*
Y1283752D03*
X1427310Y1198371D03*
Y1192571D03*
X1424856Y1217914D03*
Y1212114D03*
X1430129Y1217914D03*
Y1212114D03*
X1418280Y1273336D03*
Y1279136D03*
X1430336Y1273336D03*
Y1279136D03*
X1424852Y1273336D03*
Y1279136D03*
X1438360Y1217914D03*
Y1212114D03*
X1436251Y1273336D03*
Y1279136D03*
X1442192Y1273336D03*
Y1279136D03*
X1488500Y943900D03*
Y938100D03*
X1604204Y1123810D03*
Y1129610D03*
X1604176Y1200084D03*
Y1205884D03*
G54D68*
X409211Y1300396D03*
Y1298427D03*
Y1302364D03*
Y1312207D03*
Y1306301D03*
Y1310238D03*
Y1308270D03*
Y1304333D03*
X398881Y1383912D03*
Y1381943D03*
Y1379975D03*
Y1378006D03*
Y1391786D03*
Y1389817D03*
Y1387849D03*
Y1385880D03*
X417581Y1383912D03*
Y1381943D03*
Y1379975D03*
Y1378006D03*
Y1391786D03*
Y1389817D03*
Y1387849D03*
Y1385880D03*
X427911Y1302364D03*
Y1300396D03*
Y1298427D03*
Y1312207D03*
Y1304333D03*
Y1310238D03*
Y1306301D03*
Y1308270D03*
G54D86*
X876402Y797415D03*
X890326Y828548D03*
X895050D03*
X898835Y831912D03*
X893843Y832448D03*
X886120Y832295D03*
X955712Y833988D03*
X978978Y817618D03*
X984357Y777555D03*
X997051Y778833D03*
X990699Y778630D03*
X987990Y774005D03*
X987394Y787490D03*
X994051Y810871D03*
X996385Y816141D03*
X1007990Y765899D03*
X999990Y764566D03*
X1012695Y776728D03*
X999990Y774671D03*
X1011156Y809889D03*
X998376Y805985D03*
X1006054Y810969D03*
X1010699Y803454D03*
X1018015Y751565D03*
X1017664Y779101D03*
X1018071Y798490D03*
X1017955Y812097D03*
X1274396Y866896D03*
X1324470Y908192D03*
G54D77*
X529186Y1288800D03*
Y1293000D03*
X1443359Y1288800D03*
Y1293000D03*
G54D69*
X408231Y1384896D03*
X418561Y1305317D03*
G54D78*
X555682Y826212D03*
Y834086D03*
X558241Y826212D03*
X560800D03*
X558241Y834086D03*
X560800D03*
X583501Y797111D03*
X580942D03*
X586060D03*
X583501Y804985D03*
X580942D03*
X586060D03*
X1523000Y961437D03*
Y953563D03*
X1520441Y961437D03*
Y953563D03*
X1525559Y961437D03*
Y953563D03*
G54D96*
X1028012Y1622787D03*
G54D87*
X895384Y228740D03*
Y276772D03*
X923336Y226772D03*
Y278740D03*
G54D88*
X891012Y692138D03*
G54D97*
X1030635Y754546D03*
Y764546D03*
Y774546D03*
Y784546D03*
Y794546D03*
Y804546D03*
Y814546D03*
G54D79*
X710406Y-26826D03*
Y-36826D03*
D03*
Y-26826D03*
X735406D03*
Y-36826D03*
D03*
Y-26826D03*
X830406Y-76006D03*
D03*
Y-66006D03*
D03*
X855406Y-76006D03*
D03*
Y-66006D03*
D03*
X939542Y-36798D03*
Y-26798D03*
D03*
Y-36798D03*
X964386Y-75978D03*
D03*
Y-65978D03*
D03*
X964542Y-36798D03*
Y-26798D03*
D03*
Y-36798D03*
X989386Y-75978D03*
D03*
Y-65978D03*
D03*
X993906Y-46826D03*
Y-36826D03*
D03*
Y-26826D03*
X1018906Y-46826D03*
Y-36826D03*
D03*
Y-26826D03*
X1063906Y-76006D03*
Y-86006D03*
Y-76006D03*
Y-66006D03*
X1088906Y-76006D03*
Y-86006D03*
Y-76006D03*
Y-66006D03*
X1217686Y-85978D03*
Y-75978D03*
D03*
Y-65978D03*
X1223042Y-46928D03*
Y-36928D03*
Y-26928D03*
Y-36928D03*
X1242686Y-85978D03*
Y-75978D03*
D03*
Y-65978D03*
X1248042Y-46928D03*
Y-36928D03*
Y-26928D03*
Y-36928D03*
X1280406Y-46956D03*
Y-36956D03*
D03*
Y-26956D03*
X1305406Y-46956D03*
Y-36956D03*
D03*
Y-26956D03*
X1320406Y-76006D03*
Y-86006D03*
Y-76006D03*
Y-66006D03*
X1345406Y-76006D03*
Y-86006D03*
Y-76006D03*
Y-66006D03*
X1474186Y-85978D03*
Y-75978D03*
D03*
Y-65978D03*
X1499186Y-85978D03*
Y-75978D03*
D03*
Y-65978D03*
X1509542Y-47058D03*
Y-37058D03*
Y-27058D03*
Y-37058D03*
X1534542Y-47058D03*
Y-37058D03*
Y-27058D03*
Y-37058D03*
X1564906Y-47086D03*
Y-37086D03*
D03*
Y-27086D03*
X1574906Y-76006D03*
Y-86006D03*
Y-76006D03*
Y-66006D03*
X1589906Y-47086D03*
Y-37086D03*
D03*
Y-27086D03*
X1599906Y-76006D03*
Y-86006D03*
Y-76006D03*
Y-66006D03*
X1728686Y-85978D03*
Y-75978D03*
D03*
Y-65978D03*
X1753686Y-85978D03*
Y-75978D03*
D03*
Y-65978D03*
X1794042Y-47188D03*
Y-37188D03*
Y-27188D03*
Y-37188D03*
X1819042Y-47188D03*
Y-37188D03*
Y-27188D03*
Y-37188D03*
G54D89*
X891031Y694107D03*
X893984Y696075D03*
X891031D03*
X893984Y692138D03*
Y694107D03*
G54D98*
X1030635Y824546D03*
G54D99*
X1131743Y779174D03*
X1139617Y775434D03*
Y782914D03*
M02*
